G04 ================== begin FILE IDENTIFICATION RECORD ==================*
G04 Layout Name:  E:/<user>/9332_F0TG_MB_C/brd/0417/9332_F0TG_MB_C_V02_0417_0820.brd*
G04 Film Name:    top*
G04 File Format:  Gerber RS274X*
G04 File Origin:  Cadence Allegro 17.2-S081*
G04 Origin Date:  Wed Apr 19 14:49:55 2023*
G04 *
G04 Layer:  PIN/SPECIAL_DRILL*
G04 Layer:  DRAWING FORMAT/TITLE_BLOCK_A*
G04 Layer:  DRAWING FORMAT/TITLE_BLOCK*
G04 Layer:  VIA CLASS/TOP*
G04 Layer:  PIN/TOP*
G04 Layer:  MANUFACTURING/PHOTOPLOT_OUTLINE*
G04 Layer:  ETCH/TOP*
G04 Layer:  DRAWING FORMAT/TITLE_DATA_TOP*
G04 *
G04 Offset:    (0.00 0.00)*
G04 Mirror:    No*
G04 Mode:      Positive*
G04 Rotation:  0*
G04 FullContactRelief:  No*
G04 UndefLineWidth:     6.00*
G04 ================== end FILE IDENTIFICATION RECORD ====================*
%FSLAX25Y25*MOIN*%
%IR0*IPPOS*OFA0.00000B0.00000*MIA0B0*SFA1.00000B1.00000*%
%AMMACRO256*
4,1,28,.00748,.00051,
.00984,.00051,
.00985,.00602,
.009788,.006695,
.009614,.00735,
.009329,.007964,
.008942,.00852,
.008464,.009,
.00791,.00939,
.007296,.009677,
.006642,.009854,
.005967,.009915,
.00592,.00991,
-.0059,.00993,
-.006576,.009875,
-.007232,.009708,
-.00785,.009429,
-.008409,.009047,
-.008894,.008574,
-.009289,.008024,
-.009583,.007413,
-.009767,.006761,
-.009834,.006087,
-.00983,.00604,
-.00984,.00053,
-.00748,.00053,
-.00749,-.0099,
.00747,-.00992,
.00748,.00051,
0.0*
%
%ADD256MACRO256*%
%AMMACRO251*
4,1,32,-.01575,.06201,
-.01575,.0502,
.00197,.0502,
.00197,.04035,
-.01575,.04035,
-.01575,.03248,
.00197,.03248,
.00197,.02461,
-.01575,.02461,
-.01575,.01673,
.00197,.01673,
.00197,.00886,
-.01575,.00886,
-.01575,.00098,
.00197,.00098,
.00197,-.00689,
-.01575,-.00689,
-.01575,-.01476,
.00197,-.01476,
.00197,-.02264,
-.01575,-.02264,
-.01575,-.03051,
.00197,-.03051,
.00197,-.03839,
-.01575,-.03839,
-.01575,-.04626,
.00197,-.04626,
.00197,-.05413,
-.01575,-.05413,
-.01575,-.06201,
.01575,-.06201,
.01575,.06201,
-.01575,.06201,
0.0*
%
%ADD251MACRO251*%
%AMMACRO185*
4,1,28,-.00051,.00748,
-.00051,.00984,
-.00602,.00985,
-.006695,.009788,
-.00735,.009614,
-.007964,.009329,
-.00852,.008942,
-.009,.008464,
-.00939,.00791,
-.009677,.007296,
-.009854,.006642,
-.009915,.005967,
-.00991,.00592,
-.00993,-.0059,
-.009875,-.006576,
-.009708,-.007232,
-.009429,-.00785,
-.009047,-.008409,
-.008574,-.008894,
-.008024,-.009289,
-.007413,-.009583,
-.006761,-.009767,
-.006087,-.009834,
-.00604,-.00983,
-.00053,-.00984,
-.00053,-.00748,
.0099,-.00749,
.00992,.00747,
-.00051,.00748,
0.0*
%
%ADD185MACRO185*%
%AMMACRO143*
4,1,28,.00051,-.00748,
.00051,-.00984,
.00602,-.00985,
.006695,-.009788,
.00735,-.009614,
.007964,-.009329,
.00852,-.008942,
.009,-.008464,
.00939,-.00791,
.009677,-.007296,
.009854,-.006642,
.009915,-.005967,
.00991,-.00592,
.00993,.0059,
.009875,.006576,
.009708,.007232,
.009429,.00785,
.009047,.008409,
.008574,.008894,
.008024,.009289,
.007413,.009583,
.006761,.009767,
.006087,.009834,
.00604,.00983,
.00053,.00984,
.00053,.00748,
-.0099,.00749,
-.00992,-.00747,
.00051,-.00748,
0.0*
%
%ADD143MACRO143*%
%AMMACRO135*
4,1,5,.00591,-.01772,
.00591,.01772,
0.0,.01772,
-.00591,.01181,
-.00591,-.01772,
.00591,-.01772,
0.0*
%
%ADD135MACRO135*%
%AMMACRO277*
4,1,5,-.01772,-.00591,
.01772,-.00591,
.01772,0.0,
.01181,.00591,
-.01772,.00591,
-.01772,-.00591,
0.0*
%
%ADD277MACRO277*%
%AMMACRO316*
4,1,8,.02953,.06299,
-.02953,.06299,
-.02953,-.06299,
.02953,-.06299,
.02953,-.01968,
-.01771,-.01968,
-.01771,.01968,
.02953,.01968,
.02953,.06299,
0.0*
%
%ADD316MACRO316*%
%AMMACRO41*
4,1,8,.06299,-.02953,
.06299,.02953,
-.06299,.02953,
-.06299,-.02953,
-.01968,-.02953,
-.01968,.01771,
.01968,.01771,
.01968,-.02953,
.06299,-.02953,
0.0*
%
%ADD41MACRO41*%
%AMMACRO133*
21,1,.016,.0041,0.0,0.0,60.*%
%ADD133MACRO133*%
%ADD50R,.17X.024*%
%AMMACRO255*
4,1,28,.00748,-.00052,
.00984,-.00052,
.00983,-.00603,
.009775,-.006705,
.0096,-.007359,
.009313,-.007973,
.008925,-.008528,
.008446,-.009007,
.007891,-.009395,
.007277,-.009682,
.006622,-.009857,
.005948,-.009916,
.0059,-.00992,
-.00592,-.0099,
-.006595,-.009852,
-.007251,-.009684,
-.007868,-.009404,
-.008427,-.009021,
-.008911,-.008546,
-.009305,-.007996,
-.009598,-.007384,
-.00978,-.006732,
-.009845,-.006058,
-.00985,-.00601,
-.00984,-.0005,
-.00748,-.0005,
-.00747,.00993,
.00749,.00991,
.00748,-.00052,
0.0*
%
%ADD255MACRO255*%
%ADD225R,.11X.049*%
%AMMACRO184*
4,1,28,.00052,.00748,
.00052,.00984,
.00603,.00983,
.006705,.009775,
.007359,.0096,
.007973,.009313,
.008528,.008925,
.009007,.008446,
.009395,.007891,
.009682,.007277,
.009857,.006622,
.009916,.005948,
.00992,.0059,
.0099,-.00592,
.009852,-.006595,
.009684,-.007251,
.009404,-.007868,
.009021,-.008427,
.008546,-.008911,
.007996,-.009305,
.007384,-.009598,
.006732,-.00978,
.006058,-.009845,
.00601,-.00985,
.0005,-.00984,
.0005,-.00748,
-.00993,-.00747,
-.00991,.00749,
.00052,.00748,
0.0*
%
%ADD184MACRO184*%
%AMMACRO142*
4,1,28,-.00052,-.00748,
-.00052,-.00984,
-.00603,-.00983,
-.006705,-.009775,
-.007359,-.0096,
-.007973,-.009313,
-.008528,-.008925,
-.009007,-.008446,
-.009395,-.007891,
-.009682,-.007277,
-.009857,-.006622,
-.009916,-.005948,
-.00992,-.0059,
-.0099,.00592,
-.009852,.006595,
-.009684,.007251,
-.009404,.007868,
-.009021,.008427,
-.008546,.008911,
-.007996,.009305,
-.007384,.009598,
-.006732,.00978,
-.006058,.009845,
-.00601,.00985,
-.0005,.00984,
-.0005,.00748,
.00993,.00747,
.00991,-.00749,
-.00052,-.00748,
0.0*
%
%ADD142MACRO142*%
%ADD115R,.103X.065*%
%ADD305R,.065X.103*%
%ADD203R,.04X.007*%
%ADD182R,.031X.007*%
%ADD29C,.011*%
%ADD10C,.02*%
%AMMACRO218*
21,1,.016,.0041,0.0,0.0,45.*%
%ADD218MACRO218*%
%ADD204R,.007X.031*%
%ADD202R,.007X.04*%
%ADD183R,.032X.007*%
%ADD109C,.012*%
%ADD76R,.0041X.016*%
%ADD11C,.03*%
%ADD282R,.13X.095*%
%ADD272O,.137X.064*%
%ADD136R,.007X.032*%
%ADD119R,.095X.111*%
%ADD72R,.016X.0041*%
%ADD42R,.024X.007*%
%ADD199R,.052X.007*%
%ADD158C,.041*%
%AMMACRO85*
4,1,8,-.09252,.09055,
-.09252,.0315,
-.08268,.0315,
-.08268,-.09055,
.08268,-.09055,
.08268,.0315,
.09252,.0315,
.09252,.09055,
-.09252,.09055,
0.0*
%
%ADD85MACRO85*%
%ADD60R,.007X.024*%
%ADD234R,.015X.009*%
%ADD200R,.007X.052*%
%ADD155C,.06*%
%ADD112C,.015*%
%ADD100R,.115X.085*%
%ADD78R,.026X.007*%
%ADD59R,.119X.063*%
%ADD55R,.024X.009*%
%ADD265R,.138X.063*%
%ADD232R,.009X.015*%
%ADD108C,.016*%
%AMMACRO96*
4,1,21,-.0035,-.0085,
-.0035,.012,
.0035,.012,
.0035,-.0085,
.003447,-.009108,
.003289,-.009697,
.003031,-.01025,
.002681,-.01075,
.00225,-.011181,
.00175,-.011531,
.001197,-.011789,
.000608,-.011947,
0.0,-.012,
-.000608,-.011947,
-.001197,-.011789,
-.00175,-.011531,
-.00225,-.011181,
-.002681,-.01075,
-.003031,-.01025,
-.003289,-.009697,
-.003447,-.009108,
-.0035,-.0085,
0.0*
%
%ADD96MACRO96*%
%AMMACRO92*
4,1,21,.0085,-.0035,
-.012,-.0035,
-.012,.0035,
.0085,.0035,
.009108,.003447,
.009697,.003289,
.01025,.003031,
.01075,.002681,
.011181,.00225,
.011531,.00175,
.011789,.001197,
.011947,.000608,
.012,0.0,
.011947,-.000608,
.011789,-.001197,
.011531,-.00175,
.011181,-.00225,
.01075,-.002681,
.01025,-.003031,
.009697,-.003289,
.009108,-.003447,
.0085,-.0035,
0.0*
%
%ADD92MACRO92*%
%ADD77R,.007X.026*%
%ADD65C,.061*%
%ADD56R,.009X.024*%
%ADD30R,.063X.119*%
%ADD290R,.028X.007*%
%ADD106R,.063X.138*%
%ADD91R,.048X.126*%
%ADD66O,.137X.068*%
%ADD45C,.044*%
%ADD299C,.045*%
%ADD289R,.007X.028*%
%ADD259C,.036*%
%ADD57C,.018*%
%ADD250R,.13X.0848*%
%AMMACRO237*
4,1,8,-.0425,-.0764,
.0425,-.0764,
.0425,.0764,
-.0425,.0764,
-.0425,.0236,
-.0145,.0236,
-.0145,-.0236,
-.0425,-.0236,
-.0425,-.0764,
0.0*
%
%ADD237MACRO237*%
%ADD224C,.046*%
%ADD48C,.019*%
%ADD43C,.064*%
%ADD222C,.065*%
%ADD197R,.0848X.13*%
%ADD121C,.03017*%
%ADD75R,.178X.054*%
%ADD298C,.048*%
%ADD240R,.032X.032*%
%ADD207C,.066*%
%ADD14C,.039*%
%ADD327C,.085*%
%AMMACRO318*
4,1,30,-.08089,.09065,
-.08227,.09203,
-.10433,.09203,
-.10433,.08022,
-.08309,.08022,
-.08171,.07884,
-.02464,.07884,
-.02464,-.02608,
-.06988,-.02609,
-.06988,-.09203,
.06988,-.09203,
.06988,-.01427,
.04035,-.01427,
.04035,.02116,
.10433,.02117,
.10433,.03298,
.09055,.03298,
.09055,.04085,
.10433,.04084,
.10433,.05261,
.09055,.05266,
.09055,.06053,
.10433,.06054,
.10433,.07237,
.09055,.07237,
.09055,.08022,
.10433,.08022,
.10433,.09203,
.08227,.09203,
.08089,.09065,
-.08089,.09065,
0.0*
%
%ADD318MACRO318*%
%AMMACRO172*
4,1,44,.11811,-.11614,
.11811,.11614,
.11808,.116482,
.117992,.116813,
.117847,.117124,
.117651,.117406,
.117408,.117648,
.117127,.117845,
.116817,.117991,
.116485,.11808,
.116143,.11811,
.11614,.11811,
-.11614,.11811,
-.116482,.11808,
-.116813,.117992,
-.117124,.117847,
-.117406,.117651,
-.117648,.117408,
-.117845,.117127,
-.117991,.116817,
-.11808,.116485,
-.11811,.116143,
-.11811,.11614,
-.11811,-.11614,
-.11808,-.116482,
-.117992,-.116813,
-.117847,-.117124,
-.117651,-.117406,
-.117408,-.117648,
-.117127,-.117845,
-.116817,-.117991,
-.116485,-.11808,
-.116143,-.11811,
-.11614,-.11811,
.11614,-.11811,
.116482,-.11808,
.116813,-.117992,
.117124,-.117847,
.117406,-.117651,
.117648,-.117408,
.117845,-.117127,
.117991,-.116817,
.11808,-.116485,
.11811,-.116143,
.11811,-.11614,
0.0*
%
%ADD172MACRO172*%
%ADD154R,.06X.06*%
%ADD51C,.0193*%
%ADD291R,.158X.077*%
%ADD71R,.061X.061*%
%ADD49R,.166X.079*%
%ADD74R,.178X.095*%
%ADD329C,.0395*%
%ADD294R,.064X.064*%
%AMMACRO270*
21,1,.016,.0041,0.0,0.0,33.917*%
%ADD270MACRO270*%
%ADD146C,.01772*%
%AMMACRO63*
4,1,44,.04921,.05118,
-.04921,.05118,
-.049552,.051151,
-.049883,.051062,
-.050194,.050918,
-.050475,.050721,
-.050718,.050479,
-.050915,.050199,
-.05106,.049888,
-.05115,.049557,
-.05118,.049215,
-.05118,.04921,
-.05118,-.04921,
-.051151,-.049552,
-.051062,-.049883,
-.050918,-.050194,
-.050721,-.050475,
-.050479,-.050718,
-.050199,-.050915,
-.049888,-.05106,
-.049557,-.05115,
-.049215,-.05118,
-.04921,-.05118,
.04921,-.05118,
.049552,-.051151,
.049883,-.051062,
.050194,-.050918,
.050475,-.050721,
.050718,-.050479,
.050915,-.050199,
.05106,-.049888,
.05115,-.049557,
.05118,-.049215,
.05118,-.04921,
.05118,.04921,
.051151,.049552,
.051062,.049883,
.050918,.050194,
.050721,.050475,
.050479,.050718,
.050199,.050915,
.049888,.05106,
.049557,.05115,
.049215,.05118,
.04921,.05118,
0.0*
%
%ADD63MACRO63*%
%ADD122R,.03017X.03017*%
%ADD300R,.048X.048*%
%ADD216R,.066X.066*%
%ADD328C,.0785*%
%ADD70R,.067X.067*%
%AMMACRO16*
4,1,28,-.00748,-.00052,
-.00984,-.00052,
-.00984,-.00603,
-.009782,-.006705,
-.009607,-.007359,
-.009321,-.007974,
-.008933,-.008529,
-.008455,-.009009,
-.0079,-.009398,
-.007286,-.009685,
-.006632,-.009861,
-.005957,-.00992,
-.00591,-.00992,
.00591,-.00992,
.006585,-.009869,
.007242,-.009701,
.007859,-.009421,
.008418,-.009039,
.008903,-.008565,
.009297,-.008015,
.009591,-.007404,
.009773,-.006751,
.00984,-.006077,
.00984,-.00603,
.00984,-.00052,
.00748,-.00052,
.00748,.00991,
-.00748,.00991,
-.00748,-.00052,
0.0*
%
%ADD16MACRO16*%
%ADD260C,.06574*%
%AMMACRO195*
4,1,5,.01378,.00098,
.01378,-.00492,
-.01378,-.00492,
-.01378,.00492,
.00984,.00492,
.01378,.00098,
0.0*
%
%ADD195MACRO195*%
%AMMACRO193*
4,1,5,.00098,-.01378,
-.00492,-.01378,
-.00492,.01378,
.00492,.01378,
.00492,-.00984,
.00098,-.01378,
0.0*
%
%ADD193MACRO193*%
%AMMACRO131*
4,1,5,.00492,.01673,
-.00492,.01673,
-.00492,-.01673,
.00098,-.01673,
.00492,-.0128,
.00492,.01673,
0.0*
%
%ADD131MACRO131*%
%ADD120C,.03568*%
%AMMACRO26*
4,1,28,-.00052,.00748,
-.00052,.00984,
-.00603,.00984,
-.006705,.009782,
-.007359,.009607,
-.007974,.009321,
-.008529,.008933,
-.009009,.008455,
-.009398,.0079,
-.009685,.007286,
-.009861,.006632,
-.00992,.005957,
-.00992,.00591,
-.00992,-.00591,
-.009869,-.006585,
-.009701,-.007242,
-.009421,-.007859,
-.009039,-.008418,
-.008565,-.008903,
-.008015,-.009297,
-.007404,-.009591,
-.006751,-.009773,
-.006077,-.00984,
-.00603,-.00984,
-.00052,-.00984,
-.00052,-.00748,
.00991,-.00748,
.00991,.00748,
-.00052,.00748,
0.0*
%
%ADD26MACRO26*%
%AMMACRO36*
4,1,5,-.04823,.03445,
-.04823,-.04823,
.04823,-.04823,
.04823,.04823,
-.03445,.04823,
-.04823,.03445,
0.0*
%
%ADD36MACRO36*%
%AMMACRO15*
4,1,28,-.00748,.00051,
-.00984,.00051,
-.00984,.00602,
-.009782,.006695,
-.009607,.007349,
-.009321,.007964,
-.008933,.008519,
-.008455,.008998,
-.0079,.009388,
-.007287,.009675,
-.006632,.009851,
-.005958,.00991,
-.00591,.00991,
.00591,.00991,
.006585,.009859,
.007242,.009691,
.007859,.009411,
.008418,.009029,
.008903,.008555,
.009297,.008005,
.00959,.007394,
.009773,.006742,
.00984,.006068,
.00984,.00602,
.00984,.00051,
.00748,.00051,
.00748,-.00992,
-.00748,-.00992,
-.00748,.00051,
0.0*
%
%ADD15MACRO15*%
%AMMACRO243*
4,1,13,.11516,-.02756,
-.02744,-.02756,
-.031058,-.025101,
-.035049,-.023307,
-.03929,-.022233,
-.043653,-.021912,
-.048006,-.022354,
-.052216,-.023545,
-.056155,-.025449,
-.05917,-.02756,
-.11516,-.02756,
-.11516,.02756,
.11516,.02756,
.11516,-.02756,
0.0*
%
%ADD243MACRO243*%
%AMMACRO192*
4,1,5,-.00098,-.01378,
.00492,-.01378,
.00492,.01378,
-.00492,.01378,
-.00492,-.00984,
-.00098,-.01378,
0.0*
%
%ADD192MACRO192*%
%AMMACRO190*
4,1,5,.01378,-.00098,
.01378,.00492,
-.01378,.00492,
-.01378,-.00492,
.00984,-.00492,
.01378,-.00098,
0.0*
%
%ADD190MACRO190*%
%AMMACRO28*
4,1,28,.00051,.00748,
.00051,.00984,
.00602,.00984,
.006695,.009782,
.007349,.009607,
.007964,.009321,
.008519,.008933,
.008998,.008455,
.009388,.0079,
.009675,.007287,
.009851,.006632,
.00991,.005958,
.00991,.00591,
.00991,-.00591,
.009859,-.006585,
.009691,-.007242,
.009411,-.007859,
.009029,-.008418,
.008555,-.008903,
.008005,-.009297,
.007394,-.00959,
.006742,-.009773,
.006068,-.00984,
.00602,-.00984,
.00051,-.00984,
.00051,-.00748,
-.00992,-.00748,
-.00992,.00748,
.00051,.00748,
0.0*
%
%ADD28MACRO28*%
%ADD279R,.06574X.06574*%
%AMMACRO130*
4,1,8,-.01821,.0246,
.01821,.0246,
.01821,.01476,
-.00837,.01476,
-.00837,-.01477,
.01821,-.01477,
.01821,-.02461,
-.01821,-.02461,
-.01821,.0246,
0.0*
%
%ADD130MACRO130*%
%AMMACRO87*
4,1,13,-.012,.00002,
-.011943,.000627,
-.011782,.001216,
-.011521,.001767,
-.011168,.002265,
-.010734,.002694,
-.010233,.003041,
-.009678,.003296,
-.009088,.00345,
-.0085,.0035,
.012,.0035,
.012,-.0035,
-.00848,-.0035,
-.012,.00002,
0.0*
%
%ADD87MACRO87*%
%AMMACRO93*
4,1,13,.00002,.012,
.000627,.011943,
.001216,.011782,
.001767,.011521,
.002265,.011168,
.002694,.010734,
.003041,.010233,
.003296,.009678,
.00345,.009088,
.0035,.0085,
.0035,-.012,
-.0035,-.012,
-.0035,.00848,
.00002,.012,
0.0*
%
%ADD93MACRO93*%
%AMMACRO54*
4,1,6,-.1063,-.04134,
-.1063,.01378,
-.03543,.01378,
-.03543,.04134,
.1063,.04134,
.1063,-.04134,
-.1063,-.04134,
0.0*
%
%ADD54MACRO54*%
%AMMACRO241*
4,1,13,.11516,-.02756,
-.11516,-.02756,
-.11516,.02756,
-.05917,.02756,
-.055552,.025101,
-.051561,.023307,
-.04732,.022233,
-.042957,.021912,
-.038604,.022354,
-.034394,.023545,
-.030455,.025449,
-.02744,.02756,
.11516,.02756,
.11516,-.02756,
0.0*
%
%ADD241MACRO241*%
%AMMACRO95*
4,1,13,-.00849,.0035,
.012,.0035,
.012,-.0035,
-.0085,-.0035,
-.009108,-.003447,
-.009697,-.003289,
-.01025,-.003031,
-.01075,-.002681,
-.011181,-.00225,
-.011531,-.00175,
-.011789,-.001197,
-.011947,-.000608,
-.012,-.00001,
-.00849,.0035,
0.0*
%
%ADD95MACRO95*%
%AMMACRO205*
4,1,5,.01772,-.00394,
.01772,.00394,
-.01772,.00394,
-.01772,0.0,
-.01378,-.00394,
.01772,-.00394,
0.0*
%
%ADD205MACRO205*%
%AMMACRO90*
4,1,13,.0035,.00849,
.0035,-.012,
-.0035,-.012,
-.0035,.0085,
-.003447,.009108,
-.003289,.009697,
-.003031,.01025,
-.002681,.01075,
-.00225,.011181,
-.00175,.011531,
-.001197,.011789,
-.000608,.011947,
-.00001,.012,
.0035,.00849,
0.0*
%
%ADD90MACRO90*%
%AMMACRO181*
4,1,5,-.00394,-.01772,
.00394,-.01772,
.00394,.01772,
0.0,.01772,
-.00394,.01378,
-.00394,-.01772,
0.0*
%
%ADD181MACRO181*%
%ADD111O,.013X.01*%
%ADD309R,.13X.13*%
%ADD281R,.02X.01*%
%ADD110O,.01X.013*%
%AMMACRO254*
4,1,5,.01772,.00591,
-.01772,.00591,
-.01772,0.0,
-.01181,-.00591,
.01772,-.00591,
.01772,.00591,
0.0*
%
%ADD254MACRO254*%
%AMMACRO173*
4,1,40,-.00984,-.00472,
.00984,-.00472,
.010182,-.004691,
.010513,-.004603,
.010824,-.004458,
.011105,-.004262,
.011348,-.00402,
.011545,-.00374,
.01169,-.003429,
.01178,-.003098,
.01181,-.00276,
.01181,.00276,
.011779,.003101,
.011689,.003432,
.011543,.003742,
.011346,.004023,
.011102,.004264,
.010821,.00446,
.01051,.004604,
.010178,.004691,
.00984,.00472,
-.00984,.00472,
-.010182,.004691,
-.010513,.004603,
-.010824,.004458,
-.011105,.004262,
-.011348,.00402,
-.011545,.00374,
-.01169,.003429,
-.01178,.003098,
-.01181,.00276,
-.01181,-.00276,
-.011779,-.003101,
-.011689,-.003432,
-.011543,-.003742,
-.011346,-.004023,
-.011102,-.004264,
-.010821,-.00446,
-.01051,-.004604,
-.010178,-.004691,
-.00984,-.00472,
0.0*
%
%ADD173MACRO173*%
%ADD103R,.021X.01*%
%ADD230R,.01X.021*%
%AMMACRO171*
4,1,40,-.00472,.00984,
-.00472,-.00984,
-.004691,-.010182,
-.004603,-.010513,
-.004458,-.010824,
-.004262,-.011105,
-.00402,-.011348,
-.00374,-.011545,
-.003429,-.01169,
-.003098,-.01178,
-.00276,-.01181,
.00276,-.01181,
.003101,-.011779,
.003432,-.011689,
.003742,-.011543,
.004023,-.011346,
.004264,-.011102,
.00446,-.010821,
.004604,-.01051,
.004691,-.010178,
.00472,-.00984,
.00472,.00984,
.004691,.010182,
.004603,.010513,
.004458,.010824,
.004262,.011105,
.00402,.011348,
.00374,.011545,
.003429,.01169,
.003098,.01178,
.00276,.01181,
-.00276,.01181,
-.003101,.011779,
-.003432,.011689,
-.003742,.011543,
-.004023,.011346,
-.004264,.011102,
-.00446,.010821,
-.004604,.01051,
-.004691,.010178,
-.00472,.00984,
0.0*
%
%ADD171MACRO171*%
%ADD162R,.02X.012*%
%AMMACRO134*
21,1,.016,.0041,0.0,0.0,110.*%
%ADD134MACRO134*%
%ADD38R,.022X.01*%
%ADD286R,.05X.01*%
%ADD274O,.255X.2*%
%ADD247R,.014X.01*%
%ADD127R,.032X.01*%
%ADD102R,.021X.012*%
%ADD37R,.01X.022*%
%ADD319R,.023X.011*%
%ADD246R,.015X.01*%
%ADD245R,.01X.014*%
%ADD229R,.012X.021*%
%AMMACRO215*
21,1,.016,.0041,0.0,0.0,112.*%
%ADD215MACRO215*%
%ADD126R,.01X.05*%
%ADD125R,.01X.032*%
%ADD322R,.011X.023*%
%ADD320R,.024X.011*%
%ADD313R,.05X.03*%
%ADD252R,.032X.012*%
%ADD244R,.01X.015*%
%ADD191R,.052X.01*%
%ADD321R,.011X.024*%
%AMMACRO269*
4,1,28,-.00748,-.00051,
-.00984,-.00051,
-.00985,-.00602,
-.009788,-.006695,
-.009614,-.00735,
-.009329,-.007964,
-.008942,-.00852,
-.008464,-.009,
-.00791,-.00939,
-.007296,-.009677,
-.006642,-.009854,
-.005967,-.009915,
-.00592,-.00991,
.0059,-.00993,
.006576,-.009875,
.007232,-.009708,
.00785,-.009429,
.008409,-.009047,
.008894,-.008574,
.009289,-.008024,
.009583,-.007413,
.009767,-.006761,
.009834,-.006087,
.00983,-.00604,
.00984,-.00053,
.00748,-.00053,
.00749,.0099,
-.00747,.00992,
-.00748,-.00051,
0.0*
%
%ADD269MACRO269*%
%ADD221R,.04X.032*%
%ADD138R,.012X.032*%
%AMMACRO137*
4,1,32,.06201,.01575,
.0502,.01575,
.0502,-.00197,
.04035,-.00197,
.04035,.01575,
.03248,.01575,
.03248,-.00197,
.02461,-.00197,
.02461,.01575,
.01673,.01575,
.01673,-.00197,
.00886,-.00197,
.00886,.01575,
.00098,.01575,
.00098,-.00197,
-.00689,-.00197,
-.00689,.01575,
-.01476,.01575,
-.01476,-.00197,
-.02264,-.00197,
-.02264,.01575,
-.03051,.01575,
-.03051,-.00197,
-.03839,-.00197,
-.03839,.01575,
-.04626,.01575,
-.04626,-.00197,
-.05413,-.00197,
-.05413,.01575,
-.06201,.01575,
-.06201,-.01575,
.06201,-.01575,
.06201,.01575,
0.0*
%
%ADD137MACRO137*%
%ADD117R,.032X.022*%
%ADD116R,.05X.04*%
%ADD104R,.02X.016*%
%ADD46R,.015X.012*%
%ADD20R,.034X.02*%
%AMMACRO276*
4,1,32,.01575,-.06201,
.01575,-.0502,
-.00197,-.0502,
-.00197,-.04035,
.01575,-.04035,
.01575,-.03248,
-.00197,-.03248,
-.00197,-.02461,
.01575,-.02461,
.01575,-.01673,
-.00197,-.01673,
-.00197,-.00886,
.01575,-.00886,
.01575,-.00098,
-.00197,-.00098,
-.00197,.00689,
.01575,.00689,
.01575,.01476,
-.00197,.01476,
-.00197,.02264,
.01575,.02264,
.01575,.03051,
-.00197,.03051,
-.00197,.03839,
.01575,.03839,
.01575,.04626,
-.00197,.04626,
-.00197,.05413,
.01575,.05413,
.01575,.06201,
-.01575,.06201,
-.01575,-.06201,
.01575,-.06201,
0.0*
%
%ADD276MACRO276*%
%ADD186R,.036X.01*%
%ADD180R,.016X.02*%
%ADD141R,.022X.032*%
%ADD123R,.02X.017*%
%ADD81R,.012X.015*%
%AMMACRO64*
4,1,44,-.01181,.00295,
-.01181,-.00295,
-.01178,-.003292,
-.011692,-.003623,
-.011548,-.003934,
-.011351,-.004215,
-.011109,-.004458,
-.010828,-.004655,
-.010517,-.004801,
-.010186,-.00489,
-.009845,-.00492,
-.00984,-.00492,
.00984,-.00492,
.010182,-.00489,
.010513,-.004802,
.010824,-.004658,
.011105,-.004461,
.011348,-.004219,
.011545,-.003938,
.011691,-.003627,
.01178,-.003296,
.01181,-.002955,
.01181,-.00295,
.01181,.00295,
.01178,.003292,
.011692,.003623,
.011548,.003934,
.011351,.004215,
.011109,.004458,
.010828,.004655,
.010517,.004801,
.010186,.00489,
.009845,.00492,
.00984,.00492,
-.00984,.00492,
-.010182,.00489,
-.010513,.004802,
-.010824,.004658,
-.011105,.004461,
-.011348,.004219,
-.011545,.003938,
-.011691,.003627,
-.01178,.003296,
-.01181,.002955,
-.01181,.00295,
0.0*
%
%ADD64MACRO64*%
%AMMACRO62*
4,1,44,.00295,.01181,
-.00295,.01181,
-.003292,.01178,
-.003623,.011692,
-.003934,.011548,
-.004215,.011351,
-.004458,.011109,
-.004655,.010828,
-.004801,.010517,
-.00489,.010186,
-.00492,.009845,
-.00492,.00984,
-.00492,-.00984,
-.00489,-.010182,
-.004802,-.010513,
-.004658,-.010824,
-.004461,-.011105,
-.004219,-.011348,
-.003938,-.011545,
-.003627,-.011691,
-.003296,-.01178,
-.002955,-.01181,
-.00295,-.01181,
.00295,-.01181,
.003292,-.01178,
.003623,-.011692,
.003934,-.011548,
.004215,-.011351,
.004458,-.011109,
.004655,-.010828,
.004801,-.010517,
.00489,-.010186,
.00492,-.009845,
.00492,-.00984,
.00492,.00984,
.00489,.010182,
.004802,.010513,
.004658,.010824,
.004461,.011105,
.004219,.011348,
.003938,.011545,
.003627,.011691,
.003296,.01178,
.002955,.01181,
.00295,.01181,
0.0*
%
%ADD62MACRO62*%
%ADD58R,.04X.05*%
%AMMACRO326*
4,1,8,-.02953,-.06299,
.02953,-.06299,
.02953,.06299,
-.02953,.06299,
-.02953,.01968,
.01771,.01968,
.01771,-.01968,
-.02953,-.01968,
-.02953,-.06299,
0.0*
%
%ADD326MACRO326*%
%ADD297R,.032X.024*%
%ADD273R,.05X.015*%
%ADD228R,.025X.013*%
%ADD223R,.063X.011*%
%ADD196R,.017X.02*%
%ADD157R,.028X.01*%
%ADD83R,.04X.015*%
%ADD35R,.02X.018*%
%ADD312R,.01X.028*%
%ADD288R,.063X.012*%
%ADD275R,.052X.014*%
%ADD231R,.166X.13*%
%AMMACRO214*
21,1,.016,.0041,0.0,0.0,135.*%
%ADD214MACRO214*%
%ADD206R,.042X.024*%
%ADD152R,.053X.022*%
%ADD105R,.024X.032*%
%ADD101R,.013X.025*%
%ADD80R,.018X.02*%
%ADD52R,.018X.012*%
%AMMACRO40*
4,1,8,-.06299,.02953,
-.06299,-.02953,
.06299,-.02953,
.06299,.02953,
.01968,.02953,
.01968,-.01771,
-.01968,-.01771,
-.01968,.02953,
-.06299,.02953,
0.0*
%
%ADD40MACRO40*%
%ADD34R,.029X.01*%
%AMMACRO314*
4,1,8,.09252,-.09055,
.09252,-.0315,
.08268,-.0315,
.08268,.09055,
-.08268,.09055,
-.08268,-.0315,
-.09252,-.0315,
-.09252,-.09055,
.09252,-.09055,
0.0*
%
%ADD314MACRO314*%
%AMMACRO307*
4,1,8,.09055,.09252,
.0315,.09252,
.0315,.08268,
-.09055,.08268,
-.09055,-.08268,
.0315,-.08268,
.0315,-.09252,
.09055,-.09252,
.09055,.09252,
0.0*
%
%ADD307MACRO307*%
%ADD280R,.27X.126*%
%ADD220R,.022X.053*%
%ADD210R,.044X.014*%
%ADD198R,.024X.042*%
%ADD176R,.05X.035*%
%ADD170R,.052X.024*%
%ADD33R,.01X.029*%
%ADD317C,.122*%
%ADD287R,.063X.014*%
%ADD258R,.036X.032*%
%ADD168R,.035X.05*%
%ADD166R,.024X.052*%
%ADD153R,.014X.044*%
%ADD151R,.138X.115*%
%ADD31R,.024X.017*%
%ADD27R,.036X.04*%
%ADD21R,.034X.016*%
%AMMACRO324*
4,1,32,.05512,.01181,
.04331,.01181,
.04331,-.00098,
.03543,-.00098,
.03543,.01181,
.02362,.01181,
.02362,-.00098,
.01575,-.00098,
.01575,.01181,
.00394,.01181,
.00394,-.00098,
-.00394,-.00098,
-.00394,.01181,
-.01575,.01181,
-.01575,-.00098,
-.02362,-.00098,
-.02362,.01181,
-.03543,.01181,
-.03543,-.00098,
-.04331,-.00098,
-.04331,.01181,
-.05512,.01181,
-.05512,-.00098,
-.06299,-.00098,
-.06299,.01181,
-.0748,.01181,
-.0748,-.01181,
.0748,-.01181,
.0748,.01181,
.06299,.01181,
.06299,-.00098,
.05512,-.00098,
.05512,.01181,
0.0*
%
%ADD324MACRO324*%
%ADD315R,.044X.016*%
%AMMACRO310*
4,1,8,.01771,.01476,
-.01772,.01476,
-.01772,-.01476,
.01771,-.01476,
.01771,-.00492,
-.00394,-.00492,
-.00394,.00492,
.01771,.00492,
.01771,.01476,
0.0*
%
%ADD310MACRO310*%
%ADD301R,.063X.015*%
%ADD283R,.014X.063*%
%AMMACRO268*
4,1,28,-.00748,.00052,
-.00984,.00052,
-.00983,.00603,
-.009775,.006705,
-.0096,.007359,
-.009313,.007973,
-.008925,.008528,
-.008446,.009007,
-.007891,.009395,
-.007277,.009682,
-.006622,.009857,
-.005948,.009916,
-.0059,.00992,
.00592,.0099,
.006595,.009852,
.007251,.009684,
.007868,.009404,
.008427,.009021,
.008911,.008546,
.009305,.007996,
.009598,.007384,
.00978,.006732,
.009845,.006058,
.00985,.00601,
.00984,.0005,
.00748,.0005,
.00747,-.00993,
-.00749,-.00991,
-.00748,.00052,
0.0*
%
%ADD268MACRO268*%
%ADD175R,.054X.024*%
%AMMACRO159*
4,1,8,.01476,-.01771,
.01476,.01772,
-.01476,.01772,
-.01476,-.01771,
-.00492,-.01771,
-.00492,.00394,
.00492,.00394,
.00492,-.01771,
.01476,-.01771,
0.0*
%
%ADD159MACRO159*%
%ADD129R,.115X.138*%
%ADD114R,.017X.024*%
%ADD113R,.032X.028*%
%ADD107R,.056X.04*%
%ADD68R,.032X.036*%
%ADD303R,.048X.04*%
%ADD296R,.036X.016*%
%ADD278R,.128X.135*%
%ADD264R,.056X.05*%
%ADD236R,.024X.054*%
%ADD208R,.046X.024*%
%ADD179R,.028X.032*%
%ADD174R,.054X.016*%
%ADD156R,.052X.018*%
%ADD99R,.028X.024*%
%ADD82R,.056X.014*%
%ADD67R,.04X.056*%
%ADD39R,.016X.044*%
%ADD304R,.024X.028*%
%ADD302R,.04X.048*%
%ADD292R,.054X.044*%
%ADD271R,.1692X.13*%
%ADD242R,.065X.024*%
%ADD235R,.016X.054*%
%ADD226R,.024X.046*%
%ADD219R,.014X.056*%
%ADD212R,.054X.026*%
%ADD167R,.012X.049*%
%ADD164R,.016X.036*%
%ADD17R,.095X.03*%
%ADD12C,.125*%
%ADD266C,.315*%
%ADD257R,.049X.014*%
%ADD209R,.046X.017*%
%ADD165R,.044X.054*%
%ADD145R,.056X.052*%
%ADD249C,.217*%
%ADD239R,.052X.056*%
%ADD233R,.063X.046*%
%ADD227R,.017X.046*%
%ADD217R,.048X.025*%
%ADD213R,.059X.014*%
%ADD178R,.038X.026*%
%ADD150R,.014X.049*%
%ADD139R,.079X.012*%
%ADD69R,.091X.081*%
%ADD44R,.015X.057*%
%ADD25C,.244*%
%ADD308R,.046X.028*%
%ADD295R,.028X.036*%
%ADD261R,.014X.059*%
%ADD253R,.012X.079*%
%ADD149R,.026X.038*%
%AMMACRO88*
4,1,21,-.0085,.0035,
.012,.0035,
.012,-.0035,
-.0085,-.0035,
-.009108,-.003447,
-.009697,-.003289,
-.01025,-.003031,
-.01075,-.002681,
-.011181,-.00225,
-.011531,-.00175,
-.011789,-.001197,
-.011947,-.000608,
-.012,0.0,
-.011947,.000608,
-.011789,.001197,
-.011531,.00175,
-.011181,.00225,
-.01075,.002681,
-.01025,.003031,
-.009697,.003289,
-.009108,.003447,
-.0085,.0035,
0.0*
%
%ADD88MACRO88*%
%ADD84R,.028X.046*%
%ADD32R,.14X.14*%
%ADD306R,.096X.034*%
%AMMACRO89*
4,1,21,.0035,.0085,
.0035,-.012,
-.0035,-.012,
-.0035,.0085,
-.003447,.009108,
-.003289,.009697,
-.003031,.01025,
-.002681,.01075,
-.00225,.011181,
-.00175,.011531,
-.001197,.011789,
-.000608,.011947,
0.0,.012,
.000608,.011947,
.001197,.011789,
.00175,.011531,
.00225,.011181,
.002681,.01075,
.003031,.01025,
.003289,.009697,
.003447,.009108,
.0035,.0085,
0.0*
%
%ADD89MACRO89*%
%ADD325R,.197X.128*%
%ADD293R,.017X.059*%
%ADD201R,.205X.205*%
%ADD169R,.124X.124*%
%ADD148C,.009*%
%ADD140C,.158*%
%ADD238R,.134X.134*%
%ADD73R,.099X.042*%
%ADD24R,.048X.056*%
%AMMACRO161*
4,1,8,.0425,.0764,
-.0425,.0764,
-.0425,-.0764,
.0425,-.0764,
.0425,-.0236,
.0145,-.0236,
.0145,.0236,
.0425,.0236,
.0425,.0764,
0.0*
%
%ADD161MACRO161*%
%ADD144R,.042X.099*%
%ADD132C,.178*%
%ADD61R,.144X.144*%
%ADD13C,.394*%
%ADD267R,.166X.197*%
%ADD262R,.059X.048*%
%AMMACRO323*
4,1,24,-.01051,.04391,
-.01188,.04527,
-.03394,.04527,
-.03394,.03346,
-.02016,.03348,
-.02016,.02559,
-.03394,.02559,
-.03394,.01379,
-.02016,.0138,
-.02016,.0059,
-.03394,.00592,
-.03394,-.00591,
-.02016,-.00589,
-.02016,-.01378,
-.03394,-.01378,
-.03394,-.0256,
-.02016,-.02557,
-.02016,-.03347,
-.03394,-.03347,
-.03394,-.04527,
-.01188,-.04527,
-.00913,-.04255,
.03394,-.04255,
.03394,.04391,
-.01051,.04391,
0.0*
%
%ADD323MACRO323*%
%ADD47R,.059X.02047*%
%ADD263R,.189X.186*%
%ADD118R,.138X.138*%
%ADD79R,.174X.174*%
%ADD53R,.069X.077*%
%AMMACRO23*
4,1,28,.00052,-.00748,
.00052,-.00984,
.00603,-.00984,
.006705,-.009782,
.007359,-.009607,
.007974,-.009321,
.008529,-.008933,
.009009,-.008455,
.009398,-.0079,
.009685,-.007286,
.009861,-.006632,
.00992,-.005957,
.00992,-.00591,
.00992,.00591,
.009869,.006585,
.009701,.007242,
.009421,.007859,
.009039,.008418,
.008565,.008903,
.008015,.009297,
.007404,.009591,
.006751,.009773,
.006077,.00984,
.00603,.00984,
.00052,.00984,
.00052,.00748,
-.00991,.00748,
-.00991,-.00748,
.00052,-.00748,
0.0*
%
%ADD23MACRO23*%
%AMMACRO19*
4,1,28,.00748,.00052,
.00984,.00052,
.00984,.00603,
.009782,.006705,
.009607,.007359,
.009321,.007974,
.008933,.008529,
.008455,.009009,
.0079,.009398,
.007286,.009685,
.006632,.009861,
.005957,.00992,
.00591,.00992,
-.00591,.00992,
-.006585,.009869,
-.007242,.009701,
-.007859,.009421,
-.008418,.009039,
-.008903,.008565,
-.009297,.008015,
-.009591,.007404,
-.009773,.006751,
-.00984,.006077,
-.00984,.00603,
-.00984,.00052,
-.00748,.00052,
-.00748,-.00991,
.00748,-.00991,
.00748,.00052,
0.0*
%
%ADD19MACRO19*%
%ADD147R,.099X.067*%
%ADD163R,.067X.099*%
%AMMACRO285*
4,1,5,.01673,-.00492,
.01673,.00492,
-.01673,.00492,
-.01673,-.00098,
-.0128,-.00492,
.01673,-.00492,
0.0*
%
%ADD285MACRO285*%
%AMMACRO187*
4,1,5,-.01378,-.00098,
-.01378,.00492,
.01378,.00492,
.01378,-.00492,
-.00984,-.00492,
-.01378,-.00098,
0.0*
%
%ADD187MACRO187*%
%AMMACRO22*
4,1,28,-.00051,-.00748,
-.00051,-.00984,
-.00602,-.00984,
-.006695,-.009782,
-.007349,-.009607,
-.007964,-.009321,
-.008519,-.008933,
-.008998,-.008455,
-.009388,-.0079,
-.009675,-.007287,
-.009851,-.006632,
-.00991,-.005958,
-.00991,-.00591,
-.00991,.00591,
-.009859,.006585,
-.009691,.007242,
-.009411,.007859,
-.009029,.008418,
-.008555,.008903,
-.008005,.009297,
-.007394,.00959,
-.006742,.009773,
-.006068,.00984,
-.00602,.00984,
-.00051,.00984,
-.00051,.00748,
.00992,.00748,
.00992,-.00748,
-.00051,-.00748,
0.0*
%
%ADD22MACRO22*%
%AMMACRO18*
4,1,28,.00748,-.00051,
.00984,-.00051,
.00984,-.00602,
.009782,-.006695,
.009607,-.007349,
.009321,-.007964,
.008933,-.008519,
.008455,-.008998,
.0079,-.009388,
.007287,-.009675,
.006632,-.009851,
.005958,-.00991,
.00591,-.00991,
-.00591,-.00991,
-.006585,-.009859,
-.007242,-.009691,
-.007859,-.009411,
-.008418,-.009029,
-.008903,-.008555,
-.009297,-.008005,
-.00959,-.007394,
-.009773,-.006742,
-.00984,-.006068,
-.00984,-.00602,
-.00984,-.00051,
-.00748,-.00051,
-.00748,.00992,
.00748,.00992,
.00748,-.00051,
0.0*
%
%ADD18MACRO18*%
%AMMACRO189*
4,1,5,-.00098,.01378,
.00492,.01378,
.00492,-.01378,
-.00492,-.01378,
-.00492,.00984,
-.00098,.01378,
0.0*
%
%ADD189MACRO189*%
%AMMACRO98*
4,1,13,-.00002,-.012,
-.000627,-.011943,
-.001216,-.011782,
-.001767,-.011521,
-.002265,-.011168,
-.002694,-.010734,
-.003041,-.010233,
-.003296,-.009678,
-.00345,-.009088,
-.0035,-.0085,
-.0035,.012,
.0035,.012,
.0035,-.00848,
-.00002,-.012,
0.0*
%
%ADD98MACRO98*%
%AMMACRO94*
4,1,13,.012,-.00002,
.011943,-.000627,
.011782,-.001216,
.011521,-.001767,
.011168,-.002265,
.010734,-.002694,
.010233,-.003041,
.009678,-.003296,
.009088,-.00345,
.0085,-.0035,
-.012,-.0035,
-.012,.0035,
.00848,.0035,
.012,-.00002,
0.0*
%
%ADD94MACRO94*%
%AMMACRO128*
4,1,6,.1063,.04134,
.1063,-.01378,
.03543,-.01378,
.03543,-.04134,
-.1063,-.04134,
-.1063,.04134,
.1063,.04134,
0.0*
%
%ADD128MACRO128*%
%AMMACRO194*
4,1,5,-.01378,.00098,
-.01378,-.00492,
.01378,-.00492,
.01378,.00492,
-.00984,.00492,
-.01378,.00098,
0.0*
%
%ADD194MACRO194*%
%AMMACRO311*
4,1,9,.01181,.01476,
-.01771,.01476,
-.01771,.00492,
.00394,.00492,
.00394,-.00492,
-.01771,-.00492,
-.01771,-.01476,
.01772,-.01476,
.01772,.00886,
.01181,.01476,
0.0*
%
%ADD311MACRO311*%
%AMMACRO284*
4,1,8,.0246,.01821,
.0246,-.01821,
.01476,-.01821,
.01476,.00837,
-.01477,.00837,
-.01477,-.01821,
-.02461,-.01821,
-.02461,.01821,
.0246,.01821,
0.0*
%
%ADD284MACRO284*%
%AMMACRO188*
4,1,5,.00098,.01378,
-.00492,.01378,
-.00492,-.01378,
.00492,-.01378,
.00492,.00984,
.00098,.01378,
0.0*
%
%ADD188MACRO188*%
%AMMACRO160*
4,1,9,.01476,-.01181,
.01476,.01771,
.00492,.01771,
.00492,-.00394,
-.00492,-.00394,
-.00492,.01771,
-.01476,.01771,
-.01476,-.01772,
.00886,-.01772,
.01476,-.01181,
0.0*
%
%ADD160MACRO160*%
%AMMACRO97*
4,1,13,-.0035,-.00849,
-.0035,.012,
.0035,.012,
.0035,-.0085,
.003447,-.009108,
.003289,-.009697,
.003031,-.01025,
.002681,-.01075,
.00225,-.011181,
.00175,-.011531,
.001197,-.011789,
.000608,-.011947,
.00001,-.012,
-.0035,-.00849,
0.0*
%
%ADD97MACRO97*%
%AMMACRO86*
4,1,13,.00849,-.0035,
-.012,-.0035,
-.012,.0035,
.0085,.0035,
.009108,.003447,
.009697,.003289,
.01025,.003031,
.01075,.002681,
.011181,.00225,
.011531,.00175,
.011789,.001197,
.011947,.000608,
.012,.00001,
.00849,-.0035,
0.0*
%
%ADD86MACRO86*%
%AMMACRO211*
4,1,5,.00394,.01772,
-.00394,.01772,
-.00394,-.01772,
0.0,-.01772,
.00394,-.01378,
.00394,.01772,
0.0*
%
%ADD211MACRO211*%
%ADD330C,.01*%
%ADD331C,.013*%
%ADD332C,.014*%
%ADD333C,.017*%
%ADD334C,.01378*%
%ADD335C,.003*%
%ADD336C,.004*%
%ADD337C,.0041*%
%ADD338C,.005*%
%ADD339C,.006*%
%ADD340C,.0051*%
%ADD341C,.0042*%
%ADD342C,.0052*%
%ADD343C,.007*%
%ADD344C,.0053*%
%ADD345C,.008*%
%ADD346C,.0058*%
%ADD347C,.00399*%
%ADD356C,.03004*%
%ADD351C,.04004*%
%ADD348C,.03006*%
%ADD358C,.07005*%
%ADD352C,.07006*%
%ADD362C,.03444*%
%ADD349C,.02904*%
%ADD350C,.10006*%
%ADD363C,.1622*%
%ADD357C,.32506*%
%ADD361C,.43406*%
%ADD359C,.2582*%
%ADD360C,.33606*%
%ADD353C,.198*%
%ADD355C,.19801*%
%ADD354C,.19799*%
G75*
%LPD*%
G75*
G36*
G01X2000Y54252D02*
Y68016D01*
X2192Y68208D01*
X2512D01*
X3998Y66722D01*
Y54252D01*
G03X7874Y50376I3876J0D01*
G01X43709D01*
G02X55580Y38504I-1J-11872D01*
G01Y16000D01*
X54210Y14630D01*
X53843D01*
X53583Y14890D01*
Y38504D01*
G03X43709Y48378I-9874J0D01*
G01X7874D01*
G02X2000Y54252I0J5874D01*
G37*
G36*
G01X9874Y320190D02*
Y621983D01*
X10082Y622191D01*
X10472D01*
X10873Y621790D01*
G03X11855Y619253I29839J10091D01*
G02X11872Y619173I-183J-81D01*
G01Y320190D01*
G02X8394Y311797I-11872J2D01*
G01X5132Y308535D01*
G03X3998Y305796I2742J-2739D01*
G01Y108797D01*
X2683Y107482D01*
X2225D01*
X2000Y107707D01*
Y305795D01*
G02X3720Y309947I5873J-1D01*
G01X6982Y313209D01*
G03X9874Y320190I-6982J6982D01*
G37*
G36*
G01X29703Y402250D02*
X33692D01*
G02X33834Y402191I0J-200D01*
G01X34003Y402022D01*
G02X34062Y401880I-141J-142D01*
G01Y401103D01*
X34043Y401084D01*
Y399538D01*
G03X34102Y399396I200J0D01*
G01X34426Y399072D01*
G03X34568Y399013I142J141D01*
G01X37326D01*
G02X37468Y398954I0J-200D01*
G01X40167Y396255D01*
G02X40226Y396113I-141J-142D01*
G01Y394911D01*
G02X40167Y394769I-200J0D01*
G01X39641Y394243D01*
G02X39499Y394184I-142J141D01*
G01X34311D01*
G03X34169Y394125I0J-200D01*
G01X33014Y392970D01*
G02X32872Y392911I-142J141D01*
G01X29334D01*
G02X29192Y392970I0J200D01*
G01X29035Y393127D01*
G02X28976Y393269I141J142D01*
G01Y397098D01*
G03X28917Y397240I-200J0D01*
G01X28497Y397660D01*
G03X28355Y397719I-142J-141D01*
G01X23022D01*
G03X22880Y397660I0J-200D01*
G01X22428Y397208D01*
G03X22369Y397066I141J-142D01*
G01Y391114D01*
G03X22428Y390972I200J0D01*
G01X23063Y390337D01*
G03X23205Y390278I142J141D01*
G01X26621D01*
G02X26763Y390219I0J-200D01*
G01X27075Y389907D01*
G02X27134Y389765I-141J-142D01*
G01Y385703D01*
G03X27193Y385561I200J0D01*
G01X27719Y385035D01*
G03X27861Y384976I142J141D01*
G01X34520D01*
G03X34662Y385035I0J200D01*
G01X34777Y385150D01*
X34847Y385180D01*
X34886Y385181D01*
G03X35717Y385535I-25J1211D01*
G01X36228Y386046D01*
G02X36369Y386105I142J-141D01*
G01X39876D01*
G02X40018Y386046I0J-200D01*
G01X40369Y385695D01*
G02X40428Y385553I-141J-142D01*
G01Y383911D01*
G02X40369Y383769I-200J0D01*
G01X39333Y382733D01*
G02X39191Y382674I-142J141D01*
G01X24470D01*
G02X24328Y382733I0J200D01*
G01X20079Y386982D01*
G02X20020Y387124I141J142D01*
G01Y397689D01*
G02X20079Y397831I200J0D01*
G01X22146Y399898D01*
G02X22288Y399957I142J-141D01*
G01X27244D01*
G03X27386Y400016I0J200D01*
G01X29561Y402191D01*
G02X29703Y402250I142J-141D01*
G37*
G36*
G01X49445Y533465D02*
X53329D01*
G03X53471Y533524I0J200D01*
G01X53763Y533816D01*
G03X53822Y533958I-141J142D01*
G01Y535922D01*
G02X53881Y536064I200J0D01*
G01X53923Y536106D01*
G02X54065Y536165I142J-141D01*
G01X54439D01*
G02X54581Y536106I0J-200D01*
G01X54721Y535966D01*
G02X54780Y535824I-141J-142D01*
G01Y533770D01*
G03X54839Y533628I200J0D01*
G01X55853Y532614D01*
G03X55995Y532555I142J141D01*
G01X57739D01*
G02X57881Y532496I0J-200D01*
G01X58063Y532314D01*
G02X58122Y532172I-141J-142D01*
G01Y527878D01*
G03X58181Y527736I200J0D01*
G01X58653Y527264D01*
G03X58795Y527205I142J141D01*
G01X58914D01*
G02X59114Y527005I0J-200D01*
G01Y526393D01*
X59084Y526320D01*
X59064Y526300D01*
X59030D01*
X58957Y526270D01*
X58181Y525494D01*
G03X58122Y525352I141J-142D01*
G01Y523238D01*
G02X58063Y523096I-200J0D01*
G01X57951Y522984D01*
G02X57809Y522925I-142J141D01*
G01X55245D01*
G03X55103Y522866I0J-200D01*
G01X54791Y522554D01*
G03X54732Y522412I141J-142D01*
G01Y519538D01*
G02X54673Y519396I-200J0D01*
G01X54631Y519354D01*
G02X54489Y519295I-142J141D01*
G01X54175D01*
G02X54033Y519354I0J200D01*
G01X53901Y519486D01*
G02X53842Y519628I141J142D01*
G01Y522322D01*
G03X53783Y522464I-200J0D01*
G01X53441Y522806D01*
G03X53299Y522865I-142J-141D01*
G01X48265D01*
G03X48123Y522806I0J-200D01*
G01X47691Y522374D01*
G02X47549Y522315I-142J141D01*
G01X45105D01*
G02X44963Y522374I0J200D01*
G01X44921Y522416D01*
G02X44862Y522558I141J142D01*
G01Y523022D01*
G02X44921Y523164I200J0D01*
G01X44993Y523236D01*
G02X45135Y523295I142J-141D01*
G01X46919D01*
G03X47061Y523354I0J200D01*
G01X47163Y523456D01*
G03X47222Y523598I-141J142D01*
G01Y523962D01*
G03X47163Y524104I-200J0D01*
G01X47101Y524166D01*
G03X46959Y524225I-142J-141D01*
G01X45245D01*
G02X45103Y524284I0J200D01*
G01X44971Y524416D01*
G02X44912Y524558I141J142D01*
G01Y525012D01*
G02X44971Y525154I200J0D01*
G01X45003Y525186D01*
G02X45145Y525245I142J-141D01*
G01X48009D01*
G03X48151Y525304I0J200D01*
G01X48603Y525756D01*
G03X48662Y525898I-141J142D01*
G01Y532212D01*
G03X48603Y532354I-200J0D01*
G01X45832Y535126D01*
X45700Y535258D01*
G03X45558Y535316I-141J-142D01*
G01X42798D01*
G02X42648Y535384I0J200D01*
G03X42168Y535784I-1506J-1319D01*
G03X41663Y535998I-1026J-1718D01*
G02X41651Y536002I57J192D01*
G03X41012Y536107I-640J-1897D01*
G01X41010D01*
G03X39473Y535388I0J-2002D01*
G02X39320Y535316I-154J128D01*
G01X37855D01*
G02X37692Y535400I0J200D01*
G03X36962Y535772I-724J-519D01*
G01X35784D01*
X35782D01*
G03X34886Y534882I-6J-890D01*
G01Y534622D01*
G02X34762Y534437I-200J0D01*
G01X34706Y534413D01*
X34588Y534437D01*
X34391Y534634D01*
G02X34332Y534776I141J142D01*
G01Y534806D01*
G03X34132Y535006I-200J0D01*
G01X34096D01*
Y535850D01*
G03X33896Y536050I-200J0D01*
G01X31798D01*
G03X31598Y535850I0J-200D01*
G01Y535695D01*
X31533Y535596D01*
X31479Y535572D01*
G03X31115Y535322I493J-1107D01*
G01X30500Y534707D01*
G02X30332Y534650I-142J141D01*
G03X30167Y534662I-170J-1200D01*
G01X24562D01*
G02X24420Y534721I0J200D01*
G01X23547Y535593D01*
G02X23488Y535735I141J142D01*
G01Y540155D01*
G03X22987Y540656I-501J0D01*
G01X18187D01*
G03X17686Y540155I0J-501D01*
G01Y534247D01*
G03X18187Y533746I501J0D01*
G01X21885D01*
G02X22027Y533687I0J-200D01*
G01X23120Y532593D01*
G03X23686Y532274I856J857D01*
G01X23721Y532265D01*
X23780Y532225D01*
X23952Y531983D01*
G02X23988Y531848I-163J-116D01*
G03X23986Y531801I499J-45D01*
G01Y525893D01*
G03X24487Y525392I501J0D01*
G01X29287D01*
G03X29788Y525893I0J501D01*
G01Y527440D01*
G02X29988Y527640I200J0D01*
G01X31324D01*
G02X31524Y527440I0J-200D01*
G01X31604Y527360D01*
X32563D01*
G02X32705Y527301I0J-200D01*
G01X33691Y526314D01*
G02X33750Y526172I-141J-142D01*
G01Y525621D01*
G03X34105Y524764I1212J0D01*
G01X34709Y524160D01*
G03X35564Y523806I856J857D01*
G01X38277D01*
G03X39132Y524160I-1J1211D01*
G01X39912Y524940D01*
G02X40092Y524994I141J-142D01*
G01X40140Y524985D01*
X40216Y524922D01*
X40291Y524742D01*
G02X40248Y524524I-185J-77D01*
G01X38165Y522441D01*
G03X38151Y522427I991J-1005D01*
G03X38143Y522419I137J-145D01*
G01X38142Y522417D01*
G02X38136Y522411I-144J138D01*
G03X38088Y522358I1022J-974D01*
G01X38085Y522355D01*
X37974Y522304D01*
G02X37890Y522285I-85J181D01*
G01X20941D01*
G02X20850Y522307I0J200D01*
G02X20800Y522343I90J178D01*
G01X20232Y522911D01*
G03X20090Y522970I-142J-141D01*
G01X17686D01*
G02X17595Y522992I0J200D01*
G02X17545Y523028I90J178D01*
G01X15570Y525003D01*
G02X15534Y525053I142J140D01*
G02X15512Y525144I178J91D01*
G01Y540776D01*
G02X15516Y540814I200J-2D01*
G02X15569Y540916I196J-37D01*
G01X17291Y542638D01*
G02X17393Y542691I139J-143D01*
G02X17431Y542695I40J-196D01*
G01X34085D01*
G03X34227Y542754I0J200D01*
G01X36271Y544798D01*
G02X36373Y544851I139J-143D01*
G02X36411Y544855I40J-196D01*
G01X43527D01*
G02X43565Y544851I-2J-200D01*
G02X43667Y544798I-37J-196D01*
G01X47179Y541286D01*
X47194Y541250D01*
G03X48262Y540182I1845J777D01*
G01X48298Y540167D01*
X48915Y539550D01*
G02X48968Y539448I-143J-139D01*
G02X48972Y539410I-196J-40D01*
G01Y533938D01*
G03X49031Y533796I200J0D01*
G01X49303Y533524D01*
G03X49445Y533465I142J141D01*
G37*
G36*
G01X11086Y1358199D02*
G03X11855Y1356273I29621J10710D01*
G02X11872Y1356193I-183J-81D01*
G01Y644604D01*
G02X11855Y644524I-200J1D01*
G03X10922Y642132I28854J-12632D01*
G01X10506Y641716D01*
X10054D01*
X9874Y641896D01*
Y1358403D01*
X10144Y1358673D01*
X10612D01*
X11086Y1358199D01*
G37*
G36*
G01X29588Y1691567D02*
Y1612317D01*
G02X26110Y1603922I-11872J1D01*
G01X13007Y1590819D01*
G03X11872Y1588079I2742J-2741D01*
G01Y1381623D01*
G02X11855Y1381543I-200J1D01*
G03X11322Y1380247I28857J-12625D01*
G03X11204Y1379937I29378J-11360D01*
G03X11020Y1379432I29502J-11035D01*
G01X10708Y1379120D01*
X10144D01*
X9874Y1379390D01*
Y1588078D01*
G02X11594Y1592231I5874J0D01*
G01X24698Y1605335D01*
G03X27591Y1612317I-6982J6983D01*
G01Y1692680D01*
X27759Y1692848D01*
X28307D01*
X29588Y1691567D01*
G37*
G36*
G01X17433Y1449020D02*
X23137D01*
G02X23279Y1448961I0J-200D01*
G01X24611Y1447629D01*
G02X24670Y1447487I-141J-142D01*
G01Y1428435D01*
G02X24644Y1428336I-200J0D01*
G03X23566Y1424257I7174J-4078D01*
G03X24644Y1420178I8252J-1D01*
G02X24670Y1420079I-174J-99D01*
G01Y1413543D01*
G03X24729Y1413401I200J0D01*
G01X36831Y1401299D01*
G03X36973Y1401240I142J141D01*
G01X94627D01*
G02X94769Y1401181I0J-200D01*
G01X98901Y1397049D01*
G02X98960Y1396907I-141J-142D01*
G01Y1385313D01*
G02X98901Y1385171I-200J0D01*
G01X98669Y1384939D01*
G02X98527Y1384880I-142J141D01*
G01X95742D01*
X95726Y1384883D01*
G03X95532Y1384898I-189J-1183D01*
G01X94004D01*
G02X93863Y1384957I1J200D01*
G01X93719Y1385101D01*
G02X93660Y1385243I141J142D01*
G01Y1390027D01*
G03X93601Y1390169I-200J0D01*
G01X90099Y1393671D01*
G03X89957Y1393730I-142J-141D01*
G01X26933D01*
G02X26791Y1393789I0J200D01*
G01X15804Y1404776D01*
G02X15746Y1404917I142J141D01*
G01Y1447333D01*
G02X15804Y1447474I200J0D01*
G01X17291Y1448961D01*
G02X17433Y1449020I142J-141D01*
G37*
G36*
G01X96714Y1531895D02*
X96577Y1532032D01*
G03X96435Y1532091I-142J-141D01*
G01X94200D01*
G02X94000Y1532291I0J200D01*
G01Y1537284D01*
G03X93985Y1537301I-157J-124D01*
G01X93916Y1537369D01*
G02X93856Y1537512I140J143D01*
G01X93776Y1537592D01*
G03X93634Y1537651I-142J-141D01*
G01X90500D01*
G02X90358Y1537710I0J200D01*
G01X90276Y1537792D01*
G02X90217Y1537934I141J142D01*
G01Y1538368D01*
G02X90276Y1538510I200J0D01*
G01X90287Y1538521D01*
X90360Y1538551D01*
X93452D01*
G03X93594Y1538610I0J200D01*
G01X93958Y1538974D01*
G03X94017Y1539116I-141J142D01*
G01Y1539651D01*
G02X94217Y1539851I200J0D01*
G01X100826D01*
G02X100968Y1539792I0J-200D01*
G01X100987Y1539773D01*
X101017Y1539700D01*
Y1531034D01*
G03X101076Y1530892I200J0D01*
G01X101419Y1530549D01*
G03X101445Y1530547I28J198D01*
G01X118577D01*
G03X118719Y1530606I0J200D01*
G01X121567Y1533454D01*
X123240Y1535126D01*
Y1535234D01*
Y1584060D01*
G03X123181Y1584202I-200J0D01*
G01X121704Y1585679D01*
G03X121562Y1585738I-142J-141D01*
G01X107859D01*
G02X107717Y1585797I0J200D01*
G01X106662Y1586852D01*
G02X106603Y1586994I141J142D01*
G01Y1603144D01*
G02X106662Y1603286I200J0D01*
G01X106875Y1603499D01*
G02X107017Y1603558I142J-141D01*
G01X147157D01*
G02X147299Y1603499I0J-200D01*
G01X148908Y1601890D01*
X148927Y1601760D01*
X148895Y1601701D01*
G03X146852Y1593672I14758J-8030D01*
G03X149050Y1585364I16800J0D01*
G02X149076Y1585265I-174J-99D01*
G01Y1505185D01*
G02X149017Y1505043I-200J0D01*
G01X147941Y1503967D01*
G02X147799Y1503908I-142J141D01*
G01X112899D01*
X112824Y1503876D01*
X112798Y1503849D01*
X55918D01*
G03X55776Y1503790I0J-200D01*
G01X53389Y1501402D01*
G02X53247Y1501343I-142J141D01*
G01X37150D01*
G02X37008Y1501402I0J200D01*
G01X36972Y1501438D01*
G02X36913Y1501580I141J142D01*
G01Y1503631D01*
G03X36854Y1503773I-200J0D01*
G01X35895Y1504732D01*
G03X35753Y1504791I-142J-141D01*
G01X23718D01*
G03X23576Y1504732I0J-200D01*
G01X21246Y1502402D01*
G03X21187Y1502260I141J-142D01*
G01Y1470996D01*
G03X21246Y1470854I200J0D01*
G01X22700Y1469400D01*
G03X22842Y1469341I142J141D01*
G01X102735D01*
G02X102877Y1469282I0J-200D01*
G01X104259Y1467900D01*
G02X104318Y1467758I-141J-142D01*
G01Y1454340D01*
G02X104259Y1454198I-200J0D01*
G01X102877Y1452816D01*
G02X102735Y1452757I-142J141D01*
G01X14234D01*
G02X14092Y1452816I0J200D01*
G01X13189Y1453719D01*
G02X13130Y1453861I141J142D01*
G01Y1579823D01*
G02X13189Y1579965I200J0D01*
G01X15117Y1581893D01*
G02X15259Y1581952I142J-141D01*
G01X68491D01*
G02X68633Y1581893I0J-200D01*
G01X69776Y1580750D01*
G02X69835Y1580608I-141J-142D01*
G01Y1556499D01*
G02X69776Y1556357I-200J0D01*
G01X69144Y1555725D01*
G02X69002Y1555666I-142J141D01*
G01X57787D01*
G02X57645Y1555725I0J200D01*
G01X50042Y1563328D01*
G03X49900Y1563387I-142J-141D01*
G01X44835D01*
G03X44693Y1563328I0J-200D01*
G01X38080Y1556715D01*
G03X38021Y1556573I141J-142D01*
G01Y1549444D01*
G03X38080Y1549302I200J0D01*
G01X38095Y1549287D01*
X38125Y1549214D01*
Y1539295D01*
G03X38184Y1539153I200J0D01*
G01X46611Y1530726D01*
G03X46753Y1530667I142J141D01*
G01X49220D01*
G03X49362Y1530726I0J200D01*
G01X49587Y1530951D01*
G02X49729Y1531010I142J-141D01*
G01X52372D01*
X52446Y1530980D01*
X52474Y1530951D01*
X52709Y1530716D01*
G02X52768Y1530574I-141J-142D01*
G01Y1528279D01*
G03X52827Y1528137I200J0D01*
G01X53108Y1527856D01*
G03X53250Y1527797I142J141D01*
G01X55269D01*
X55275Y1527791D01*
X61392D01*
G03X61534Y1527850I0J200D01*
G01X61616Y1527932D01*
G03X61675Y1528074I-141J142D01*
G01Y1528650D01*
X61674Y1528651D01*
Y1531192D01*
G03X61615Y1531334I-200J0D01*
G01X61113Y1531836D01*
G03X60971Y1531895I-142J-141D01*
G01X60834Y1532032D01*
G03X60692Y1532091I-142J-141D01*
G01X58457D01*
G02X58257Y1532291I0J200D01*
G01Y1537285D01*
G03X58198Y1537427I-200J0D01*
G01X58033Y1537592D01*
G03X57891Y1537651I-142J-141D01*
G01X54757D01*
G02X54615Y1537710I0J200D01*
G01X54533Y1537792D01*
G02X54474Y1537934I141J142D01*
G01Y1538368D01*
G02X54533Y1538510I200J0D01*
G01X54544Y1538521D01*
X54617Y1538551D01*
X57709D01*
G03X57851Y1538610I0J200D01*
G01X58215Y1538974D01*
G03X58274Y1539116I-141J142D01*
G01Y1539668D01*
G02X58333Y1539810I200J0D01*
G01X58344Y1539821D01*
X58417Y1539851D01*
X65083D01*
G02X65225Y1539792I0J-200D01*
G01X65244Y1539773D01*
X65274Y1539700D01*
Y1531034D01*
G03X65333Y1530892I200J0D01*
G01X65676Y1530549D01*
G03X65702Y1530547I28J198D01*
G01X76039D01*
G03X76181Y1530606I0J200D01*
G01X76561Y1530986D01*
G02X76703Y1531045I142J-141D01*
G01X81722D01*
G03X81864Y1531104I0J200D01*
G01X82297Y1531537D01*
G02X82439Y1531596I142J-141D01*
G01X87828D01*
G02X87970Y1531537I0J-200D01*
G01X88452Y1531055D01*
G02X88511Y1530913I-141J-142D01*
G01Y1528279D01*
G03X88570Y1528137I200J0D01*
G01X88851Y1527856D01*
G03X88993Y1527797I142J141D01*
G01X91012D01*
X91018Y1527791D01*
X97135D01*
G03X97277Y1527850I0J200D01*
G01X97359Y1527932D01*
G03X97418Y1528074I-141J142D01*
G01Y1528650D01*
X97417Y1528651D01*
Y1531192D01*
G03X97358Y1531334I-200J0D01*
G01X96856Y1531836D01*
G03X96714Y1531895I-142J-141D01*
G37*
G36*
G01X32367Y533064D02*
X32452D01*
G02X32594Y533005I0J-200D01*
G01X34856Y530743D01*
X34886Y530678D01*
X34889Y530642D01*
G03X35782Y529818I888J66D01*
G01X36962D01*
G03X37858Y530708I6J890D01*
G01Y531562D01*
Y531644D01*
X37740Y531762D01*
X37739D01*
X37622Y531878D01*
Y532694D01*
G02X37822Y532894I200J0D01*
G01X39320D01*
G02X39473Y532822I-1J-200D01*
G03X40109Y532317I1537J1283D01*
G02X40218Y532160I-90J-179D01*
G01X40232Y532036D01*
G02X40164Y531864I-199J-21D01*
G03X40103Y531807I796J-913D01*
G01X39110Y530814D01*
G03X38756Y529957I857J-856D01*
G01Y527660D01*
G02X38721Y527548I-200J1D01*
G03X38493Y526996I1246J-838D01*
G01X38487Y526967D01*
X38459Y526914D01*
X37832Y526287D01*
G02X37690Y526228I-142J141D01*
G01X36374D01*
G02X36174Y526428I0J200D01*
G01Y526757D01*
G03X35819Y527614I-1212J0D01*
G01X34319Y529114D01*
G02X34260Y529255I141J142D01*
G01Y529457D01*
G03X33342Y530347I-891J0D01*
G01X33339Y530346D01*
X32200D01*
X32198Y530347D01*
G03X31579Y530115I-19J-890D01*
G02X31444Y530062I-136J147D01*
G01X29988D01*
G02X29788Y530262I1J200D01*
G01Y531190D01*
G02X29862Y531345I200J0D01*
G01X30100Y531541D01*
G02X30266Y531582I126J-155D01*
G01X30267D01*
G03X30559Y531553I294J1473D01*
G01X30562D01*
G03X32036Y532768I0J1502D01*
G01X32042Y532797D01*
X32070Y532850D01*
X32225Y533005D01*
G02X32367Y533064I142J-141D01*
G37*
G36*
G01X36508Y664480D02*
G03I-656J0D01*
G37*
G36*
G01Y673010D02*
G03I-656J0D01*
G37*
G36*
G01Y686410D02*
G03I-656J0D01*
G37*
G36*
G01Y683910D02*
G03I-656J0D01*
G37*
G36*
G01Y675510D02*
G03I-656J0D01*
G37*
G36*
G01Y697322D02*
G03I-656J0D01*
G37*
G36*
G01Y694822D02*
G03I-656J0D01*
G37*
G36*
G01Y705728D02*
G03I-656J0D01*
G37*
G36*
G01X36549Y1498567D02*
Y1496157D01*
X35855Y1495463D01*
X33030D01*
X23792D01*
X22846Y1494517D01*
Y1471627D01*
X23993Y1470480D01*
X29590D01*
X32905D01*
X109517D01*
X111241Y1472204D01*
X118199D01*
X119968Y1473973D01*
Y1501410D01*
X118489Y1502889D01*
X56732D01*
X54143Y1500300D01*
X37506D01*
X36549Y1499343D01*
Y1498567D01*
G37*
G36*
G01X39033Y1623905D02*
Y1602848D01*
Y1598243D01*
X38445Y1597655D01*
X37458D01*
X37161Y1597952D01*
Y1601329D01*
X36233Y1602257D01*
X33297D01*
X32797Y1602757D01*
X32682Y1602872D01*
X32667Y1602888D01*
Y1622739D01*
X33833Y1623905D01*
X34333Y1624405D01*
X38533D01*
X39033Y1623905D01*
G37*
G36*
G01X33667Y1626405D02*
Y1629905D01*
X34667Y1630905D01*
X38667D01*
X39167Y1630405D01*
Y1625905D01*
X38667Y1625405D01*
X34667D01*
X33667Y1626405D01*
G37*
G36*
G01X48338Y412613D02*
G03I-720J0D01*
G37*
G36*
G01X50858Y425810D02*
G03I-720J0D01*
G37*
G36*
G01X45902D02*
G03I-720J0D01*
G37*
G36*
G01X48339Y421655D02*
G03I-720J0D01*
G37*
G36*
G01X45742Y449106D02*
G03I-720J0D01*
G37*
G36*
G01X50722D02*
G03I-720J0D01*
G37*
G36*
G01X224171Y761123D02*
X230318D01*
G02X230518Y760923I0J-200D01*
G01Y759154D01*
G03X231019Y758653I501J0D01*
G01X236919D01*
G03X237420Y759154I0J501D01*
G01Y760262D01*
G02X237544Y760447I200J0D01*
G01X237601Y760470D01*
X237718Y760447D01*
X239291Y758874D01*
G02X239350Y758732I-141J-142D01*
G01Y756396D01*
G02X239291Y756254I-200J0D01*
G01X238938Y755901D01*
G02X238797Y755842I-142J141D01*
G01X231195D01*
G02X231035Y755923I1J200D01*
G01X230815Y756218D01*
X230798Y756309D01*
X230812Y756356D01*
G03X230871Y756765I-1393J410D01*
G01Y756766D01*
G03X227967I-1452J0D01*
G01Y756765D01*
G03X228026Y756356I1452J1D01*
G01X228040Y756309D01*
X228023Y756218D01*
X227803Y755923D01*
G02X227643Y755842I-161J119D01*
G01X224153D01*
G02X223993Y755923I1J200D01*
G01X223773Y756218D01*
X223756Y756309D01*
X223770Y756356D01*
G03X223829Y756765I-1393J410D01*
G01Y756766D01*
G03X220925I-1452J0D01*
G03X221680Y755492I1452J0D01*
G02X221781Y755351I-96J-175D01*
G01X221819Y755126D01*
G03X221803Y755110I1761J-1777D01*
G01X208664Y741971D01*
G03X208155Y741236I1769J-1769D01*
G01X208115Y741178D01*
X207464Y740527D01*
G03X207405Y740385I141J-142D01*
G01Y739678D01*
G02X207344Y739534I-200J0D01*
G01X207109Y739306D01*
X207034Y739277D01*
X206993Y739278D01*
G03X206933Y739279I-63J-2001D01*
G03Y735275I0J-2002D01*
G03X206993Y735276I-3J2002D01*
G01X207034Y735277D01*
X207109Y735248D01*
X207344Y735020D01*
G02X207405Y734876I-139J-144D01*
G01Y734284D01*
G02X207315Y734117I-200J0D01*
G01X206994Y733906D01*
X206894Y733897D01*
X206847Y733917D01*
G03X206254Y734039I-593J-1380D01*
G03Y731035I0J-1502D01*
G03X206847Y731157I0J1502D01*
G01X206894Y731177D01*
X206994Y731168D01*
X207315Y730957D01*
G02X207405Y730790I-110J-167D01*
G01Y730455D01*
X198800Y721850D01*
Y706470D01*
X188730Y696400D01*
X70450D01*
X42223Y724627D01*
Y727708D01*
G02X42164Y727850I141J142D01*
G01Y755170D01*
X42974Y755980D01*
X48150D01*
X48650Y755480D01*
Y751430D01*
X48910Y751170D01*
X52640D01*
X52774Y751304D01*
Y759937D01*
X53960Y761123D01*
X72079D01*
G02X72236Y761046I-1J-200D01*
G01X72459Y760759D01*
X72477Y760670D01*
X72466Y760624D01*
G03X72421Y760266I1407J-359D01*
G03X75325I1452J0D01*
G03X75280Y760624I-1452J-1D01*
G01X75269Y760670D01*
X75287Y760759D01*
X75510Y761046D01*
G02X75667Y761123I158J-123D01*
G01X81814D01*
G02X82014Y760923I0J-200D01*
G01Y759154D01*
G03X82515Y758653I501J0D01*
G01X88415D01*
G03X88916Y759154I0J501D01*
G01Y760923D01*
G02X89116Y761123I200J0D01*
G01X101780D01*
G02X101937Y761046I-1J-200D01*
G01X102160Y760759D01*
X102178Y760670D01*
X102167Y760624D01*
G03X102122Y760266I1407J-359D01*
G03X105026I1452J0D01*
G03X104981Y760624I-1452J-1D01*
G01X104970Y760670D01*
X104988Y760759D01*
X105211Y761046D01*
G02X105368Y761123I158J-123D01*
G01X111514D01*
G02X111714Y760923I0J-200D01*
G01Y759154D01*
G03X112216Y758653I502J1D01*
G01X118116D01*
G03X118618Y759154I0J502D01*
G01Y760923D01*
G02X118818Y761123I200J0D01*
G01X131330D01*
G02X131487Y761046I-1J-200D01*
G01X131710Y760759D01*
X131728Y760670D01*
X131717Y760624D01*
G03X131672Y760266I1407J-359D01*
G03X134576I1452J0D01*
G03X134531Y760624I-1452J-1D01*
G01X134520Y760670D01*
X134538Y760759D01*
X134761Y761046D01*
G02X134918Y761123I158J-123D01*
G01X141214D01*
G02X141414Y760923I0J-200D01*
G01Y759154D01*
G03X141916Y758653I502J1D01*
G01X147816D01*
G03X148318Y759154I0J502D01*
G01Y760923D01*
G02X148518Y761123I200J0D01*
G01X161181D01*
G02X161338Y761046I-1J-200D01*
G01X161561Y760759D01*
X161579Y760670D01*
X161568Y760624D01*
G03X161523Y760266I1407J-359D01*
G03X164427I1452J0D01*
G03X164382Y760624I-1452J-1D01*
G01X164371Y760670D01*
X164389Y760759D01*
X164612Y761046D01*
G02X164769Y761123I158J-123D01*
G01X170916D01*
G02X171116Y760923I0J-200D01*
G01Y759154D01*
G03X171617Y758653I501J0D01*
G01X177517D01*
G03X178018Y759154I0J501D01*
G01Y760923D01*
G02X178218Y761123I200J0D01*
G01X190882D01*
G02X191039Y761046I-1J-200D01*
G01X191262Y760759D01*
X191280Y760670D01*
X191269Y760624D01*
G03X191224Y760266I1407J-359D01*
G03X194128I1452J0D01*
G03X194083Y760624I-1452J-1D01*
G01X194072Y760670D01*
X194090Y760759D01*
X194313Y761046D01*
G02X194470Y761123I158J-123D01*
G01X200616D01*
G02X200816Y760923I0J-200D01*
G01Y759154D01*
G03X201318Y758653I502J1D01*
G01X207218D01*
G03X207720Y759154I0J502D01*
G01Y760923D01*
G02X207920Y761123I200J0D01*
G01X220583D01*
G02X220740Y761046I-1J-200D01*
G01X220963Y760759D01*
X220981Y760670D01*
X220970Y760624D01*
G03X220925Y760266I1407J-359D01*
G03X223829I1452J0D01*
G03X223784Y760624I-1452J-1D01*
G01X223773Y760670D01*
X223791Y760759D01*
X224014Y761046D01*
G02X224171Y761123I158J-123D01*
G37*
G36*
G01X56989Y794303D02*
X61217D01*
X62210Y793310D01*
Y775299D01*
X61620Y774709D01*
X52974D01*
G02X52774Y774909I0J200D01*
G01Y778055D01*
X52790Y778071D01*
Y779060D01*
X52600Y779250D01*
X48980D01*
X48790Y779060D01*
Y775079D01*
X48420Y774709D01*
X44065D01*
G02X43923Y774768I0J200D01*
G01X43527Y775164D01*
G02X43468Y775306I141J142D01*
G01Y792752D01*
G02X43527Y792894I200J0D01*
G01X44877Y794244D01*
G02X45019Y794303I142J-141D01*
G01X54589D01*
G02X54698Y794271I0J-200D01*
G03X55789Y793947I1092J1678D01*
G03X56880Y794271I-1J2002D01*
G02X56989Y794303I109J-168D01*
G37*
G36*
G01X49098Y1608661D02*
Y1608664D01*
X49109Y1608675D01*
X51528D01*
X51557Y1608646D01*
Y1608548D01*
Y1607490D01*
X51548Y1607481D01*
Y1603496D01*
Y1597911D01*
X51133Y1597496D01*
X44633D01*
X44433Y1597696D01*
Y1599665D01*
X46664Y1601896D01*
X47133D01*
X48633Y1603396D01*
Y1608196D01*
X49098Y1608661D01*
G37*
G36*
G01X318935Y10876D02*
X319061Y10935D01*
X319507Y10828D01*
G02X319661Y10634I-46J-195D01*
G01Y2200D01*
G02X319461Y2000I-200J0D01*
G01X53783D01*
G02X53583Y2200I0J200D01*
G01Y10634D01*
G02X53737Y10828I200J-1D01*
G01X54183Y10935D01*
X54309Y10876D01*
X54340Y10814D01*
G03X55496Y9466I3306J1666D01*
G01X55580Y9304D01*
Y3996D01*
X317664D01*
Y9304D01*
X317748Y9466D01*
G03X318904Y10814I-2150J3014D01*
G01X318935Y10876D01*
G37*
G36*
G01X63553Y409597D02*
G03I-720J0D01*
G37*
G36*
G01X63528Y418675D02*
G03I-720J0D01*
G37*
G36*
G01X66100Y427810D02*
G03I-720J0D01*
G37*
G36*
G01X61113D02*
G03I-720J0D01*
G37*
G36*
G01X57198Y589521D02*
G03I-656J0D01*
G37*
G36*
G01X65579Y795316D02*
G03I-656J0D01*
G37*
G36*
G01Y832127D02*
G03I-656J0D01*
G37*
G36*
G01Y868938D02*
G03I-656J0D01*
G37*
G36*
G01Y905750D02*
G03I-656J0D01*
G37*
G36*
G01Y942561D02*
G03I-656J0D01*
G37*
G36*
G01Y1089805D02*
G03I-656J0D01*
G37*
G36*
G01Y1126616D02*
G03I-656J0D01*
G37*
G36*
G01Y1163427D02*
G03I-656J0D01*
G37*
G36*
G01Y1200238D02*
G03I-656J0D01*
G37*
G36*
G01Y1237049D02*
G03I-656J0D01*
G37*
G36*
G01X60404Y1660972D02*
Y1670601D01*
X60714Y1670911D01*
X69991D01*
X70529Y1670373D01*
Y1661323D01*
X70064Y1660858D01*
X67329D01*
X66896Y1660425D01*
Y1657485D01*
X66699Y1657288D01*
X66172D01*
X65987Y1657473D01*
Y1660591D01*
X65782Y1660796D01*
X60580D01*
X60404Y1660972D01*
G37*
G36*
G01X78446Y520108D02*
G03I-656J0D01*
G37*
G36*
G01X78389Y526764D02*
G03I-656J0D01*
G37*
G36*
G01X78446Y537808D02*
G03I-656J0D01*
G37*
G36*
G01X78389Y544464D02*
G03I-656J0D01*
G37*
G36*
G01X81721Y791970D02*
G03I-656J0D01*
G37*
G36*
G01Y828781D02*
G03I-656J0D01*
G37*
G36*
G01Y865592D02*
G03I-656J0D01*
G37*
G36*
G01Y902403D02*
G03I-656J0D01*
G37*
G36*
G01Y939214D02*
G03I-656J0D01*
G37*
G36*
G01Y1086458D02*
G03I-656J0D01*
G37*
G36*
G01Y1123269D02*
G03I-656J0D01*
G37*
G36*
G01Y1233702D02*
G03I-656J0D01*
G37*
G36*
G01X74356Y1335688D02*
X122474D01*
X122861Y1335301D01*
Y1329701D01*
X122161Y1329001D01*
X103473D01*
X101939Y1327467D01*
Y1321846D01*
X101129Y1321036D01*
X73019D01*
X72461Y1321594D01*
Y1333793D01*
X74356Y1335688D01*
G37*
G36*
G01X238051Y1374061D02*
X243142D01*
X243284Y1374002D01*
X243508Y1373778D01*
Y1366027D01*
X244451Y1365084D01*
X244835Y1364700D01*
X256100D01*
X256484Y1365084D01*
X266630D01*
X270573Y1369027D01*
X281353D01*
X287983Y1362397D01*
Y1352497D01*
X284733Y1349247D01*
Y1348287D01*
X278793Y1342347D01*
X263173D01*
X262033Y1341207D01*
Y1337695D01*
X261573Y1337235D01*
X234757D01*
X233397Y1335875D01*
Y1328057D01*
X234367Y1327087D01*
X252893D01*
X253028Y1326952D01*
Y1320842D01*
X252953Y1320767D01*
X202007D01*
X201387Y1321387D01*
Y1326577D01*
X201897Y1327087D01*
X221027D01*
X221797Y1327857D01*
Y1335927D01*
X220489Y1337235D01*
X73929D01*
X72945D01*
X72460Y1337720D01*
Y1381430D01*
X74860Y1383830D01*
X87390D01*
X87993Y1383227D01*
Y1378087D01*
X91790Y1374290D01*
Y1364740D01*
X92698Y1363832D01*
X94145D01*
X100522D01*
X102410Y1361944D01*
X108951D01*
X109007Y1362000D01*
Y1364701D01*
X107544Y1366164D01*
X105292D01*
X104992Y1366464D01*
X102002D01*
X101952Y1366514D01*
Y1367314D01*
X102002Y1367364D01*
X104992D01*
X105706Y1368078D01*
Y1371065D01*
X104992Y1371779D01*
X102002D01*
X102001Y1371780D01*
X101783D01*
X101673Y1371890D01*
Y1372524D01*
X101803Y1372654D01*
X101977D01*
X102002Y1372679D01*
X104991D01*
X105656Y1373344D01*
Y1373864D01*
X105756Y1373964D01*
X112556D01*
X112656Y1373864D01*
Y1366064D01*
X114020Y1364700D01*
X124949D01*
X125384Y1365135D01*
X128267D01*
X128825Y1364577D01*
X132570D01*
X135230Y1361917D01*
X141540D01*
Y1364776D01*
X140216Y1366100D01*
X138000D01*
X137629Y1366471D01*
X134396D01*
X134233Y1366634D01*
Y1367234D01*
X134358Y1367359D01*
X137759D01*
X138200Y1367800D01*
Y1371600D01*
X138009Y1371791D01*
X134394D01*
X134273Y1371912D01*
Y1372524D01*
X134403Y1372654D01*
X137954D01*
X138210Y1372910D01*
Y1373923D01*
X138280Y1373993D01*
G03X138382Y1373972I555J2439D01*
G03X138837Y1373928I467J2458D01*
G01X138862D01*
G03X139621Y1374051I-16J2502D01*
G01X139651Y1374061D01*
X144742D01*
X144884Y1374002D01*
X145108Y1373778D01*
Y1368228D01*
X145103Y1368223D01*
Y1366359D01*
X146625Y1364837D01*
X160617D01*
X161617Y1363837D01*
X166117D01*
X168047Y1361907D01*
X174210D01*
Y1364740D01*
X172850Y1366100D01*
X170403D01*
X170273Y1366230D01*
Y1366244D01*
X170051Y1366466D01*
X167101D01*
X166933Y1366634D01*
Y1367234D01*
X167050Y1367351D01*
X170313D01*
X170641D01*
X170910Y1367620D01*
Y1371550D01*
X170675Y1371785D01*
X170282D01*
X167158D01*
X166973Y1371970D01*
Y1372524D01*
X167103Y1372654D01*
X170377D01*
X170554D01*
X170900Y1373000D01*
Y1373891D01*
X170998Y1373989D01*
G03X171082Y1373972I538J2443D01*
G03X171537Y1373928I467J2458D01*
G01X171562D01*
G03X172321Y1374051I-16J2502D01*
G01X172351Y1374061D01*
X177442D01*
X177584Y1374002D01*
X177701Y1373885D01*
Y1365887D01*
X178631Y1364957D01*
X178888Y1364700D01*
X188700D01*
X188957Y1364957D01*
X193185D01*
X193555Y1364587D01*
X197961D01*
X200641Y1361907D01*
X207170D01*
Y1364730D01*
X205800Y1366100D01*
X203303D01*
X203173Y1366230D01*
Y1366244D01*
X202947Y1366470D01*
X199997D01*
X199833Y1366634D01*
Y1367234D01*
X199948Y1367349D01*
X203212D01*
X203489D01*
X203820Y1367680D01*
Y1371570D01*
X203596Y1371794D01*
X203173D01*
X200066D01*
X199873Y1371987D01*
Y1372524D01*
X200003Y1372654D01*
X203277D01*
X203554D01*
X203800Y1372900D01*
Y1373790D01*
X203982Y1373972D01*
G03X204437Y1373928I467J2458D01*
G01X204462D01*
G03X205221Y1374051I-16J2502D01*
G01X205251Y1374061D01*
X210342D01*
X210484Y1374002D01*
X210708Y1373778D01*
Y1366093D01*
X211874Y1364927D01*
X212101Y1364700D01*
X221373D01*
X221600Y1364927D01*
X227213D01*
X227611Y1364529D01*
X230635D01*
X233257Y1361907D01*
X240000D01*
Y1364800D01*
X238700Y1366100D01*
X236024D01*
X235644Y1366480D01*
X232892D01*
X232777Y1366595D01*
Y1367267D01*
X232863Y1367353D01*
X236153D01*
X236600Y1367800D01*
Y1371300D01*
Y1371650D01*
X236466Y1371784D01*
X236414D01*
X236363D01*
X236316D01*
X232823D01*
X232673Y1371934D01*
Y1372524D01*
X232803Y1372654D01*
X236077D01*
X236454D01*
X236600Y1372800D01*
Y1373891D01*
X236698Y1373989D01*
G03X236782Y1373972I538J2443D01*
G03X237237Y1373928I467J2458D01*
G01X237262D01*
G03X238021Y1374051I-16J2502D01*
G01X238051Y1374061D01*
G37*
G36*
G01X116700Y1531898D02*
X102497D01*
X102477Y1531918D01*
Y1540000D01*
X102502Y1540025D01*
X108040D01*
X108614Y1540599D01*
Y1543891D01*
X110374Y1545651D01*
Y1551751D01*
X109579Y1552546D01*
X107079D01*
X106674Y1552951D01*
Y1556251D01*
X105374Y1557551D01*
X100974D01*
X100450Y1557027D01*
X100432D01*
X99870Y1556465D01*
X99794D01*
X83752D01*
X82375Y1555088D01*
Y1555030D01*
X79996Y1552651D01*
Y1547869D01*
X80745Y1547120D01*
Y1532588D01*
X80231Y1532073D01*
X76061D01*
X75898Y1531910D01*
X66774D01*
X66736Y1531948D01*
Y1540027D01*
X66762Y1540053D01*
X72325D01*
X72871Y1540599D01*
Y1544396D01*
X74178Y1545703D01*
X74348Y1545873D01*
Y1552593D01*
X72622Y1554319D01*
X72621D01*
X71423Y1555517D01*
Y1579036D01*
X76673Y1584286D01*
X103516D01*
X119672D01*
X121516D01*
X122205Y1583597D01*
Y1535744D01*
X118359Y1531898D01*
X117770D01*
X116700D01*
G37*
G36*
G01X73847Y1738118D02*
X373320D01*
G02X373505Y1737994I0J-200D01*
G01X373668Y1737594D01*
X373644Y1737476D01*
X373600Y1737433D01*
G03X372398Y1736186I22069J-22475D01*
G02X372250Y1736120I-148J134D01*
G01X345757D01*
X345755D01*
X345710D01*
X345684Y1736129D01*
X345683D01*
G03X345096Y1736222I-605J-1917D01*
G03X345081I-7J-2010D01*
G01X345077D01*
G03X345062I-7J-2010D01*
G03X344475Y1736129I18J-2010D01*
G01X344468Y1736127D01*
X344448Y1736120D01*
X330009D01*
X330007D01*
X329962D01*
X329936Y1736129D01*
X329935D01*
G03X329348Y1736222I-605J-1917D01*
G03X329333I-7J-2010D01*
G01X329329D01*
G03X329314I-7J-2010D01*
G03X328727Y1736129I18J-2010D01*
G01X328720Y1736127D01*
X328700Y1736120D01*
X314261D01*
X314259D01*
X314214D01*
X314188Y1736129D01*
X314187D01*
G03X313600Y1736222I-605J-1917D01*
G03X313585I-7J-2010D01*
G01X313581D01*
G03X313566I-7J-2010D01*
G03X312979Y1736129I18J-2010D01*
G01X312972Y1736127D01*
X312952Y1736120D01*
X299679D01*
X299627Y1736135D01*
X299603Y1736149D01*
G03X299344Y1736222I-261J-428D01*
G01X296326D01*
G03X296067Y1736149I2J-501D01*
G01X296043Y1736135D01*
X295991Y1736120D01*
X278827D01*
X278825D01*
X278780D01*
X278754Y1736129D01*
X278753D01*
G03X278166Y1736222I-605J-1917D01*
G03X278151I-7J-2010D01*
G01X278147D01*
G03X278132I-7J-2010D01*
G03X277545Y1736129I18J-2010D01*
G01X277538Y1736127D01*
X277518Y1736120D01*
X263079D01*
X263077D01*
X263032D01*
X263006Y1736129D01*
X263005D01*
G03X262418Y1736222I-605J-1917D01*
G03X262403I-7J-2010D01*
G01X262399D01*
G03X262384I-7J-2010D01*
G03X261797Y1736129I18J-2010D01*
G01X261790Y1736127D01*
X261770Y1736120D01*
X247331D01*
X247329D01*
X247284D01*
X247258Y1736129D01*
X247257D01*
G03X246670Y1736222I-605J-1917D01*
G03X246655I-7J-2010D01*
G01X246651D01*
G03X246636I-8J-2010D01*
G03X246049Y1736129I18J-2010D01*
G01X246042Y1736127D01*
X246022Y1736120D01*
X232749D01*
X232697Y1736135D01*
X232673Y1736149D01*
G03X232414Y1736222I-261J-428D01*
G01X229396D01*
G03X229137Y1736149I2J-501D01*
G01X229113Y1736135D01*
X229061Y1736120D01*
X74946D01*
X73600Y1737466D01*
Y1737871D01*
X73847Y1738118D01*
G37*
G36*
G01X95280Y795316D02*
G03I-656J0D01*
G37*
G36*
G01Y832127D02*
G03I-656J0D01*
G37*
G36*
G01Y868938D02*
G03I-656J0D01*
G37*
G36*
G01Y905750D02*
G03I-656J0D01*
G37*
G36*
G01Y942561D02*
G03I-656J0D01*
G37*
G36*
G01Y1089805D02*
G03I-656J0D01*
G37*
G36*
G01Y1126616D02*
G03I-656J0D01*
G37*
G36*
G01Y1163427D02*
G03I-656J0D01*
G37*
G36*
G01Y1200238D02*
G03I-656J0D01*
G37*
G36*
G01Y1237049D02*
G03I-656J0D01*
G37*
G36*
G01X99196Y1319036D02*
X223126D01*
X224561Y1317601D01*
Y1289903D01*
X221423Y1286765D01*
X90704D01*
X89053Y1288416D01*
Y1308227D01*
X89913Y1309087D01*
X96641D01*
X98561Y1311007D01*
Y1318401D01*
X99196Y1319036D01*
G37*
G36*
G01X98681Y1365357D02*
X94073D01*
X92790Y1366640D01*
Y1374990D01*
X88993Y1378787D01*
Y1383395D01*
G02X89051Y1383535I197J0D01*
G01X89355Y1383839D01*
G02X89495Y1383897I140J-139D01*
G01X95531D01*
G02X95671Y1383839I0J-197D01*
G01X95925Y1383585D01*
G02X95983Y1383445I-139J-140D01*
G01Y1370799D01*
G03X96041Y1370659I197J0D01*
G01X96645Y1370055D01*
G03X96785Y1369997I140J139D01*
G01X96986D01*
X97039Y1369981D01*
X97064Y1369965D01*
G03X98101Y1369657I1038J1594D01*
G03X98768Y1369778I-1J1902D01*
G01X98823Y1369799D01*
X98935Y1369775D01*
X99165Y1369545D01*
G02X99223Y1369405I-139J-140D01*
G01Y1365899D01*
G02X99165Y1365759I-197J0D01*
G01X98821Y1365415D01*
G02X98681Y1365357I-140J139D01*
G37*
G36*
G01X101896Y1589589D02*
X88501D01*
X87992Y1590098D01*
Y1601239D01*
X88757Y1602004D01*
X104614D01*
X105584Y1601034D01*
Y1590277D01*
X104896Y1589589D01*
X101896D01*
G37*
G36*
G01X111422Y791970D02*
G03I-656J0D01*
G37*
G36*
G01Y828781D02*
G03I-656J0D01*
G37*
G36*
G01Y865592D02*
G03I-656J0D01*
G37*
G36*
G01Y902403D02*
G03I-656J0D01*
G37*
G36*
G01Y939214D02*
G03I-656J0D01*
G37*
G36*
G01Y1086458D02*
G03I-656J0D01*
G37*
G36*
G01Y1123269D02*
G03I-656J0D01*
G37*
G36*
G01Y1233702D02*
G03I-656J0D01*
G37*
G36*
G01X125848Y1335688D02*
X155074D01*
X155461Y1335301D01*
Y1329501D01*
X154761Y1328801D01*
X135661D01*
X134211Y1327351D01*
Y1321851D01*
X133396Y1321036D01*
X103726D01*
X103161Y1321601D01*
Y1327001D01*
X103961Y1327801D01*
X122961D01*
X124161Y1329001D01*
Y1334001D01*
X125848Y1335688D01*
G37*
G36*
G01X128700Y1442295D02*
X111300D01*
X111202Y1442198D01*
Y1425536D01*
Y1424898D01*
X111400Y1424700D01*
X128700D01*
X128800Y1424800D01*
Y1425600D01*
Y1442195D01*
X128700Y1442295D01*
G37*
G36*
G01X124980Y795316D02*
G03I-656J0D01*
G37*
G36*
G01Y832127D02*
G03I-656J0D01*
G37*
G36*
G01Y868938D02*
G03I-656J0D01*
G37*
G36*
G01Y905750D02*
G03I-656J0D01*
G37*
G36*
G01Y942561D02*
G03I-656J0D01*
G37*
G36*
G01Y1089805D02*
G03I-656J0D01*
G37*
G36*
G01Y1126616D02*
G03I-656J0D01*
G37*
G36*
G01Y1163427D02*
G03I-656J0D01*
G37*
G36*
G01Y1200238D02*
G03I-656J0D01*
G37*
G36*
G01Y1237049D02*
G03I-656J0D01*
G37*
G36*
G01X177778Y1412394D02*
X179419Y1410753D01*
G03X179561Y1410694I142J141D01*
G01X220312D01*
X220342Y1410684D01*
G03X220803Y1410612I460J1431D01*
G03X221264Y1410684I1J1503D01*
G01X221294Y1410694D01*
X226661Y1405327D01*
Y1366483D01*
G02X226602Y1366341I-200J0D01*
G01X226437Y1366176D01*
G02X226295Y1366117I-142J141D01*
G01X212466D01*
G02X212324Y1366176I0J200D01*
G01X212311Y1366189D01*
Y1373885D01*
G02X212370Y1374027I200J0D01*
G01X212576Y1374233D01*
G02X212718Y1374292I142J-141D01*
G01X217870D01*
G03X218012Y1374350I1J200D01*
G01X218408Y1374746D01*
G03X218467Y1374888I-141J142D01*
G01Y1377791D01*
G02X218526Y1377933I200J0D01*
G01X219916Y1379323D01*
G03X219975Y1379465I-141J142D01*
G01Y1386484D01*
G03X219916Y1386626I-200J0D01*
G01X219413Y1387129D01*
G03X219271Y1387188I-142J-141D01*
G01X209765D01*
G02X209623Y1387247I0J200D01*
G01X208519Y1388351D01*
G03X208377Y1388410I-142J-141D01*
G01X196689D01*
G03X196547Y1388351I0J-200D01*
G01X193820Y1385624D01*
G03X193761Y1385482I141J-142D01*
G01Y1366983D01*
G02X193702Y1366841I-200J0D01*
G01X192940Y1366079D01*
G02X192798Y1366020I-142J141D01*
G01X179770D01*
G02X179628Y1366079I0J200D01*
G01X179470Y1366237D01*
G02X179411Y1366379I141J142D01*
G01Y1373885D01*
G02X179470Y1374027I200J0D01*
G01X179676Y1374233D01*
G02X179818Y1374292I142J-141D01*
G01X184970D01*
G03X185112Y1374350I1J200D01*
G01X185578Y1374815D01*
G03X185637Y1374957I-141J142D01*
G01Y1377861D01*
G02X185696Y1378003I200J0D01*
G01X187016Y1379323D01*
G03X187075Y1379465I-141J142D01*
G01Y1385087D01*
X187061Y1385101D01*
Y1385984D01*
G03X187002Y1386126I-200J0D01*
G01X184657Y1388471D01*
G03X184515Y1388530I-142J-141D01*
G01X164083D01*
G03X163941Y1388471I0J-200D01*
G01X161020Y1385550D01*
G03X160961Y1385408I141J-142D01*
G01Y1366683D01*
G02X160902Y1366541I-200J0D01*
G01X160320Y1365959D01*
G02X160178Y1365900I-142J141D01*
G01X147143D01*
G02X147001Y1365959I0J200D01*
G01X146770Y1366190D01*
G02X146711Y1366332I141J142D01*
G01Y1373885D01*
G02X146770Y1374027I200J0D01*
G01X146976Y1374233D01*
G02X147118Y1374292I142J-141D01*
G01X152270D01*
G03X152412Y1374350I1J200D01*
G01X152822Y1374760D01*
G03X152881Y1374902I-141J142D01*
G01Y1377805D01*
G02X152940Y1377947I200J0D01*
G01X154316Y1379323D01*
G03X154375Y1379465I-141J142D01*
G01Y1384887D01*
X154361Y1384901D01*
Y1386484D01*
G03X154302Y1386626I-200J0D01*
G01X152647Y1388281D01*
G03X152505Y1388340I-142J-141D01*
G01X131283D01*
G03X131141Y1388281I0J-200D01*
G01X128420Y1385560D01*
G03X128361Y1385418I141J-142D01*
G01Y1366483D01*
G02X128302Y1366341I-200J0D01*
G01X128155Y1366194D01*
G02X128013Y1366135I-142J141D01*
G01X124982D01*
G03X124840Y1366076I0J-200D01*
G01X124806Y1366042D01*
G02X124664Y1365983I-142J141D01*
G01X114286D01*
G02X114144Y1366042I0J200D01*
G01X114133Y1366053D01*
X114103Y1366126D01*
Y1374000D01*
G02X114162Y1374142I200J0D01*
G01X114173Y1374153D01*
X114246Y1374183D01*
X119561D01*
G03X119703Y1374241I1J200D01*
G01X120239Y1374777D01*
G03X120298Y1374919I-141J142D01*
G01Y1377822D01*
G02X120357Y1377964I200J0D01*
G01X121716Y1379323D01*
G03X121775Y1379465I-141J142D01*
G01Y1383887D01*
X121761Y1383901D01*
Y1391917D01*
G02X121820Y1392059I200J0D01*
G01X123921Y1394160D01*
G02X124063Y1394219I142J-141D01*
G01X140029D01*
G03X140171Y1394278I0J200D01*
G01X155167Y1409274D01*
Y1409432D01*
X164584Y1418849D01*
Y1418931D01*
X171158D01*
X171188Y1418900D01*
X171272D01*
X177778Y1412394D01*
G37*
G36*
G01X147223Y426170D02*
X152787D01*
G02X152929Y426111I0J-200D01*
G01X153491Y425549D01*
G02X153550Y425407I-141J-142D01*
G01Y421783D01*
G02X153491Y421641I-200J0D01*
G01X153249Y421399D01*
G02X153107Y421340I-142J141D01*
G01X139573D01*
X139030Y421883D01*
X138900Y422013D01*
Y424670D01*
X139310Y425080D01*
X145620D01*
X146710Y426170D01*
X147223D01*
G37*
G36*
G01X151149Y448191D02*
X151301Y448039D01*
G02X151360Y447897I-141J-142D01*
G01Y441083D01*
G03X151419Y440941I200J0D01*
G01X152611Y439749D01*
G02X152670Y439607I-141J-142D01*
G01Y437523D01*
G02X152611Y437381I-200J0D01*
G01X151459Y436229D01*
G02X151317Y436170I-142J141D01*
G01X137423D01*
G02X137281Y436229I0J200D01*
G01X136719Y436791D01*
G02X136660Y436933I141J142D01*
G01Y447357D01*
G02X136719Y447499I200J0D01*
G01X137411Y448191D01*
G02X137553Y448250I142J-141D01*
G01X151007D01*
G02X151149Y448191I0J-200D01*
G37*
G36*
G01X142292Y486570D02*
X155937D01*
G02X156079Y486511I0J-200D01*
G01X157681Y484909D01*
G02X157740Y484767I-141J-142D01*
G01Y467032D01*
G02X157564Y466834I-199J0D01*
G01X156766D01*
Y464308D01*
G02X156592Y464134I-199J24D01*
G01X155766D01*
Y452108D01*
G02X155592Y451934I-199J24D01*
G01X138948D01*
G02X138774Y452108I24J198D01*
G01Y464134D01*
X137948D01*
G02X137774Y464308I24J198D01*
G01Y466834D01*
X137496D01*
X137380Y466950D01*
Y485317D01*
G02X137439Y485459I200J0D01*
G01X138394Y486414D01*
G02X138535Y486472I141J-142D01*
G01X141642D01*
G03X142264Y486562I-3J2212D01*
G01X142292Y486570D01*
G37*
G36*
G01X140397Y510404D02*
X153633D01*
G02X153774Y510346I0J-200D01*
G01X154261Y509859D01*
G02X154320Y509717I-141J-142D01*
G01Y501353D01*
G02X154261Y501211I-200J0D01*
G01X153889Y500839D01*
G02X153747Y500780I-142J141D01*
G01X140523D01*
G02X140381Y500839I0J200D01*
G01X138639Y502581D01*
G02X138580Y502723I141J142D01*
G01Y508587D01*
G02X138639Y508729I200J0D01*
G01X140256Y510346D01*
G02X140397Y510404I141J-142D01*
G37*
G36*
G01X141122Y791970D02*
G03I-656J0D01*
G37*
G36*
G01Y828781D02*
G03I-656J0D01*
G37*
G36*
G01Y865592D02*
G03I-656J0D01*
G37*
G36*
G01Y902403D02*
G03I-656J0D01*
G37*
G36*
G01Y939214D02*
G03I-656J0D01*
G37*
G36*
G01Y1086458D02*
G03I-656J0D01*
G37*
G36*
G01Y1233702D02*
G03I-656J0D01*
G37*
G36*
G01X158448Y1335688D02*
X187674D01*
X188061Y1335301D01*
Y1329501D01*
X187361Y1328801D01*
X168261D01*
X166811Y1327351D01*
Y1321851D01*
X165996Y1321036D01*
X136326D01*
X135761Y1321601D01*
Y1327001D01*
X136561Y1327801D01*
X155561D01*
X156761Y1329001D01*
Y1334001D01*
X158448Y1335688D01*
G37*
G36*
G01X138191Y1447963D02*
Y1449905D01*
X137894Y1450202D01*
X132133D01*
X131859Y1449928D01*
Y1445288D01*
X130018Y1443447D01*
Y1441823D01*
X130030Y1441811D01*
X132756D01*
X134921Y1443976D01*
Y1446911D01*
X135927Y1447917D01*
X138145D01*
X138191Y1447963D01*
G37*
G36*
G01X137232Y1665816D02*
X135862D01*
X135082Y1665036D01*
Y1662186D01*
X134992Y1662096D01*
X134692D01*
X134612Y1662176D01*
Y1664966D01*
X134092Y1665486D01*
X132442D01*
X132022Y1665906D01*
Y1668466D01*
X131032Y1669456D01*
X128922D01*
X128832Y1669546D01*
Y1669896D01*
X128922Y1669986D01*
X131162D01*
X131952Y1670776D01*
Y1673476D01*
X131242Y1674186D01*
X128932D01*
X128822Y1674296D01*
Y1674646D01*
X128902Y1674726D01*
X131262D01*
X131842Y1675306D01*
Y1678306D01*
X132562Y1679026D01*
X133842D01*
X134552Y1679736D01*
Y1681906D01*
X134702Y1682056D01*
X135032D01*
X135152Y1681936D01*
Y1679816D01*
X135732Y1679236D01*
X137572D01*
X138032Y1678776D01*
Y1675356D01*
X138662Y1674726D01*
X140782D01*
X140912Y1674596D01*
Y1672756D01*
X140762Y1672606D01*
X138472D01*
X138012Y1672146D01*
Y1670636D01*
X138612Y1670036D01*
X140712D01*
X140872Y1669876D01*
Y1669566D01*
X140712Y1669406D01*
X138352D01*
X138022Y1669076D01*
Y1666606D01*
X137232Y1665816D01*
G37*
G36*
G01X153653Y448340D02*
X157837D01*
G02X157979Y448281I0J-200D01*
G01X158271Y447989D01*
G02X158330Y447847I-141J-142D01*
G01Y430063D01*
G02X158271Y429921I-200J0D01*
G01X158029Y429679D01*
G02X157887Y429620I-142J141D01*
G01X153393D01*
G02X153251Y429679I0J200D01*
G01X152819Y430111D01*
G02X152760Y430253I141J142D01*
G01Y433967D01*
G02X152819Y434109I200J0D01*
G01X153611Y434901D01*
G03X153670Y435043I-141J142D01*
G01Y437024D01*
X153672Y437025D01*
Y440105D01*
X153670Y440106D01*
Y440607D01*
G03X153611Y440749I-200J0D01*
G01X153319Y441041D01*
G02X153260Y441183I141J142D01*
G01Y447947D01*
G02X153319Y448089I200J0D01*
G01X153511Y448281D01*
G02X153653Y448340I142J-141D01*
G37*
G36*
G01X142152Y491434D02*
G03I-510J0D01*
G37*
G36*
G01X154681Y795316D02*
G03I-656J0D01*
G37*
G36*
G01Y832127D02*
G03I-656J0D01*
G37*
G36*
G01Y868938D02*
G03I-656J0D01*
G37*
G36*
G01Y905750D02*
G03I-656J0D01*
G37*
G36*
G01Y942561D02*
G03I-656J0D01*
G37*
G36*
G01Y1089805D02*
G03I-656J0D01*
G37*
G36*
G01Y1126616D02*
G03I-656J0D01*
G37*
G36*
G01Y1163427D02*
G03I-656J0D01*
G37*
G36*
G01Y1200238D02*
G03I-656J0D01*
G37*
G36*
G01Y1237049D02*
G03I-656J0D01*
G37*
G36*
G01X157473Y1548344D02*
X159107D01*
G02X159249Y1548285I0J-200D01*
G01X159963Y1547571D01*
G02X160022Y1547429I-141J-142D01*
G01Y1542762D01*
G02X159822Y1542562I-200J0D01*
G01X159000D01*
G03X158531Y1542467I1J-1212D01*
G01X158494Y1542452D01*
X158250D01*
G03X157748Y1541950I0J-502D01*
G01Y1540750D01*
G03X158250Y1540248I502J0D01*
G01X158494D01*
X158531Y1540233D01*
G03X159000Y1540138I470J1117D01*
G01X159822D01*
G02X160022Y1539938I0J-200D01*
G01Y1539462D01*
G02X159822Y1539262I-200J0D01*
G01X159000D01*
G03X158531Y1539167I1J-1212D01*
G01X158494Y1539152D01*
X158250D01*
G03X157748Y1538650I0J-502D01*
G01Y1537450D01*
G03X158250Y1536948I502J0D01*
G01X158494D01*
X158531Y1536933D01*
G03X159000Y1536838I470J1117D01*
G01X159822D01*
G02X160022Y1536638I0J-200D01*
G01Y1531980D01*
G02X159963Y1531839I-200J1D01*
G01X159945Y1531820D01*
G02X159803Y1531762I-141J142D01*
G01X159000D01*
G03X158531Y1531667I1J-1212D01*
G01X158494Y1531652D01*
X158250D01*
G03X157748Y1531150I0J-502D01*
G01Y1529950D01*
G03X157777Y1529783I502J1D01*
G01X157788Y1529751D01*
Y1527170D01*
G02X157717Y1527017I-200J0D01*
G03X156998Y1525480I1283J-1537D01*
G03X157570Y1524079I2002J0D01*
G01X157608Y1524040D01*
X157634Y1523934D01*
X157505Y1523495D01*
X157426Y1523421D01*
X157372Y1523409D01*
G03X155421Y1520968I552J-2441D01*
G03X157923Y1518466I2502J0D01*
G03X160056Y1519661I0J2501D01*
G02X160227Y1519756I170J-105D01*
G01X161024D01*
G02X161101Y1519741I1J-200D01*
G01X163887Y1518587D01*
G03X164351Y1518494I464J1111D01*
G01X165167D01*
X165176Y1518485D01*
Y1518040D01*
G03X165271Y1517571I1212J1D01*
G01X165286Y1517534D01*
Y1517290D01*
G03X165307Y1517149I502J3D01*
G01X165317Y1517113D01*
X165313Y1517044D01*
X165178Y1516741D01*
X165129Y1516691D01*
X165096Y1516675D01*
G03X163990Y1515630I1084J-2255D01*
G01X163964Y1515583D01*
X163874Y1515528D01*
X163420Y1515519D01*
X163327Y1515570D01*
X163299Y1515616D01*
G03X161162Y1516816I-2137J-1303D01*
G03Y1511812I0J-2502D01*
G03X162436Y1512161I-1J2502D01*
G01X162496Y1512196D01*
X162631Y1512179D01*
X164167Y1510643D01*
X164194Y1510592D01*
X164200Y1510562D01*
G03X164252Y1510379I1188J239D01*
G01X164265Y1510345D01*
Y1510309D01*
G02X164065Y1510109I-200J0D01*
G01X153676D01*
G02X153534Y1510168I0J200D01*
G01X151125Y1512577D01*
G02X151066Y1512719I141J142D01*
G01Y1545428D01*
G02X151125Y1545570I200J0D01*
G01X153556Y1548001D01*
G02X153702Y1548059I141J-142D01*
G01X154033Y1548051D01*
X154107Y1548017D01*
X154135Y1547986D01*
G03X155618Y1547329I1483J1345D01*
G03X157304Y1548252I0J2001D01*
G02X157473Y1548344I168J-108D01*
G37*
G36*
G01X161403Y402610D02*
X168637D01*
G02X168779Y402551I0J-200D01*
G01X169281Y402049D01*
G02X169340Y401907I-141J-142D01*
G01Y400226D01*
X169350Y400216D01*
Y393550D01*
X168950Y393150D01*
X166100D01*
X161463D01*
G02X161321Y393209I0J200D01*
G01X160779Y393751D01*
G02X160720Y393893I141J142D01*
G01Y401927D01*
G02X160779Y402069I200J0D01*
G01X161261Y402551D01*
G02X161403Y402610I142J-141D01*
G37*
G36*
G01X170320Y417677D02*
Y411153D01*
G02X170261Y411011I-200J0D01*
G01X169649Y410399D01*
G02X169507Y410340I-142J141D01*
G01X164203D01*
G02X164061Y410399I0J200D01*
G01X163269Y411191D01*
G02X163210Y411333I141J142D01*
G01Y417727D01*
G02X163269Y417869I200J0D01*
G01X163781Y418381D01*
G02X163923Y418440I142J-141D01*
G01X169557D01*
G02X169699Y418381I0J-200D01*
G01X170261Y417819D01*
G02X170320Y417677I-141J-142D01*
G37*
G36*
G01X161420Y424767D02*
Y405403D01*
G02X161361Y405261I-200J0D01*
G01X161209Y405109D01*
G02X161067Y405050I-142J141D01*
G01X157133D01*
G02X156991Y405109I0J200D01*
G01X156299Y405801D01*
G02X156240Y405943I141J142D01*
G01Y425647D01*
G02X156299Y425789I200J0D01*
G01X156651Y426141D01*
G02X156793Y426200I142J-141D01*
G01X159987D01*
G02X160129Y426141I0J-200D01*
G01X161361Y424909D01*
G02X161420Y424767I-141J-142D01*
G37*
G36*
G01X177929Y447651D02*
X178081Y447499D01*
G02X178140Y447357I-141J-142D01*
G01Y440543D01*
G03X178199Y440401I200J0D01*
G01X179391Y439209D01*
G02X179450Y439067I-141J-142D01*
G01Y436983D01*
G02X179391Y436841I-200J0D01*
G01X178239Y435689D01*
G02X178097Y435630I-142J141D01*
G01X164203D01*
G02X164061Y435689I0J200D01*
G01X163499Y436251D01*
G02X163440Y436393I141J142D01*
G01Y446817D01*
G02X163499Y446959I200J0D01*
G01X164191Y447651D01*
G02X164333Y447710I142J-141D01*
G01X177787D01*
G02X177929Y447651I0J-200D01*
G37*
G36*
G01X165413Y486030D02*
X182717D01*
G02X182859Y485971I0J-200D01*
G01X184461Y484369D01*
G02X184520Y484227I-141J-142D01*
G01Y466492D01*
G02X184344Y466294I-199J0D01*
G01X183546D01*
Y463768D01*
G02X183372Y463594I-199J24D01*
G01X182546D01*
Y451568D01*
G02X182372Y451394I-199J24D01*
G01X165728D01*
G02X165554Y451568I25J199D01*
G01Y463594D01*
X164728D01*
G02X164554Y463768I25J199D01*
G01Y466294D01*
X164276D01*
X164160Y466410D01*
Y484777D01*
G02X164219Y484919I200J0D01*
G01X165271Y485971D01*
G02X165413Y486030I142J-141D01*
G37*
G36*
G01X181041Y500671D02*
X180669Y500299D01*
G02X180527Y500240I-142J141D01*
G01X167303D01*
G02X167161Y500299I0J200D01*
G01X165419Y502041D01*
G02X165360Y502183I141J142D01*
G01Y508047D01*
G02X165419Y508189I200J0D01*
G01X167061Y509831D01*
G02X167203Y509890I142J-141D01*
G01X180387D01*
G02X180529Y509831I0J-200D01*
G01X181041Y509319D01*
G02X181100Y509177I-141J-142D01*
G01Y500813D01*
G02X181041Y500671I-200J0D01*
G37*
G36*
G01X170823Y791970D02*
G03I-656J0D01*
G37*
G36*
G01Y828781D02*
G03I-656J0D01*
G37*
G36*
G01Y865592D02*
G03I-656J0D01*
G37*
G36*
G01Y902403D02*
G03I-656J0D01*
G37*
G36*
G01Y939214D02*
G03I-656J0D01*
G37*
G36*
G01Y1086458D02*
G03I-656J0D01*
G37*
G36*
G01Y1233702D02*
G03I-656J0D01*
G37*
G36*
G01X191348Y1335688D02*
X220574D01*
X220610Y1335652D01*
Y1329150D01*
X220261Y1328801D01*
X201161D01*
X199711Y1327351D01*
Y1321851D01*
X198896Y1321036D01*
X169226D01*
X168661Y1321601D01*
Y1327001D01*
X169461Y1327801D01*
X188461D01*
X189661Y1329001D01*
Y1334001D01*
X191348Y1335688D01*
G37*
G36*
G01X174450Y1440081D02*
X174936Y1439595D01*
G02X174995Y1439453I-141J-142D01*
G01Y1424381D01*
G02X174936Y1424239I-200J0D01*
G01X174711Y1424014D01*
G02X174569Y1423955I-142J141D01*
G01X163230D01*
G02X163088Y1424014I0J200D01*
G01X162590Y1424512D01*
G02X162531Y1424654I141J142D01*
G01Y1437714D01*
G02X162590Y1437856I200J0D01*
G01X164815Y1440081D01*
G02X164957Y1440140I142J-141D01*
G01X174308D01*
G02X174450Y1440081I0J-200D01*
G37*
G36*
G01X167270Y1462595D02*
G03I-519J0D01*
G37*
G36*
G01X169180Y1459995D02*
G03I-519J0D01*
G37*
G36*
G01X163632Y1477590D02*
G03I-519J0D01*
G37*
G36*
G01X169180Y1465195D02*
G03I-519J0D01*
G37*
G36*
G01X163632Y1486190D02*
G03I-519J0D01*
G37*
G36*
G01X166232Y1484280D02*
G03I-519J0D01*
G37*
G36*
G01Y1479500D02*
G03I-519J0D01*
G37*
G36*
G01X161032D02*
G03I-519J0D01*
G37*
G36*
G01Y1484280D02*
G03I-519J0D01*
G37*
G36*
G01X166232Y1506080D02*
G03I-519J0D01*
G37*
G36*
G01X161032D02*
G03I-519J0D01*
G37*
G36*
G01Y1501300D02*
G03I-519J0D01*
G37*
G36*
G01X163632Y1499490D02*
G03I-519J0D01*
G37*
G36*
G01X166232Y1501300D02*
G03I-519J0D01*
G37*
G36*
G01X163632Y1507982D02*
G03I-519J0D01*
G37*
G36*
G01X186613Y1574076D02*
X182820D01*
X182523Y1573779D01*
Y1567909D01*
X174788Y1560174D01*
X159521D01*
X158681Y1559334D01*
Y1556411D01*
Y1550545D01*
X159598Y1549628D01*
X179544D01*
X186471Y1556555D01*
X186957D01*
X187008Y1556606D01*
Y1573681D01*
X186613Y1574076D01*
G37*
G36*
G01X174326Y1567192D02*
Y1574248D01*
X177967Y1577889D01*
X178464Y1578386D01*
X183263D01*
X183760Y1577889D01*
X184739Y1576910D01*
X194850D01*
X202110Y1569650D01*
X221520D01*
X222620Y1570750D01*
Y1581660D01*
X220962Y1583318D01*
X193695D01*
X177358D01*
X171869Y1577829D01*
X169538D01*
X168491Y1576782D01*
X159889D01*
X159083Y1575976D01*
Y1562121D01*
X159573Y1561631D01*
X162026D01*
X172035D01*
X173611D01*
X174326Y1562346D01*
Y1563922D01*
Y1567192D01*
G37*
G36*
G01X190810Y401850D02*
X188300D01*
X188090Y401640D01*
Y395470D01*
X187300Y394680D01*
X182350D01*
X182100Y394430D01*
Y393000D01*
X182430Y392670D01*
X190730D01*
X190990Y392930D01*
Y401670D01*
X190810Y401850D01*
G37*
G36*
G01X180330Y424867D02*
Y411373D01*
G02X180271Y411231I-200J0D01*
G01X180029Y410989D01*
G02X179887Y410930I-142J141D01*
G01X176983D01*
G02X176841Y410989I0J200D01*
G01X176629Y411201D01*
G02X176570Y411343I141J142D01*
G01Y417997D01*
G03X176511Y418139I-200J0D01*
G01X175949Y418701D01*
G02X175890Y418843I141J142D01*
G01Y425327D01*
G02X175949Y425469I200J0D01*
G01X176051Y425571D01*
G02X176193Y425630I142J-141D01*
G01X179567D01*
G02X179709Y425571I0J-200D01*
G01X180271Y425009D01*
G02X180330Y424867I-141J-142D01*
G37*
G36*
G01X188200Y424227D02*
Y404863D01*
G02X188141Y404721I-200J0D01*
G01X187989Y404569D01*
G02X187847Y404510I-142J141D01*
G01X183913D01*
G02X183771Y404569I0J200D01*
G01X183079Y405261D01*
G02X183020Y405403I141J142D01*
G01Y425107D01*
G02X183079Y425249I200J0D01*
G01X183431Y425601D01*
G02X183573Y425660I142J-141D01*
G01X186767D01*
G02X186909Y425601I0J-200D01*
G01X188141Y424369D01*
G02X188200Y424227I-141J-142D01*
G37*
G36*
G01X180433Y447800D02*
X184617D01*
G02X184759Y447741I0J-200D01*
G01X185051Y447449D01*
G02X185110Y447307I-141J-142D01*
G01Y429523D01*
G02X185051Y429381I-200J0D01*
G01X184809Y429139D01*
G02X184667Y429080I-142J141D01*
G01X180173D01*
G02X180031Y429139I0J200D01*
G01X179599Y429571D01*
G02X179540Y429713I141J142D01*
G01Y433427D01*
G02X179599Y433569I200J0D01*
G01X180391Y434361D01*
G03X180450Y434503I-141J142D01*
G01Y436484D01*
X180452Y436485D01*
Y439565D01*
X180450Y439566D01*
Y440067D01*
G03X180391Y440209I-200J0D01*
G01X180099Y440501D01*
G02X180040Y440643I141J142D01*
G01Y447407D01*
G02X180099Y447549I200J0D01*
G01X180291Y447741D01*
G02X180433Y447800I142J-141D01*
G37*
G36*
G01X184382Y795316D02*
G03I-656J0D01*
G37*
G36*
G01Y832127D02*
G03I-656J0D01*
G37*
G36*
G01Y868938D02*
G03I-656J0D01*
G37*
G36*
G01Y905750D02*
G03I-656J0D01*
G37*
G36*
G01Y942561D02*
G03I-656J0D01*
G37*
G36*
G01Y1089805D02*
G03I-656J0D01*
G37*
G36*
G01Y1126616D02*
G03I-656J0D01*
G37*
G36*
G01Y1163427D02*
G03I-656J0D01*
G37*
G36*
G01Y1200238D02*
G03I-656J0D01*
G37*
G36*
G01Y1237049D02*
G03I-656J0D01*
G37*
G36*
G01X185728Y1430508D02*
X204980D01*
X207480D01*
X211228D01*
X211728Y1430008D01*
Y1418508D01*
Y1416709D01*
Y1416324D01*
X210661Y1415257D01*
X181553D01*
X180420Y1416390D01*
Y1429581D01*
X181347Y1430508D01*
X183759D01*
X185728D01*
G37*
G36*
G01X173960Y1459995D02*
G03I-519J0D01*
G37*
G36*
G01X175870Y1462595D02*
G03I-519J0D01*
G37*
G36*
G01X175880Y1455495D02*
G03I-519J0D01*
G37*
G36*
G01X173970Y1452895D02*
G03I-519J0D01*
G37*
G36*
G01X175880Y1450295D02*
G03I-519J0D01*
G37*
G36*
G01X180660D02*
G03I-519J0D01*
G37*
G36*
G01X182570Y1452895D02*
G03I-519J0D01*
G37*
G36*
G01X180660Y1455495D02*
G03I-519J0D01*
G37*
G36*
G01X173960Y1465195D02*
G03I-519J0D01*
G37*
G36*
G01X180589Y1571350D02*
Y1574077D01*
X181939Y1575427D01*
Y1576645D01*
X181409Y1577175D01*
X179000D01*
X176723Y1574898D01*
Y1574235D01*
Y1571158D01*
Y1569471D01*
Y1569019D01*
X177133Y1568609D01*
X180099D01*
X180589Y1569099D01*
Y1569535D01*
Y1571350D01*
G37*
G36*
G01X180361Y1659391D02*
Y1648635D01*
G02X180302Y1648493I-200J0D01*
G01X180057Y1648248D01*
G02X179915Y1648189I-142J141D01*
G01X176791D01*
G02X176649Y1648248I0J200D01*
G01X176417Y1648480D01*
G02X176358Y1648622I141J142D01*
G01Y1658596D01*
G02X176417Y1658738I200J0D01*
G01X177269Y1659590D01*
G02X177411Y1659649I142J-141D01*
G01X180103D01*
G02X180245Y1659590I0J-200D01*
G01X180302Y1659533D01*
G02X180361Y1659391I-141J-142D01*
G37*
G36*
G01X197100Y417137D02*
Y410613D01*
G02X197041Y410471I-200J0D01*
G01X196429Y409859D01*
G02X196287Y409800I-142J141D01*
G01X190983D01*
G02X190841Y409859I0J200D01*
G01X190049Y410651D01*
G02X189990Y410793I141J142D01*
G01Y417187D01*
G02X190049Y417329I200J0D01*
G01X190561Y417841D01*
G02X190703Y417900I142J-141D01*
G01X196337D01*
G02X196479Y417841I0J-200D01*
G01X197041Y417279D01*
G02X197100Y417137I-141J-142D01*
G37*
G36*
G01X207759Y643924D02*
X232223D01*
G02X232365Y643865I0J-200D01*
G01X233256Y642974D01*
G02X233315Y642832I-141J-142D01*
G01Y624513D01*
X233345Y624440D01*
X233350Y624435D01*
Y623077D01*
G03X233409Y622935I200J0D01*
G01X239415Y616929D01*
X239416Y616928D01*
X241168Y615176D01*
X248599D01*
X248627Y615205D01*
X248701Y615235D01*
X312061D01*
X312079Y615216D01*
X320064D01*
X320796Y614484D01*
Y603767D01*
X320562Y603533D01*
X269876D01*
X269771Y603638D01*
Y604894D01*
G03X269813Y605246I-1459J353D01*
G01Y608206D01*
G03X269754Y608347I-200J-1D01*
G01X269667Y608434D01*
Y612142D01*
X268771Y613038D01*
X266861D01*
X264460Y610637D01*
G03X264401Y610495I141J-142D01*
G01Y607061D01*
G02X264342Y606919I-200J0D01*
G01X263160Y605737D01*
G02X263018Y605678I-142J141D01*
G01X241835D01*
X240378Y604221D01*
Y567689D01*
X238938Y566249D01*
X231860D01*
X231193Y566916D01*
Y612329D01*
G02X231153Y612449I160J120D01*
G01Y633754D01*
G03X231094Y633896I-200J0D01*
G01X229627Y635363D01*
G03X229485Y635422I-142J-141D01*
G01X211023D01*
G03X210881Y635363I0J-200D01*
G01X209990Y634472D01*
G03X209931Y634330I141J-142D01*
G01Y624341D01*
G02X209872Y624199I-200J0D01*
G01X205319Y619646D01*
G03X205261Y619507I139J-140D01*
G01Y588531D01*
G02X205202Y588389I-200J0D01*
G01X204455Y587642D01*
G02X204313Y587583I-142J141D01*
G01X198712D01*
G02X198570Y587642I0J200D01*
G01X197823Y588389D01*
G02X197764Y588531I141J142D01*
G01Y595329D01*
G03X197749Y595406I-200J1D01*
G01X197721Y595471D01*
G02X197706Y595548I185J76D01*
G01Y642210D01*
G02X197765Y642352I200J0D01*
G01X199182Y643769D01*
G02X199324Y643828I142J-141D01*
G01X207537D01*
G03X207679Y643887I0J200D01*
G01X207686Y643894D01*
X207759Y643924D01*
G37*
G36*
G01X311999Y747146D02*
X400657D01*
X405154Y742649D01*
Y735813D01*
X405157Y735810D01*
Y734114D01*
X404722Y733679D01*
X402750D01*
X400116Y736313D01*
Y744256D01*
X399348Y745024D01*
X398890D01*
X398790Y745124D01*
X380243D01*
X379533Y744414D01*
Y728782D01*
X380223Y728092D01*
X400521D01*
X403251Y725362D01*
X406577D01*
X410361Y729146D01*
X432157D01*
X432336Y729325D01*
X434685D01*
X435660Y730300D01*
Y736530D01*
X434041Y738149D01*
X432380D01*
X432351Y738178D01*
X413851D01*
X413151Y738878D01*
Y744678D01*
X413951Y745478D01*
X441325D01*
X442157Y744646D01*
Y723146D01*
X444325Y720978D01*
X465895D01*
X466157Y720716D01*
Y714615D01*
X465420Y713878D01*
X446051D01*
X444951Y712778D01*
Y706281D01*
X446586Y704646D01*
X466924D01*
X468851Y702719D01*
Y693509D01*
X468657Y693315D01*
X467457D01*
X467160Y693612D01*
Y701830D01*
X466266Y702724D01*
X445643D01*
X444933Y702014D01*
Y686284D01*
X445654Y685564D01*
X465361D01*
Y686111D01*
X467805D01*
Y683960D01*
X468562Y683203D01*
X471437D01*
X472803Y684569D01*
X476003D01*
X477157Y683415D01*
Y679646D01*
X478157Y678646D01*
X499656D01*
X502757Y675549D01*
Y666015D01*
X502157Y665415D01*
X500157D01*
X499460Y666112D01*
Y675430D01*
X498666Y676224D01*
X497282D01*
X497150Y676356D01*
X478603D01*
X478471Y676224D01*
X478243D01*
X477533Y675514D01*
Y659898D01*
X478367Y659064D01*
X498077D01*
Y659611D01*
X500405D01*
Y657460D01*
X501162Y656703D01*
X504037D01*
X504157Y656583D01*
Y655472D01*
X506983Y652646D01*
X509983D01*
X510851Y651778D01*
Y645481D01*
X512186Y644146D01*
X535157D01*
X536157Y643146D01*
Y637146D01*
X539157Y634146D01*
X560726D01*
X562257Y632615D01*
Y616715D01*
Y566917D01*
X559640Y564300D01*
X513530D01*
X510710Y567120D01*
Y583900D01*
X517060Y590250D01*
X544030D01*
X546470Y592690D01*
Y613106D01*
X544430Y615146D01*
X540157D01*
X538509Y616794D01*
X534227D01*
X531643Y619378D01*
X525051D01*
X525038Y619365D01*
X524954D01*
Y619281D01*
X524951Y619278D01*
Y618621D01*
X524954Y618618D01*
Y616586D01*
X526417Y615123D01*
X528261D01*
X528546Y614838D01*
X532011D01*
X532031Y614818D01*
Y613968D01*
X532011Y613948D01*
X528446D01*
X528245Y613747D01*
Y609815D01*
X528532Y609528D01*
X532011D01*
X532031Y609508D01*
Y608648D01*
X532011Y608628D01*
X528670D01*
X528245Y608203D01*
Y607403D01*
X528215Y607373D01*
X521375D01*
X521345Y607403D01*
Y615195D01*
X519975Y616565D01*
X511554D01*
Y616528D01*
X501775D01*
X501351Y616952D01*
Y626657D01*
X504451Y629757D01*
Y651078D01*
X503751Y651778D01*
X500043D01*
X497856Y653965D01*
X496854D01*
X496438Y653549D01*
X491738D01*
X491654Y653465D01*
Y650716D01*
X493147Y649223D01*
X494961D01*
X495246Y648938D01*
X498711D01*
X498721Y648928D01*
Y648068D01*
X498701Y648048D01*
X495146D01*
X494945Y647847D01*
Y643975D01*
X495292Y643628D01*
X498711D01*
X498751Y643588D01*
Y642768D01*
X498711Y642728D01*
X495370D01*
X494945Y642303D01*
Y641503D01*
X494915Y641473D01*
X488075D01*
X488045Y641503D01*
Y649325D01*
X486692Y650678D01*
X468851D01*
X468651Y650878D01*
Y653090D01*
X471751Y656190D01*
Y661740D01*
Y677678D01*
X471273Y678156D01*
X467565D01*
X465752Y679969D01*
X459054D01*
Y677166D01*
X460497Y675723D01*
X462361D01*
X462646Y675438D01*
X466101D01*
X466141Y675398D01*
Y674578D01*
X466111Y674548D01*
X462546D01*
X462345Y674347D01*
Y670465D01*
X462692Y670118D01*
X466121D01*
X466151Y670088D01*
Y669278D01*
X466111Y669238D01*
X462780D01*
X462345Y668803D01*
Y668003D01*
X462315Y667973D01*
X455475D01*
X455445Y668003D01*
Y675965D01*
X454245Y677165D01*
X436370D01*
X436090Y677445D01*
Y679130D01*
X437802Y680842D01*
Y684228D01*
X439657Y686084D01*
Y701297D01*
X439039Y701915D01*
X435954D01*
X435474Y701435D01*
Y700305D01*
X434298Y699129D01*
X430127D01*
X429945Y698947D01*
Y695105D01*
X430332Y694718D01*
X433711D01*
X433741Y694688D01*
Y693868D01*
X433711Y693838D01*
X430380D01*
X429945Y693403D01*
Y692603D01*
X429915Y692573D01*
X423075D01*
X423045Y692603D01*
Y698353D01*
X423033Y698365D01*
Y700698D01*
X422011Y701720D01*
X407624D01*
X407611Y701733D01*
Y718410D01*
X406428Y719593D01*
X403000D01*
X402458Y719051D01*
Y718143D01*
X401244Y716929D01*
X397127D01*
X396945Y716747D01*
Y712905D01*
X397322Y712528D01*
X400711D01*
X400741Y712498D01*
Y711658D01*
X400711Y711628D01*
X397370D01*
X396945Y711203D01*
Y710403D01*
X396915Y710373D01*
X390075D01*
X390045Y710403D01*
Y716153D01*
X390049Y716157D01*
Y718261D01*
X388832Y719478D01*
X370237D01*
X369406Y718647D01*
Y718478D01*
X367806Y716878D01*
X364212D01*
X364169Y716835D01*
X363899Y716566D01*
Y716185D01*
X363891Y716165D01*
Y712847D01*
X363899Y712826D01*
Y712665D01*
X364023Y712541D01*
Y712535D01*
X364073Y712485D01*
X367363D01*
X367443Y712405D01*
Y711685D01*
X367313Y711555D01*
X364039D01*
X363899Y711415D01*
Y711185D01*
X363891Y711165D01*
Y710431D01*
X363832Y710289D01*
X363750Y710207D01*
X363638Y710161D01*
X363592Y710174D01*
G03X363334Y710237I-722J-2395D01*
G03X362879Y710281I-467J-2458D01*
G01X362854D01*
G03X362095Y710158I16J-2502D01*
G01X362065Y710148D01*
X357131D01*
X356991Y710288D01*
Y716102D01*
X356996D01*
Y718164D01*
X355680Y719480D01*
X347032D01*
X346830Y719278D01*
X340521D01*
X339871Y719928D01*
X337900D01*
X335101Y717129D01*
X331027D01*
X330845Y716947D01*
Y713055D01*
X331172Y712728D01*
X334611D01*
X334651Y712688D01*
Y711868D01*
X334621Y711838D01*
X331280D01*
X330845Y711403D01*
Y710603D01*
X330815Y710573D01*
X323975D01*
X323945Y710603D01*
Y718379D01*
X322594Y719730D01*
X308266D01*
X307157Y718621D01*
Y714401D01*
X306773Y714017D01*
X302170D01*
X301157Y715030D01*
Y724121D01*
X300475Y724803D01*
X300291D01*
X299920Y725174D01*
X281373D01*
X280663Y724464D01*
Y708833D01*
X281340Y708156D01*
X301544D01*
X304132Y705568D01*
X307080D01*
X307157Y705491D01*
Y700638D01*
X307156D01*
Y699807D01*
X306856Y699507D01*
X304680D01*
X302192Y697019D01*
X298247D01*
X298065Y696837D01*
Y692955D01*
X298442Y692578D01*
X301841D01*
X301901Y692518D01*
Y691728D01*
X301851Y691678D01*
X298450D01*
X298065Y691293D01*
Y690493D01*
X298035Y690463D01*
X291195D01*
X291165Y690493D01*
Y698232D01*
X289826Y699571D01*
X275082D01*
X274157Y698646D01*
Y680915D01*
X272657Y679415D01*
X270160D01*
X268245Y681320D01*
Y689993D01*
X267604Y690634D01*
X267489D01*
X267190Y690933D01*
X248643D01*
X247933Y690223D01*
Y674586D01*
X248705Y673814D01*
X268992D01*
X271763Y671043D01*
X273766D01*
X274225Y670584D01*
Y667687D01*
X274247Y667665D01*
Y665672D01*
X273885Y665310D01*
X272052D01*
X269481Y662739D01*
X265510D01*
X265328Y662557D01*
Y658652D01*
X265642Y658338D01*
X269111D01*
X269141Y658308D01*
Y657468D01*
X269111Y657438D01*
X265753D01*
X265328Y657013D01*
Y656213D01*
X265298Y656183D01*
X258458D01*
X258428Y656213D01*
Y664072D01*
X257079Y665421D01*
X234314D01*
X232921Y664028D01*
Y647108D01*
X231611Y645798D01*
X204351D01*
X204326Y645823D01*
X198936D01*
X197821Y646938D01*
Y686161D01*
X204806Y693146D01*
X268157D01*
X268657Y693646D01*
Y700646D01*
X268979Y700968D01*
X271157D01*
X275157Y704968D01*
Y722452D01*
X280067Y727362D01*
X300873D01*
X301657Y728146D01*
Y734146D01*
X302657Y735146D01*
X308157D01*
X309157Y736146D01*
Y736200D01*
X310972Y738015D01*
Y746119D01*
X311999Y747146D01*
G37*
G36*
G01X200524Y791970D02*
G03I-656J0D01*
G37*
G36*
G01Y828781D02*
G03I-656J0D01*
G37*
G36*
G01Y865592D02*
G03I-656J0D01*
G37*
G36*
G01Y902403D02*
G03I-656J0D01*
G37*
G36*
G01Y939214D02*
G03I-656J0D01*
G37*
G36*
G01Y1086458D02*
G03I-656J0D01*
G37*
G36*
G01Y1123269D02*
G03I-656J0D01*
G37*
G36*
G01Y1160080D02*
G03I-656J0D01*
G37*
G36*
G01Y1196891D02*
G03I-656J0D01*
G37*
G36*
G01Y1233702D02*
G03I-656J0D01*
G37*
G36*
G01X200760Y1459995D02*
G03I-519J0D01*
G37*
G36*
G01X195980D02*
G03I-519J0D01*
G37*
G36*
G01X194070Y1462595D02*
G03I-519J0D01*
G37*
G36*
G01X200770Y1452895D02*
G03I-519J0D01*
G37*
G36*
G01X189280Y1474895D02*
G03I-519J0D01*
G37*
G36*
G01X187370Y1472295D02*
G03I-519J0D01*
G37*
G36*
G01X189280Y1469695D02*
G03I-519J0D01*
G37*
G36*
G01X194060D02*
G03I-519J0D01*
G37*
G36*
G01X195970Y1472295D02*
G03I-519J0D01*
G37*
G36*
G01X194060Y1474895D02*
G03I-519J0D01*
G37*
G36*
G01X200760Y1465195D02*
G03I-519J0D01*
G37*
G36*
G01X195980D02*
G03I-519J0D01*
G37*
G36*
G01X200335Y1527011D02*
X201961D01*
G02X202026Y1527000I0J-200D01*
G01X202940Y1526686D01*
G03X203346Y1526607I487J1420D01*
G01X203385Y1526605D01*
X203454Y1526573D01*
X203670Y1526345D01*
G02X203724Y1526207I-146J-137D01*
G01Y1524099D01*
G02X203670Y1523961I-200J-1D01*
G01X203454Y1523733D01*
X203385Y1523701D01*
X203346Y1523699D01*
G03X203031Y1523648I81J-1499D01*
G01X201809Y1523313D01*
G02X201756Y1523306I-52J193D01*
G01X200069D01*
G02X199999Y1523319I1J200D01*
G01X199228Y1523607D01*
G03X198703Y1523702I-526J-1407D01*
G03X198306Y1523648I2J-1502D01*
G01X197085Y1523313D01*
G02X197032Y1523306I-52J193D01*
G01X195345D01*
G02X195275Y1523319I1J200D01*
G01X194504Y1523607D01*
G03X193979Y1523702I-526J-1407D01*
G03X193582Y1523648I2J-1502D01*
G01X192360Y1523313D01*
G02X192307Y1523306I-52J193D01*
G01X190620D01*
G02X190550Y1523319I1J200D01*
G01X189779Y1523607D01*
G03X189254Y1523702I-526J-1407D01*
G03X188857Y1523648I2J-1502D01*
G01X187636Y1523313D01*
G02X187583Y1523306I-52J193D01*
G01X186180D01*
G02X186038Y1523365I0J200D01*
G01X185876Y1523527D01*
G02X185817Y1523669I141J142D01*
G01Y1526626D01*
G02X185946Y1526813I200J0D01*
G01X186430Y1526998D01*
G02X186502Y1527011I71J-187D01*
G01X187787D01*
G02X187852Y1527000I0J-200D01*
G01X188766Y1526686D01*
G03X189254Y1526604I489J1420D01*
G03X189676Y1526665I-2J1502D01*
G01X190830Y1527003D01*
G02X190886Y1527011I56J-192D01*
G01X192512D01*
G02X192577Y1527000I0J-200D01*
G01X193491Y1526686D01*
G03X193979Y1526604I489J1420D01*
G03X194401Y1526665I-2J1502D01*
G01X195555Y1527003D01*
G02X195611Y1527011I56J-192D01*
G01X197236D01*
G02X197301Y1527000I0J-200D01*
G01X198215Y1526686D01*
G03X198703Y1526604I489J1420D01*
G03X199125Y1526665I-2J1502D01*
G01X200279Y1527003D01*
G02X200335Y1527011I56J-192D01*
G37*
G36*
G01X213731Y1553361D02*
X212919Y1552549D01*
G02X212777Y1552490I-142J141D01*
G01X188963D01*
G02X188821Y1552549I0J200D01*
G01X188256Y1553114D01*
G02X188197Y1553256I141J142D01*
G01Y1575111D01*
G02X188256Y1575253I200J0D01*
G01X188403Y1575400D01*
G02X188545Y1575459I142J-141D01*
G01X193410D01*
G02X193552Y1575400I0J-200D01*
G01X213731Y1555221D01*
G02X213790Y1555079I-141J-142D01*
G01Y1553503D01*
G02X213731Y1553361I-200J0D01*
G37*
G36*
G01X230081Y632685D02*
Y615218D01*
Y580581D01*
Y566470D01*
X229822Y566211D01*
X214266D01*
X206501Y573976D01*
Y580810D01*
Y582268D01*
Y618248D01*
X211771Y623518D01*
Y633621D01*
X212564Y634414D01*
X228352D01*
X230081Y632685D01*
G37*
G36*
G01X214083Y795316D02*
G03I-656J0D01*
G37*
G36*
G01Y832127D02*
G03I-656J0D01*
G37*
G36*
G01Y868938D02*
G03I-656J0D01*
G37*
G36*
G01Y905750D02*
G03I-656J0D01*
G37*
G36*
G01Y942561D02*
G03I-656J0D01*
G37*
G36*
G01Y1089805D02*
G03I-656J0D01*
G37*
G36*
G01Y1126616D02*
G03I-656J0D01*
G37*
G36*
G01Y1163427D02*
G03I-656J0D01*
G37*
G36*
G01Y1200238D02*
G03I-656J0D01*
G37*
G36*
G01Y1237049D02*
G03I-656J0D01*
G37*
G36*
G01X202670Y1462595D02*
G03I-519J0D01*
G37*
G36*
G01X202680Y1455495D02*
G03I-519J0D01*
G37*
G36*
G01X207460D02*
G03I-519J0D01*
G37*
G36*
G01X209370Y1452895D02*
G03I-519J0D01*
G37*
G36*
G01X207460Y1450295D02*
G03I-519J0D01*
G37*
G36*
G01X202680D02*
G03I-519J0D01*
G37*
G36*
G01X216080Y1474895D02*
G03I-519J0D01*
G37*
G36*
G01X214170Y1472295D02*
G03I-519J0D01*
G37*
G36*
G01X216080Y1469695D02*
G03I-519J0D01*
G37*
G36*
G01X205135Y1527011D02*
X206685D01*
G02X206750Y1527000I0J-200D01*
G01X207664Y1526686D01*
G03X208115Y1526605I488J1420D01*
G01X208154Y1526604D01*
X208225Y1526573D01*
X208448Y1526345D01*
G02X208504Y1526205I-144J-139D01*
G01Y1524101D01*
G02X208448Y1523961I-200J-1D01*
G01X208225Y1523733D01*
X208154Y1523702D01*
X208115Y1523701D01*
G03X207755Y1523648I37J-1501D01*
G01X206533Y1523313D01*
G02X206480Y1523306I-52J193D01*
G01X205091D01*
G02X204949Y1523365I0J200D01*
G01X204785Y1523529D01*
G02X204726Y1523671I141J142D01*
G01Y1526602D01*
G02X204785Y1526744I200J0D01*
G01X204993Y1526952D01*
G02X205135Y1527011I142J-141D01*
G37*
G36*
G01X210187D02*
X211409D01*
G02X211474Y1527000I0J-200D01*
G01X212388Y1526686D01*
G03X212830Y1526605I489J1420D01*
G01X212869Y1526604D01*
X212940Y1526573D01*
X213161Y1526345D01*
G02X213218Y1526205I-143J-140D01*
G01Y1524101D01*
G02X213161Y1523961I-200J0D01*
G01X212940Y1523733D01*
X212869Y1523702D01*
X212830Y1523701D01*
G03X212479Y1523648I47J-1501D01*
G01X211258Y1523313D01*
G02X211205Y1523306I-52J193D01*
G01X209893D01*
G02X209751Y1523365I0J200D01*
G01X209565Y1523551D01*
G02X209506Y1523693I141J142D01*
G01Y1526330D01*
G02X209565Y1526472I200J0D01*
G01X210045Y1526952D01*
G02X210187Y1527011I142J-141D01*
G37*
G36*
G01X223954Y1527010D02*
X224906D01*
G02X225048Y1526951I0J-200D01*
G01X225306Y1526693D01*
G02X225364Y1526552I-142J-141D01*
G01Y1525527D01*
G03X225423Y1525386I200J1D01*
G01X225429Y1525380D01*
X225459Y1525307D01*
Y1525276D01*
X225796Y1524939D01*
X225869Y1524909D01*
X225900D01*
X226192Y1524617D01*
G03X226333Y1524558I142J141D01*
G01X227362D01*
G02X227562Y1524358I0J-200D01*
G01Y1524098D01*
G02X227499Y1523953I-200J1D01*
G01X227256Y1523724D01*
X227180Y1523696D01*
X227138Y1523699D01*
G03X227050Y1523702I-95J-1499D01*
G03X226653Y1523648I2J-1502D01*
G01X225431Y1523313D01*
G02X225378Y1523306I-52J193D01*
G01X223691D01*
G02X223621Y1523319I1J200D01*
G01X222850Y1523607D01*
G03X222325Y1523702I-526J-1407D01*
G03X221928Y1523648I2J-1502D01*
G01X220707Y1523313D01*
G02X220654Y1523306I-52J193D01*
G01X218967D01*
G02X218897Y1523319I1J200D01*
G01X218126Y1523607D01*
G03X217601Y1523702I-526J-1407D01*
G03X217204Y1523648I2J-1502D01*
G01X215982Y1523313D01*
G02X215929Y1523306I-52J193D01*
G01X214535D01*
G02X214393Y1523365I0J200D01*
G01X214278Y1523480D01*
G02X214219Y1523622I141J142D01*
G01Y1526271D01*
G02X214278Y1526413I200J0D01*
G01X214816Y1526951D01*
G02X214958Y1527010I142J-141D01*
G01X216137D01*
G02X216202Y1526999I0J-200D01*
G01X217113Y1526686D01*
G03X217601Y1526604I489J1420D01*
G03X218023Y1526665I-2J1502D01*
G01X219174Y1527002D01*
G02X219230Y1527010I56J-192D01*
G01X220861D01*
G02X220926Y1526999I0J-200D01*
G01X221837Y1526686D01*
G03X222325Y1526604I489J1420D01*
G03X222747Y1526665I-2J1502D01*
G01X223898Y1527002D01*
G02X223954Y1527010I56J-192D01*
G37*
G36*
G01X221197Y522453D02*
G03I-510J0D01*
G37*
G36*
G01X227197D02*
G03I-510J0D01*
G37*
G36*
G01X219626Y694146D02*
X218351Y695419D01*
Y700578D01*
Y704227D01*
X220165Y706041D01*
X243762D01*
X247109Y702694D01*
X247369Y702434D01*
X247849Y701954D01*
X248657Y701146D01*
X249242Y700561D01*
X266930D01*
X267657Y699834D01*
Y694646D01*
X267157Y694146D01*
X219626D01*
G37*
G36*
G01X230225Y791970D02*
G03I-656J0D01*
G37*
G36*
G01Y828781D02*
G03I-656J0D01*
G37*
G36*
G01Y865592D02*
G03I-656J0D01*
G37*
G36*
G01Y902403D02*
G03I-656J0D01*
G37*
G36*
G01Y939214D02*
G03I-656J0D01*
G37*
G36*
G01Y1086458D02*
G03I-656J0D01*
G37*
G36*
G01Y1123269D02*
G03I-656J0D01*
G37*
G36*
G01Y1160080D02*
G03I-656J0D01*
G37*
G36*
G01Y1196891D02*
G03I-656J0D01*
G37*
G36*
G01Y1233702D02*
G03I-656J0D01*
G37*
G36*
G01X228102Y1319284D02*
X251942D01*
G02X252142Y1319084I0J-200D01*
G01Y1287454D01*
G03X252200Y1287313I200J0D01*
G01X266564Y1272949D01*
G03X266706Y1272890I142J141D01*
G01X287901D01*
G03X288014Y1272925I0J200D01*
G01X288040Y1272942D01*
X288096Y1272960D01*
X289286D01*
G02X289427Y1272901I-1J-200D01*
G01X289486Y1272842D01*
G03X289627Y1272784I141J142D01*
G01X320515D01*
G03X320656Y1272842I0J200D01*
G01X320715Y1272901D01*
G02X320857Y1272960I142J-141D01*
G01X322076D01*
G02X322217Y1272901I-1J-200D01*
G01X322297Y1272821D01*
G03X322439Y1272762I142J141D01*
G01X353283D01*
G03X353425Y1272821I0J200D01*
G01X353505Y1272901D01*
G02X353647Y1272960I142J-141D01*
G01X354675D01*
G02X354817Y1272901I0J-200D01*
G01X354822Y1272896D01*
G03X354963Y1272838I141J142D01*
G01X385667D01*
G03X385808Y1272896I0J200D01*
G01X387243Y1274331D01*
G03X387302Y1274473I-141J142D01*
G01Y1280674D01*
G02X387361Y1280816I200J0D01*
G01X387989Y1281444D01*
G02X388131Y1281503I142J-141D01*
G01X393416D01*
G03X393558Y1281562I0J200D01*
G01X397440Y1285444D01*
G03X397499Y1285586I-141J142D01*
G01Y1291701D01*
G02X397558Y1291843I200J0D01*
G01X397940Y1292225D01*
G02X398082Y1292284I142J-141D01*
G01X424113D01*
G02X424255Y1292225I0J-200D01*
G01X425137Y1291343D01*
G02X425196Y1291201I-141J-142D01*
G01Y1287940D01*
G03X425255Y1287798I200J0D01*
G01X425787Y1287266D01*
G03X425929Y1287207I142J141D01*
G01X431430D01*
G02X431572Y1287148I0J-200D01*
G01X431943Y1286777D01*
X431965Y1286657D01*
X431940Y1286600D01*
G03X431732Y1285602I2294J-999D01*
G01Y1285230D01*
G02X431532Y1285030I-200J0D01*
G01X423433D01*
G03X423291Y1284971I0J-200D01*
G01X420729Y1282409D01*
G03X420670Y1282267I141J-142D01*
G01Y1261061D01*
G02X420611Y1260919I-200J0D01*
G01X396719Y1237027D01*
G02X396577Y1236968I-142J141D01*
G01X390721D01*
X390631Y1237042D01*
Y1240057D01*
G03X390633Y1240146I-2002J90D01*
G01Y1240147D01*
G03X388630Y1242150I-2003J0D01*
G03X387405Y1241732I0J-2004D01*
G02X387153Y1241739I-122J158D01*
G03X386303Y1242054I-850J-989D01*
G03Y1239448I0J-1303D01*
G03X386565Y1239475I-2J1303D01*
G02X386672Y1239468I41J-196D01*
G01Y1237170D01*
G02X386476Y1237021I-193J51D01*
G03X386461I-8J-1303D01*
G03X386118Y1236975I0J-1302D01*
G01X386092Y1236968D01*
X286741D01*
G02X286599Y1237027I0J200D01*
G01X249272Y1274354D01*
G03X249130Y1274413I-142J-141D01*
G01X239093D01*
G02X238951Y1274472I0J200D01*
G01X229359Y1284064D01*
G03X229217Y1284123I-142J-141D01*
G01X228432D01*
G02X228290Y1284182I0J200D01*
G01X226922Y1285550D01*
X226893Y1285578D01*
X226863Y1285652D01*
Y1318045D01*
G02X226922Y1318187I200J0D01*
G01X227960Y1319225D01*
G02X228102Y1319284I142J-141D01*
G37*
G36*
G01X220870Y1462595D02*
G03I-519J0D01*
G37*
G36*
G01X222780Y1459995D02*
G03I-519J0D01*
G37*
G36*
G01X227560D02*
G03I-519J0D01*
G37*
G36*
G01X229470Y1462595D02*
G03I-519J0D01*
G37*
G36*
G01X229480Y1455495D02*
G03I-519J0D01*
G37*
G36*
G01X227570Y1452895D02*
G03I-519J0D01*
G37*
G36*
G01X229480Y1450295D02*
G03I-519J0D01*
G37*
G36*
G01X220860Y1469695D02*
G03I-519J0D01*
G37*
G36*
G01X222770Y1472295D02*
G03I-519J0D01*
G37*
G36*
G01X220860Y1474895D02*
G03I-519J0D01*
G37*
G36*
G01X222780Y1465195D02*
G03I-519J0D01*
G37*
G36*
G01X227560D02*
G03I-519J0D01*
G37*
G36*
G01X229255Y1527179D02*
X229818D01*
G02X229883Y1527168I0J-200D01*
G01X230057Y1527108D01*
G02X230186Y1526964I-66J-189D01*
G01X230211Y1526857D01*
X230190Y1526836D01*
Y1523475D01*
G02X230043Y1523282I-200J0D01*
G01X229182Y1523046D01*
G02X229059Y1523052I-52J193D01*
G01X228724Y1523177D01*
G02X228653Y1523223I71J187D01*
G01X228622Y1523254D01*
G02X228563Y1523396I141J142D01*
G01Y1525249D01*
G03X228504Y1525391I-200J0D01*
G01X228394Y1525501D01*
G03X228252Y1525560I-142J-141D01*
G01X226748D01*
G02X226606Y1525619I0J200D01*
G01X226425Y1525800D01*
G02X226366Y1525942I141J142D01*
G01Y1526384D01*
G02X226425Y1526526I200J0D01*
G01X226533Y1526634D01*
X226634Y1526662D01*
X226686Y1526649D01*
G03X227050Y1526604I365J1457D01*
G03X227472Y1526665I-2J1502D01*
G01X228182Y1526873D01*
X228218D01*
X228233Y1526888D01*
X229199Y1527171D01*
G02X229255Y1527179I56J-192D01*
G37*
G36*
G01X244206Y23005D02*
G03I-720J0D01*
G37*
G36*
G01X246916Y81865D02*
X254819D01*
X255673Y81011D01*
Y65697D01*
X256171Y65199D01*
X256884Y64486D01*
Y53799D01*
X256681Y53596D01*
X256035D01*
X252961D01*
X251987Y54570D01*
Y64070D01*
X250358Y65699D01*
Y69091D01*
X248984Y70465D01*
X245616D01*
X244716Y71365D01*
Y79665D01*
X246916Y81865D01*
G37*
G36*
G01X248193Y110446D02*
Y116746D01*
X247793Y117146D01*
X244093D01*
X243393Y116446D01*
Y111046D01*
X244093Y110346D01*
X248093D01*
X248193Y110446D01*
G37*
G36*
G01X267505Y601735D02*
X273798D01*
X273961Y601572D01*
Y600367D01*
X273829Y600235D01*
X270005D01*
X260413D01*
X259378Y599200D01*
Y595000D01*
Y592500D01*
Y589200D01*
Y585929D01*
X259458Y585849D01*
X260128Y585179D01*
X261308D01*
X261675D01*
X261773D01*
X261814Y585138D01*
Y581592D01*
X261756Y581534D01*
X261534D01*
X260644D01*
X244876D01*
X243909Y582501D01*
Y603937D01*
X244650Y604678D01*
X250261D01*
X250684D01*
X264041D01*
X264061Y604658D01*
X266985Y601735D01*
X267505D01*
G37*
G36*
G01X308617Y718563D02*
X315371D01*
G02X315513Y718504I0J-200D01*
G01X315595Y718422D01*
G03X315737Y718363I142J141D01*
G01X322254D01*
G02X322454Y718163I0J-200D01*
G01Y710765D01*
G02X322254Y710565I-200J0D01*
G01X316830D01*
G03X316688Y710506I0J-200D01*
G01X316560Y710378D01*
G03X316501Y710236I141J-142D01*
G01Y706511D01*
G02X316442Y706369I-200J0D01*
G01X314684Y704611D01*
X314360Y704288D01*
G03X314301Y704146I141J-142D01*
G01Y696467D01*
G03X314360Y696325I200J0D01*
G01X314992Y695693D01*
X315021Y695665D01*
X315051Y695591D01*
Y693238D01*
G03X315110Y693096I200J0D01*
G01X315542Y692664D01*
G03X315684Y692605I142J141D01*
G01X320795D01*
G03X320937Y692664I0J200D01*
G01X324268Y695995D01*
G02X324410Y696054I142J-141D01*
G01X339482D01*
G03X339624Y696113I0J200D01*
G01X340592Y697081D01*
G03X340651Y697223I-141J142D01*
G01Y717014D01*
G02X340710Y717156I200J0D01*
G01X341741Y718187D01*
X341769Y718216D01*
X341843Y718246D01*
X348481D01*
G02X348623Y718187I0J-200D01*
G01X348714Y718096D01*
Y718095D01*
X355301D01*
G02X355501Y717895I0J-200D01*
G01Y710497D01*
G02X355301Y710297I-200J0D01*
G01X349900D01*
G03X349758Y710238I0J-200D01*
G01X349550Y710030D01*
G03X349491Y709888I141J-142D01*
G01Y706452D01*
G02X349432Y706310I-200J0D01*
G01X347371Y704249D01*
G03X347312Y704107I141J-142D01*
G01Y697390D01*
G03X347371Y697248I200J0D01*
G01X348717Y695902D01*
G03X348859Y695843I142J141D01*
G01X372733D01*
G03X372875Y695902I0J200D01*
G01X373842Y696869D01*
G03X373901Y697011I-141J142D01*
G01Y717745D01*
G02X373960Y717887I200J0D01*
G01X374360Y718287D01*
X374388Y718316D01*
X374462Y718346D01*
X381488D01*
G02X381630Y718287I0J-200D01*
G01X381695Y718222D01*
G03X381837Y718163I142J141D01*
G01X388351D01*
G02X388551Y717963I0J-200D01*
G01Y710565D01*
G02X388351Y710365I-200J0D01*
G01X382840D01*
G03X382698Y710306I0J-200D01*
G01X382454Y710062D01*
G03X382395Y709920I141J-142D01*
G01Y706395D01*
G02X382336Y706253I-200J0D01*
G01X380800Y704717D01*
G03X380741Y704575I141J-142D01*
G01Y697781D01*
G03X380800Y697639I200J0D01*
G01X382478Y695961D01*
G03X382620Y695902I142J141D01*
G01X399590D01*
X401344Y694148D01*
X403174D01*
X406118D01*
G03X406260Y694207I0J200D01*
G01X407102Y695049D01*
G03X407161Y695191I-141J142D01*
G01Y697567D01*
G02X407220Y697709I200J0D01*
G01X407672Y698161D01*
G03X407731Y698303I-141J142D01*
G01Y700354D01*
G02X407790Y700496I200J0D01*
G01X407798Y700504D01*
G02X407940Y700563I142J-141D01*
G01X414471D01*
G02X414613Y700504I0J-200D01*
G01X414695Y700422D01*
G03X414837Y700363I142J141D01*
G01X421354D01*
G02X421554Y700163I0J-200D01*
G01Y692765D01*
G02X421354Y692565I-200J0D01*
G01X415930D01*
G03X415788Y692506I0J-200D01*
G01X415554Y692272D01*
G03X415495Y692130I141J-142D01*
G01Y688395D01*
G02X415436Y688253I-200J0D01*
G01X413716Y686533D01*
G03X413657Y686391I141J-142D01*
G01Y668917D01*
G02X413598Y668775I-200J0D01*
G01X405716Y660893D01*
G03X405657Y660751I141J-142D01*
G01Y626345D01*
X403930Y624618D01*
X326600D01*
X322330Y620348D01*
X238807D01*
G02X238665Y620407I0J200D01*
G01X234716Y624356D01*
G02X234657Y624498I141J142D01*
G01Y663041D01*
G02X234716Y663183I200J0D01*
G01X235620Y664087D01*
G02X235762Y664146I142J-141D01*
G01X249897D01*
G02X250039Y664087I0J-200D01*
G01X250095Y664031D01*
G03X250237Y663972I142J141D01*
G01X256748D01*
G02X256890Y663913I0J-200D01*
G01X256895Y663908D01*
G02X256954Y663766I-141J-142D01*
G01Y656374D01*
G02X256754Y656174I-200J0D01*
G01X251450D01*
G03X251308Y656115I0J-200D01*
G01X251010Y655817D01*
G03X250951Y655675I141J-142D01*
G01Y652461D01*
G02X250892Y652319I-200J0D01*
G01X249216Y650643D01*
G03X249157Y650501I141J-142D01*
G01Y639855D01*
G03X249216Y639713I200J0D01*
G01X249842Y639087D01*
G03X249984Y639028I142J141D01*
G01X256268D01*
G03X256410Y639087I0J200D01*
G01X259424Y642101D01*
G02X259566Y642160I142J-141D01*
G01X273116D01*
G03X273258Y642219I0J200D01*
G01X276197Y645159D01*
G03X276256Y645301I-141J142D01*
G01Y671431D01*
G02X276315Y671573I200J0D01*
G01X277434Y672692D01*
G03X277493Y672834I-141J142D01*
G01Y673049D01*
X277496Y673052D01*
Y678933D01*
G03X277437Y679075I-200J0D01*
G01X276190Y680322D01*
X276185D01*
X275216Y681291D01*
G02X275157Y681433I141J142D01*
G01Y697663D01*
G02X275216Y697805I200J0D01*
G01X275698Y698287D01*
X275726Y698316D01*
X275800Y698346D01*
X282668D01*
G02X282810Y698287I0J-200D01*
G01X282825Y698272D01*
G03X282967Y698213I142J141D01*
G01X289484D01*
G02X289684Y698013I0J-200D01*
G01Y690615D01*
G02X289484Y690415I-200J0D01*
G01X284260D01*
G03X284118Y690356I0J-200D01*
G01X283700Y689938D01*
G03X283641Y689796I141J-142D01*
G01Y685213D01*
G02X283582Y685071I-200J0D01*
G01X281690Y683179D01*
G03X281631Y683037I141J-142D01*
G01Y676828D01*
G03X281690Y676686I200J0D01*
G01X283208Y675168D01*
X283237Y675140D01*
X283267Y675066D01*
Y672908D01*
G03X283326Y672766I200J0D01*
G01X283896Y672196D01*
G03X284038Y672137I142J141D01*
G01X289137D01*
G03X289279Y672196I0J200D01*
G01X292809Y675726D01*
G02X292951Y675785I142J-141D01*
G01X305461D01*
G03X305603Y675844I0J200D01*
G01X308098Y678339D01*
G03X308157Y678481I-141J142D01*
G01Y705141D01*
G02X308216Y705283I200J0D01*
G01X310167Y707234D01*
G03X310226Y707376I-141J142D01*
G01Y713174D01*
G03X310167Y713316I-200J0D01*
G01X308216Y715267D01*
G02X308157Y715409I141J142D01*
G01Y718063D01*
G02X308216Y718205I200J0D01*
G01X308515Y718504D01*
X308543Y718533D01*
X308617Y718563D01*
G37*
G36*
G01X442101Y793900D02*
Y747988D01*
X440950Y746837D01*
X435810D01*
G02X435668Y746778I-142J141D01*
G01X412927D01*
G02X412785Y746837I0J200D01*
G01X411216Y748406D01*
G02X411157Y748548I141J142D01*
G01Y759841D01*
G03X411098Y759983I-200J0D01*
G01X405767Y765314D01*
G03X405625Y765373I-142J-141D01*
G01X314124D01*
G03X313982Y765314I0J-200D01*
G01X312591Y763923D01*
Y757728D01*
X311773Y756910D01*
X305579D01*
X302216Y753548D01*
G03X302157Y753406I141J-142D01*
G01Y745998D01*
G02X302098Y745856I-200J0D01*
G01X301716Y745474D01*
G02X301574Y745415I-142J141D01*
G01X280740D01*
G03X280598Y745356I0J-200D01*
G01X279781Y744539D01*
Y737668D01*
X278967Y736854D01*
X272095D01*
X267016Y731774D01*
G03X266957Y731632I141J-142D01*
G01Y711798D01*
G02X266898Y711656I-200J0D01*
G01X266516Y711274D01*
G02X266374Y711215I-142J141D01*
G01X243940D01*
G02X243798Y711274I0J200D01*
G01X243074Y711998D01*
G02X243015Y712140I141J142D01*
G01Y713352D01*
G03X242956Y713494I-200J0D01*
G01X242243Y714207D01*
G03X242101Y714266I-142J-141D01*
G01X234871D01*
X234335Y714802D01*
Y725472D01*
X240331Y731468D01*
X303382Y794518D01*
X441483D01*
X442101Y793900D01*
G37*
G36*
G01X260291Y1334284D02*
Y1313483D01*
X260269Y1313461D01*
Y1311649D01*
X258847Y1310227D01*
Y1305481D01*
X260291Y1304037D01*
Y1302523D01*
Y1296978D01*
X266901Y1290368D01*
Y1282928D01*
X268121Y1281708D01*
X286711D01*
X287411Y1281008D01*
Y1275148D01*
X287155Y1274892D01*
X267452D01*
X254143Y1288201D01*
Y1327734D01*
X253093Y1328784D01*
X235061D01*
X234619Y1329226D01*
Y1335131D01*
X235271Y1335784D01*
X258791D01*
X260291Y1334284D01*
G37*
G36*
G01X266175Y1393727D02*
X311236D01*
G02X311378Y1393668I0J-200D01*
G01X321191Y1383855D01*
G03X321333Y1383796I142J141D01*
G01X331769D01*
G02X331911Y1383737I0J-200D01*
G01X341589Y1374059D01*
G03X341731Y1374000I142J141D01*
G01X407443D01*
X408894Y1372549D01*
X410464Y1370978D01*
X411090Y1370352D01*
X420648D01*
X427931Y1363069D01*
G02X427990Y1362927I-141J-142D01*
G01Y1339584D01*
G02X427790Y1339384I-200J0D01*
G01X410334D01*
X410260Y1339414D01*
X410232Y1339443D01*
X409946Y1339729D01*
G02X409887Y1339871I141J142D01*
G01Y1347298D01*
G02X410087Y1347498I200J0D01*
G01X415333D01*
G03X415475Y1347557I0J200D01*
G01X415984Y1348066D01*
G03X416043Y1348208I-141J142D01*
G01Y1352704D01*
G02X416100Y1352844I200J0D01*
G01X416101Y1352845D01*
X417059Y1353803D01*
G03X417118Y1353945I-141J142D01*
G01Y1359324D01*
G03X417059Y1359466I-200J0D01*
G01X414737Y1361788D01*
G03X414595Y1361847I-142J-141D01*
G01X393946D01*
G03X393804Y1361788I0J-200D01*
G01X391718Y1359702D01*
G03X391659Y1359560I141J-142D01*
G01Y1334694D01*
X391629Y1334620D01*
X391600Y1334592D01*
X389401Y1332393D01*
G03X389342Y1332251I141J-142D01*
G01Y1324511D01*
G03X389401Y1324369I200J0D01*
G01X391202Y1322568D01*
G02X391261Y1322426I-141J-142D01*
G01Y1320269D01*
X391231Y1320195D01*
X391202Y1320167D01*
X391152Y1320117D01*
Y1320115D01*
X391077Y1320040D01*
G02X390935Y1319981I-142J141D01*
G01X377575D01*
X377501Y1320011D01*
X377473Y1320040D01*
X377364Y1320149D01*
G02X377305Y1320291I141J142D01*
G01Y1327737D01*
G02X377486Y1327910I196J-23D01*
G01X382343D01*
G03X382485Y1327969I0J200D01*
G01X383428Y1328912D01*
G03X383487Y1329054I-141J142D01*
G01Y1331937D01*
G02X383544Y1332077I200J0D01*
G01X383545Y1332078D01*
X385002Y1333535D01*
G03X385061Y1333677I-141J142D01*
G01Y1340333D01*
G03X385002Y1340475I-200J0D01*
G01X383196Y1342281D01*
G03X383054Y1342340I-142J-141D01*
G01X361313D01*
G03X361171Y1342281I0J-200D01*
G01X358668Y1339778D01*
G03X358609Y1339636I141J-142D01*
G01Y1320217D01*
X358579Y1320143D01*
X358550Y1320115D01*
X358284Y1319849D01*
G02X358142Y1319790I-142J141D01*
G01X344776D01*
X344702Y1319820D01*
X344674Y1319849D01*
X344564Y1319959D01*
G02X344505Y1320101I141J142D01*
G01Y1327537D01*
G02X344686Y1327710I196J-23D01*
G01X349704D01*
G03X349846Y1327769I0J200D01*
G01X350643Y1328566D01*
G03X350702Y1328708I-141J142D01*
G01Y1331752D01*
G02X350759Y1331892I200J0D01*
G01X350760Y1331893D01*
X351965Y1333098D01*
G03X352023Y1333237I-139J140D01*
G01Y1340274D01*
G03X351964Y1340416I-200J0D01*
G01X350309Y1342071D01*
G03X350167Y1342130I-142J-141D01*
G01X329023D01*
G03X328881Y1342071I0J-200D01*
G01X325768Y1338958D01*
G03X325709Y1338816I141J-142D01*
G01Y1320336D01*
X325679Y1320262D01*
X325650Y1320234D01*
X325347Y1319931D01*
G02X325205Y1319872I-142J141D01*
G01X311826D01*
X311752Y1319902D01*
X311724Y1319931D01*
X311625Y1320030D01*
Y1320031D01*
X311601Y1320055D01*
Y1327595D01*
G02X311772Y1327766I196J-25D01*
G01X316770D01*
G03X316912Y1327825I0J200D01*
G01X317709Y1328622D01*
G03X317768Y1328764I-141J142D01*
G01Y1331779D01*
G02X317825Y1331919I200J0D01*
G01X317826Y1331920D01*
X319061Y1333155D01*
G03X319119Y1333294I-139J140D01*
G01Y1340398D01*
G03X319060Y1340540I-200J0D01*
G01X317249Y1342351D01*
G03X317107Y1342410I-142J-141D01*
G01X296413D01*
G03X296271Y1342351I0J-200D01*
G01X293240Y1339320D01*
G03X293181Y1339178I141J-142D01*
G01Y1320491D01*
X293151Y1320417D01*
X293122Y1320389D01*
X292598Y1319865D01*
G02X292456Y1319806I-142J141D01*
G01X279068D01*
X278994Y1319836D01*
X278966Y1319865D01*
X278764Y1320067D01*
G02X278705Y1320209I141J142D01*
G01Y1327623D01*
G02X278876Y1327794I195J-24D01*
G01X284359D01*
G03X284501Y1327853I0J200D01*
G01X284807Y1328159D01*
G03X284866Y1328301I-141J142D01*
G01Y1332070D01*
G02X284923Y1332210I200J0D01*
G01X284924Y1332211D01*
X286303Y1333590D01*
G03X286361Y1333729I-139J140D01*
G01Y1348442D01*
G02X286418Y1348582I200J0D01*
G01X286419Y1348583D01*
X289724Y1351888D01*
G03X289783Y1352030I-141J142D01*
G01Y1363153D01*
G03X289724Y1363295I-200J0D01*
G01X282361Y1370658D01*
G03X282219Y1370717I-142J-141D01*
G01X269023D01*
G03X268881Y1370658I0J-200D01*
G01X264416Y1366193D01*
G02X264274Y1366134I-142J141D01*
G01X245404D01*
X245330Y1366164D01*
X245302Y1366193D01*
X245164Y1366331D01*
G02X245105Y1366473I141J142D01*
G01Y1373661D01*
G02X245162Y1373801I200J0D01*
G01X245163Y1373802D01*
X245316Y1373955D01*
G02X245318Y1373957I142J-140D01*
G02X245458Y1374014I140J-143D01*
G01X250418D01*
G03X250560Y1374073I0J200D01*
G01X250969Y1374482D01*
Y1374527D01*
X251247Y1374805D01*
G03X251306Y1374947I-141J142D01*
G01Y1379081D01*
G02X251363Y1379221I200J0D01*
G01X251364Y1379222D01*
X253262Y1381120D01*
G02X253404Y1381179I142J-141D01*
G01X253461D01*
G03X253603Y1381238I0J200D01*
G01X266033Y1393668D01*
G02X266175Y1393727I142J-141D01*
G37*
G36*
G01X234260Y1450295D02*
G03I-519J0D01*
G37*
G36*
G01X236170Y1452895D02*
G03I-519J0D01*
G37*
G36*
G01X234260Y1455495D02*
G03I-519J0D01*
G37*
G36*
G01X242880Y1474895D02*
G03I-519J0D01*
G37*
G36*
G01X240970Y1472295D02*
G03I-519J0D01*
G37*
G36*
G01X242880Y1469695D02*
G03I-519J0D01*
G37*
G36*
G01X257028Y1527011D02*
X258004D01*
G02X258110Y1526981I1J-200D01*
G01X258382Y1526810D01*
G02X258418Y1526782I-104J-171D01*
G01X258483Y1526717D01*
G02X258542Y1526575I-141J-142D01*
G01Y1523591D01*
G02X258483Y1523449I-200J0D01*
G01X258399Y1523365D01*
G02X258257Y1523306I-142J141D01*
G01X256762D01*
G02X256692Y1523319I1J200D01*
G01X255921Y1523607D01*
G03X255396Y1523702I-526J-1407D01*
G03X254999Y1523648I2J-1502D01*
G01X253778Y1523313D01*
G02X253725Y1523306I-52J193D01*
G01X252038D01*
G02X251968Y1523319I1J200D01*
G01X251197Y1523607D01*
G03X250672Y1523702I-526J-1407D01*
G03X250275Y1523648I2J-1502D01*
G01X249053Y1523313D01*
G02X249000Y1523306I-52J193D01*
G01X247313D01*
G02X247243Y1523319I1J200D01*
G01X246472Y1523607D01*
G03X245947Y1523702I-526J-1407D01*
G03X245550Y1523648I2J-1502D01*
G01X244329Y1523313D01*
G02X244276Y1523306I-52J193D01*
G01X242589D01*
G02X242519Y1523319I1J200D01*
G01X241748Y1523607D01*
G03X241223Y1523702I-526J-1407D01*
G03X241173Y1523701I5J-1502D01*
G01X241132Y1523699D01*
X241056Y1523728D01*
X240820Y1523957D01*
G02X240760Y1524100I140J143D01*
G01Y1526206D01*
G02X240820Y1526349I200J0D01*
G01X241056Y1526578D01*
X241132Y1526607D01*
X241173Y1526605D01*
G03X241223Y1526604I55J1501D01*
G03X241645Y1526665I-2J1502D01*
G01X242799Y1527003D01*
G02X242855Y1527011I56J-192D01*
G01X244480D01*
G02X244545Y1527000I0J-200D01*
G01X245459Y1526686D01*
G03X245947Y1526604I489J1420D01*
G03X246369Y1526665I-2J1502D01*
G01X247523Y1527003D01*
G02X247579Y1527011I56J-192D01*
G01X249205D01*
G02X249270Y1527000I0J-200D01*
G01X250184Y1526686D01*
G03X250672Y1526604I489J1420D01*
G03X251094Y1526665I-2J1502D01*
G01X252248Y1527003D01*
G02X252304Y1527011I56J-192D01*
G01X253929D01*
G02X253994Y1527000I0J-200D01*
G01X254908Y1526686D01*
G03X255396Y1526604I489J1420D01*
G03X255818Y1526665I-2J1502D01*
G01X256972Y1527003D01*
G02X257028Y1527011I56J-192D01*
G37*
G36*
G01X238130D02*
X239354D01*
G02X239496Y1526952I0J-200D01*
G01X239699Y1526749D01*
G02X239758Y1526607I-141J-142D01*
G01Y1523980D01*
G02X239699Y1523838I-200J0D01*
G01X239226Y1523365D01*
G02X239084Y1523306I-142J141D01*
G01X237864D01*
G02X237794Y1523319I1J200D01*
G01X237023Y1523607D01*
G03X236498Y1523702I-526J-1407D01*
G03X236221Y1523676I1J-1502D01*
G01X236172Y1523666D01*
X236077Y1523696D01*
X235951Y1523822D01*
G02X235892Y1523963I141J142D01*
G01Y1526216D01*
G02X235959Y1526365I200J0D01*
G01X236213Y1526592D01*
X236293Y1526618D01*
X236336Y1526613D01*
G03X236498Y1526604I164J1493D01*
G03X236920Y1526665I-2J1502D01*
G01X238074Y1527003D01*
G02X238130Y1527011I56J-192D01*
G37*
G36*
G01X233406D02*
X234355D01*
G02X234497Y1526952I0J-200D01*
G01X234832Y1526617D01*
G02X234891Y1526475I-141J-142D01*
G01Y1523832D01*
G02X234832Y1523690I-200J0D01*
G01X234507Y1523365D01*
G02X234365Y1523306I-142J141D01*
G01X233140D01*
G02X233070Y1523319I1J200D01*
G01X232299Y1523607D01*
G03X231774Y1523702I-526J-1407D01*
G03X231513Y1523679I0J-1492D01*
G01X231465Y1523670D01*
X231372Y1523699D01*
X231251Y1523820D01*
G02X231192Y1523962I141J142D01*
G01Y1526338D01*
G02X231251Y1526480I200J0D01*
G01X231377Y1526606D01*
X231468Y1526635D01*
X231518Y1526627D01*
G03X231774Y1526604I262J1478D01*
G03X232196Y1526665I-2J1502D01*
G01X233350Y1527003D01*
G02X233406Y1527011I56J-192D01*
G37*
G36*
G01X267767Y1587647D02*
Y1571493D01*
G02X267708Y1571351I-200J0D01*
G01X266966Y1570609D01*
G02X266824Y1570550I-142J141D01*
G01X235870D01*
G02X235728Y1570609I0J200D01*
G01X233836Y1572501D01*
G02X233777Y1572643I141J142D01*
G01Y1587177D01*
G02X233836Y1587319I200J0D01*
G01X234578Y1588061D01*
G02X234720Y1588120I142J-141D01*
G01X267294D01*
G02X267436Y1588061I0J-200D01*
G01X267708Y1587789D01*
G02X267767Y1587647I-141J-142D01*
G37*
G36*
G01X235136Y1616788D02*
G03I-582J0D01*
G37*
G36*
G01X258772Y35575D02*
X260633D01*
G02X260775Y35516I0J-200D01*
G01X261587Y34704D01*
G02X261646Y34562I-141J-142D01*
G01Y26518D01*
G02X261587Y26376I-200J0D01*
G01X261405Y26194D01*
G02X261263Y26135I-142J141D01*
G01X249619D01*
G02X249477Y26194I0J200D01*
G01X246735Y28936D01*
G02X246676Y29078I141J142D01*
G01Y35422D01*
G02X246735Y35564I200J0D01*
G01X246746Y35575D01*
X248056D01*
G02X248254Y35399I0J-199D01*
G01Y29905D01*
X248457Y29702D01*
X248921D01*
X249124Y29905D01*
Y35399D01*
G02X249322Y35575I198J-23D01*
G01X250418D01*
G02X250616Y35399I0J-199D01*
G01Y29905D01*
X250819Y29702D01*
X251283D01*
X251486Y29905D01*
Y35399D01*
G02X251684Y35575I198J-23D01*
G01X252780D01*
G02X252978Y35399I0J-199D01*
G01Y29905D01*
X253181Y29702D01*
X253645D01*
X253848Y29905D01*
Y35399D01*
G02X254046Y35575I198J-23D01*
G01X255142D01*
G02X255340Y35399I0J-199D01*
G01Y29905D01*
X255543Y29702D01*
X256007D01*
X256210Y29905D01*
Y35399D01*
G02X256408Y35575I198J-23D01*
G01X257504D01*
G02X257704Y35389I0J-201D01*
G01Y29905D01*
X257906Y29702D01*
X258370D01*
X258572Y29905D01*
Y35389D01*
G02X258772Y35575I200J-15D01*
G37*
G36*
G01X277259Y57893D02*
Y53508D01*
X269700Y45950D01*
X265215Y41465D01*
X260635D01*
X258772D01*
G02X258572Y41651I0J201D01*
G01Y47221D01*
X258370Y47424D01*
X257906D01*
X257704Y47221D01*
Y41651D01*
G02X257504Y41465I-200J15D01*
G01X256410D01*
G02X256210Y41651I0J201D01*
G01Y47221D01*
X256008Y47424D01*
X255544D01*
X255342Y47221D01*
Y41651D01*
G02X255142Y41465I-200J15D01*
G01X254046D01*
G02X253848Y41641I0J199D01*
G01Y47221D01*
X253645Y47424D01*
X253181D01*
X252978Y47221D01*
Y41641D01*
G02X252780Y41465I-198J23D01*
G01X251684D01*
G02X251486Y41641I0J199D01*
G01Y47221D01*
X251283Y47424D01*
X250819D01*
X250616Y47221D01*
Y41641D01*
G02X250418Y41465I-198J23D01*
G01X249322D01*
G02X249124Y41641I0J199D01*
G01Y47221D01*
X248921Y47424D01*
X248457D01*
X248254Y47221D01*
Y41641D01*
G02X248056Y41465I-198J23D01*
G01X247842D01*
G02X247700Y41524I0J200D01*
G01X246875Y42349D01*
G02X246816Y42491I141J142D01*
G01Y50282D01*
G02X246820Y50319I200J-3D01*
G01Y50321D01*
G02X246873Y50422I196J-39D01*
G01X248811Y52360D01*
X257196D01*
X257890Y53054D01*
Y70108D01*
X258343Y70561D01*
X258569Y70787D01*
X276189D01*
X277259Y69717D01*
Y62195D01*
Y57893D01*
G37*
G36*
G01X260105Y105916D02*
X274721D01*
G02X274797Y105901I0J-200D01*
G01X274833Y105886D01*
X274843Y105876D01*
Y98017D01*
G03X274847Y97977I200J0D01*
G01X274852Y97957D01*
Y97734D01*
X274882Y97661D01*
X274910Y97633D01*
X276979Y95563D01*
G03X276986Y95556I145J138D01*
G01X276988Y95555D01*
G03X276992Y95551I143J139D01*
G01X277008Y95535D01*
X277081Y95504D01*
X286795D01*
G02X286912Y95447I-24J-198D01*
G01X289296Y93063D01*
G02X289349Y92962I-143J-140D01*
G01Y92960D01*
G02X289353Y92923I-196J-40D01*
G01Y73050D01*
X290033Y72370D01*
X293199D01*
X294647Y70922D01*
Y65832D01*
X294873Y65606D01*
X302718D01*
X303517Y66405D01*
X306652D01*
X307541Y67294D01*
X307575Y67309D01*
G03X307942Y67560I-489J1109D01*
G01X311568Y71186D01*
G03X311819Y71553I-858J856D01*
G01X311834Y71587D01*
X311864Y71617D01*
G03X311923Y71759I-141J142D01*
G01Y75576D01*
X311927Y75596D01*
G03X311957Y75866I-1472J300D01*
G01Y75895D01*
G03X311927Y76194I-1502J0D01*
G01X311923Y76214D01*
Y84632D01*
X312159Y84868D01*
X312481D01*
X312506Y84893D01*
X312883Y84516D01*
Y77439D01*
G03X312942Y77297I200J0D01*
G01X313544Y76695D01*
G03X313686Y76636I142J141D01*
G01X315090D01*
G03X315232Y76695I0J200D01*
G01X315815Y77278D01*
G03X315858Y77343I-142J141D01*
G01X315873Y77379D01*
Y77405D01*
G02X315890Y77486I200J0D01*
G01Y82642D01*
X316153Y82905D01*
X316565D01*
X316828Y82642D01*
Y77397D01*
X317869Y76356D01*
X317911Y76303D01*
G02X317942Y76246I-158J-123D01*
G01X317953Y76214D01*
Y56939D01*
X317433Y56419D01*
X301114D01*
X300046Y57487D01*
X282703D01*
X281867Y58323D01*
Y60108D01*
Y71419D01*
X280788Y72498D01*
Y83357D01*
X279130Y85015D01*
X272163D01*
X269473D01*
X268567Y84109D01*
Y73676D01*
X267389Y72498D01*
X259429D01*
X257107D01*
X256850Y72755D01*
Y81487D01*
X257504Y82141D01*
X259475D01*
X260016Y82682D01*
G02X260020Y82719I200J-3D01*
G01Y82721D01*
G02X260073Y82822I196J-39D01*
G01X260157Y82906D01*
G03X260216Y83048I-141J142D01*
G01Y85890D01*
G03X260157Y86032I-200J0D01*
G01X260061Y86128D01*
G02X260054Y86135I138J145D01*
G01Y105775D01*
G02X260078Y105870I200J0D01*
G01X260101Y105913D01*
X260105Y105916D01*
G37*
G36*
G01X246318Y105768D02*
X248662D01*
X248887Y105543D01*
Y94952D01*
X249693Y94146D01*
X253093D01*
X253393Y93846D01*
Y90846D01*
X252893Y90346D01*
X247993D01*
X246093Y92246D01*
Y105543D01*
X246318Y105768D01*
G37*
G36*
G01X259053Y86496D02*
Y105896D01*
X257653D01*
X257353Y105596D01*
Y101363D01*
X255553Y99563D01*
Y86996D01*
X256153Y86396D01*
X258953D01*
X259053Y86496D01*
G37*
G36*
G01X250130Y105768D02*
X253242D01*
X253493Y105517D01*
Y96346D01*
X252993Y95846D01*
X250093D01*
X249887Y96052D01*
Y105525D01*
X250130Y105768D01*
G37*
G36*
G01X310051Y80025D02*
X310681D01*
X310918Y80262D01*
Y85006D01*
Y85403D01*
X311467Y85952D01*
X313365D01*
X313983Y85334D01*
Y85006D01*
Y78363D01*
X314268Y78078D01*
X314610D01*
X314886Y78354D01*
Y111642D01*
X309528Y117000D01*
X282282D01*
X277609Y112327D01*
X259916D01*
X259640Y112051D01*
Y108002D01*
X260291Y107351D01*
X276114D01*
X280342Y103123D01*
X294994D01*
X300301Y97816D01*
X308352D01*
X308354Y97814D01*
X309367D01*
X309939Y97242D01*
X309960Y96220D01*
Y80116D01*
X310051Y80025D01*
G37*
G36*
G01X249566Y117115D02*
X258626D01*
X258986Y116755D01*
Y114165D01*
X258616Y113795D01*
X250156D01*
X249296Y114655D01*
Y116845D01*
X249566Y117115D01*
G37*
G36*
G01X252293Y126146D02*
X262393D01*
X262693Y126446D01*
Y128946D01*
X263293Y129546D01*
X269193D01*
X270293Y128446D01*
Y126246D01*
X270793Y125746D01*
X273100D01*
X273600Y126246D01*
Y134546D01*
X272900Y135246D01*
X252993D01*
X249493D01*
X248933Y134686D01*
Y126486D01*
X249273Y126146D01*
X252293D01*
G37*
G36*
G01X271642Y675323D02*
X249227D01*
X248936Y675614D01*
Y689808D01*
X249058Y689930D01*
X266775D01*
X267005Y689700D01*
Y680793D01*
X269563Y678235D01*
X272350D01*
X272486Y678099D01*
Y676167D01*
X271642Y675323D01*
G37*
G36*
G01X300457Y734742D02*
X300657Y734542D01*
Y728764D01*
X300321Y728428D01*
X279439D01*
X274157Y723146D01*
Y705646D01*
X271360Y702849D01*
X249916D01*
X249157Y703608D01*
Y708646D01*
X249464Y708953D01*
X267242D01*
X267417D01*
X269154Y710690D01*
Y730412D01*
X273484Y734742D01*
X300457D01*
G37*
G36*
G01X262073Y1305652D02*
X260908D01*
X260296D01*
X260163Y1305785D01*
Y1310089D01*
X260780Y1310706D01*
X261633Y1311559D01*
X263680D01*
X263851Y1311388D01*
Y1309947D01*
X262177Y1308273D01*
Y1307880D01*
Y1305756D01*
X262073Y1305652D01*
G37*
G36*
G01X247670Y1462595D02*
G03I-519J0D01*
G37*
G36*
G01X249580Y1459995D02*
G03I-519J0D01*
G37*
G36*
G01X254360D02*
G03I-519J0D01*
G37*
G36*
G01X256270Y1462595D02*
G03I-519J0D01*
G37*
G36*
G01X256280Y1455495D02*
G03I-519J0D01*
G37*
G36*
G01X261060D02*
G03I-519J0D01*
G37*
G36*
G01X254370Y1452895D02*
G03I-519J0D01*
G37*
G36*
G01X256280Y1450295D02*
G03I-519J0D01*
G37*
G36*
G01X261060D02*
G03I-519J0D01*
G37*
G36*
G01X247660Y1469695D02*
G03I-519J0D01*
G37*
G36*
G01D02*
G03I-519J0D01*
G37*
G36*
G01Y1474895D02*
G03I-519J0D01*
G37*
G36*
G01X249570Y1472295D02*
G03I-519J0D01*
G37*
G36*
G01X249580Y1465195D02*
G03I-519J0D01*
G37*
G36*
G01X254360D02*
G03I-519J0D01*
G37*
G36*
G01X259192Y1616788D02*
G03I-518J0D01*
G37*
G36*
G01X273316Y27185D02*
G03I-720J0D01*
G37*
G36*
G01X272316Y40165D02*
G03I-720J0D01*
G37*
G36*
G01X272752Y523076D02*
G03I-510J0D01*
G37*
G36*
G01X261278Y596000D02*
Y594100D01*
X261478Y593900D01*
X265878D01*
X266178Y594200D01*
Y595900D01*
X265940Y596138D01*
X261416D01*
X261278Y596000D01*
G37*
G36*
G01X271005Y599235D02*
X275088D01*
X277229Y601376D01*
X277238D01*
X277954Y602092D01*
X277961D01*
X278247Y602378D01*
X317061D01*
X323430D01*
X325163D01*
X325687Y601854D01*
Y592191D01*
X325074Y591578D01*
X322710D01*
X316811D01*
X312561D01*
X297351D01*
X293500D01*
X290771Y594307D01*
X286860D01*
X283601Y597567D01*
X264307D01*
X263898Y597158D01*
X261520D01*
X261278Y597400D01*
Y599000D01*
X261513Y599235D01*
X271005D01*
G37*
G36*
G01X264482Y592178D02*
X264483D01*
X266319D01*
G03X266459Y592236I0J197D01*
G01X267543Y593320D01*
G03X267601Y593460I-139J140D01*
G01Y595368D01*
G02X267798Y595566I197J1D01*
G01X268731D01*
X268879Y595418D01*
Y594223D01*
Y593151D01*
G02X268853Y593052I-197J-1D01*
G01X267611Y590897D01*
G02X267580Y590857I-170J100D01*
G01X266816Y590093D01*
X263561D01*
X262806D01*
Y592081D01*
X262903Y592178D01*
X264482D01*
G37*
G36*
G01X264001Y588787D02*
X262876D01*
X262854Y588765D01*
Y583110D01*
X263125Y582839D01*
X264723D01*
X264813Y582929D01*
X264872Y582988D01*
Y588773D01*
X264858Y588787D01*
X264001D01*
G37*
G36*
G01X273730Y678319D02*
X274748D01*
X275360D01*
X275493Y678186D01*
Y673882D01*
X274876Y673265D01*
X274023Y672412D01*
X271976D01*
X271805Y672583D01*
Y674024D01*
X273479Y675698D01*
X273507Y675726D01*
Y678096D01*
X273730Y678319D01*
G37*
G36*
G01X288693Y1019214D02*
G02I-13780J0D01*
G37*
G36*
G01X436740Y1361250D02*
X442677D01*
X453750D01*
X455584Y1359416D01*
Y1348386D01*
G02X455643Y1348244I-141J-142D01*
G01Y1311450D01*
X455613Y1311376D01*
X455584Y1311348D01*
X454520Y1310284D01*
G02X454378Y1310225I-142J141D01*
G01X398743D01*
G03X398601Y1310166I0J-200D01*
G01X396881Y1308446D01*
G03X396822Y1308304I141J-142D01*
G01Y1302349D01*
X396792Y1302275D01*
X396763Y1302247D01*
X396282Y1301766D01*
G02X396140Y1301707I-142J141D01*
G01X393163D01*
G03X393021Y1301648I0J-200D01*
G01X389856Y1298483D01*
Y1293444D01*
X387185Y1290773D01*
G02X387043Y1290714I-142J141D01*
G01X268435D01*
X268361Y1290744D01*
X268333Y1290773D01*
X262429Y1296676D01*
X261490Y1297615D01*
G02X261431Y1297757I141J142D01*
G01Y1303210D01*
X261461Y1303284D01*
X261490Y1303312D01*
X262372Y1304194D01*
G02X262514Y1304253I142J-141D01*
G01X266119D01*
X266193Y1304223D01*
X266221Y1304194D01*
X267470Y1302945D01*
G02X267529Y1302803I-141J-142D01*
G01Y1293988D01*
G03X267588Y1293846I200J0D01*
G01X268334Y1293100D01*
G03X268476Y1293041I142J141D01*
G01X287040D01*
G03X287182Y1293100I0J200D01*
G01X287661Y1293579D01*
G03X287720Y1293721I-141J142D01*
G01Y1309423D01*
X286945Y1310198D01*
X266615D01*
X266541Y1310228D01*
X266513Y1310257D01*
X264270Y1312500D01*
G03X264128Y1312559I-142J-141D01*
G01X261631D01*
G02X261431Y1312759I0J200D01*
G01Y1317357D01*
X261461Y1317431D01*
X261490Y1317459D01*
X261672Y1317641D01*
G02X261814Y1317700I142J-141D01*
G01X265507D01*
X267410Y1315797D01*
X273407D01*
G03X273607Y1315997I0J200D01*
G01Y1318493D01*
G03X273548Y1318635I-200J0D01*
G01X272253Y1319930D01*
X270258D01*
X270073Y1320115D01*
Y1320129D01*
X269942Y1320260D01*
G03X269800Y1320319I-142J-141D01*
G01X266976D01*
X266902Y1320349D01*
X266874Y1320378D01*
X266792Y1320460D01*
G02X266733Y1320602I141J142D01*
G01Y1321019D01*
G02X266933Y1321219I200J0D01*
G01X268943D01*
X268953Y1321209D01*
X270004D01*
G03X270146Y1321268I0J200D01*
G01X270258Y1321380D01*
G03X270317Y1321522I-141J142D01*
G01Y1321909D01*
X270325Y1321929D01*
Y1325247D01*
X270317Y1325268D01*
Y1325346D01*
G03X270258Y1325488I-200J0D01*
G01X270193Y1325553D01*
Y1325559D01*
X270173Y1325579D01*
X270137Y1325594D01*
G03X270120Y1325600I-75J-185D01*
G01X270077Y1325643D01*
X266862D01*
G02X266773Y1325809I112J167D01*
G01Y1326366D01*
X266803Y1326440D01*
X266832Y1326468D01*
X266844Y1326480D01*
X266872Y1326509D01*
X270064D01*
X270094Y1326539D01*
G03X270236Y1326598I0J200D01*
G01X270258Y1326620D01*
G03X270317Y1326762I-141J142D01*
G01Y1326909D01*
X270325Y1326929D01*
Y1327624D01*
G02X270341Y1327701I200J-1D01*
G01X270385Y1327806D01*
X270438Y1327859D01*
G02X270504Y1327903I142J-141D01*
G01X270578Y1327933D01*
X270624Y1327920D01*
G03X270882Y1327857I722J2395D01*
G03X271337Y1327813I467J2458D01*
G01X271362D01*
G03X272121Y1327936I-16J2502D01*
G01X272152Y1327946D01*
X277203D01*
X277290Y1327859D01*
Y1319900D01*
X278580Y1318610D01*
X287747D01*
X287940Y1318803D01*
X292459D01*
G03X292527Y1318805I-1J1200D01*
G01X292861D01*
X292935Y1318775D01*
X292963Y1318746D01*
X293283Y1318426D01*
G03X293425Y1318367I142J141D01*
G01X297742D01*
X300332Y1315777D01*
X306307D01*
G03X306507Y1315977I0J200D01*
G01Y1318449D01*
G03X306448Y1318591I-200J0D01*
G01X305255Y1319784D01*
G03X305113Y1319843I-142J-141D01*
G01X303256D01*
X303182Y1319873D01*
X303154Y1319902D01*
X302969Y1320087D01*
Y1320101D01*
X302838Y1320232D01*
G03X302696Y1320291I-142J-141D01*
G01X299872D01*
X299798Y1320321D01*
X299770Y1320350D01*
X299688Y1320432D01*
G02X299629Y1320574I141J142D01*
G01Y1320991D01*
G02X299829Y1321191I200J0D01*
G01X301839D01*
X301849Y1321181D01*
X302900D01*
G03X303042Y1321240I0J200D01*
G01X303154Y1321352D01*
G03X303213Y1321494I-141J142D01*
G01Y1321881D01*
X303221Y1321901D01*
Y1325219D01*
X303213Y1325240D01*
Y1325318D01*
G03X303154Y1325460I-200J0D01*
G01X303089Y1325525D01*
Y1325531D01*
X303069Y1325551D01*
X303033Y1325566D01*
G03X302957Y1325581I-76J-185D01*
G01X302921Y1325617D01*
X299755D01*
X299704Y1325668D01*
G02X299669Y1325781I165J113D01*
G01Y1326338D01*
X299699Y1326412D01*
X299728Y1326440D01*
X299740Y1326452D01*
X299768Y1326481D01*
X299812Y1326499D01*
X302978D01*
X302990Y1326511D01*
G03X303132Y1326570I0J200D01*
G01X303154Y1326592D01*
G03X303213Y1326734I-141J142D01*
G01Y1326881D01*
X303221Y1326901D01*
Y1327596D01*
G02X303237Y1327673I200J-1D01*
G01X303281Y1327778D01*
X303334Y1327831D01*
G02X303400Y1327875I142J-141D01*
G01X303474Y1327905D01*
X303520Y1327892D01*
G03X303778Y1327829I722J2395D01*
G03X304233Y1327785I467J2458D01*
G01X304258D01*
G03X305017Y1327908I-16J2502D01*
G01X305048Y1327918D01*
X310012D01*
X310240Y1327690D01*
Y1319780D01*
X311460Y1318560D01*
X320258D01*
X320570Y1318872D01*
X325677D01*
X326163Y1318386D01*
G03X326305Y1318327I142J141D01*
G01X330630D01*
X333245Y1315712D01*
X339202D01*
G03X339402Y1315912I0J200D01*
G01Y1318448D01*
X338005Y1319845D01*
X336058D01*
X335873Y1320030D01*
Y1320044D01*
X335742Y1320175D01*
G03X335600Y1320234I-142J-141D01*
G01X332776D01*
X332702Y1320264D01*
X332674Y1320293D01*
X332592Y1320375D01*
G02X332533Y1320517I141J142D01*
G01Y1320934D01*
G02X332733Y1321134I200J0D01*
G01X334743D01*
X334753Y1321124D01*
X335804D01*
G03X335946Y1321183I0J200D01*
G01X336058Y1321295D01*
G03X336117Y1321437I-141J142D01*
G01Y1321824D01*
X336125Y1321844D01*
Y1325162D01*
X336117Y1325183D01*
Y1325261D01*
G03X336058Y1325403I-200J0D01*
G01X335993Y1325468D01*
Y1325474D01*
X335973Y1325494D01*
X335937Y1325509D01*
G03X335861Y1325524I-76J-185D01*
G01X335484D01*
X335449Y1325559D01*
X332660D01*
G02X332573Y1325724I113J165D01*
G01Y1326281D01*
X332603Y1326355D01*
X332632Y1326383D01*
X332644Y1326395D01*
X332672Y1326424D01*
X332719Y1326443D01*
X335883D01*
X335894Y1326454D01*
G03X336036Y1326513I0J200D01*
G01X336058Y1326535D01*
G03X336117Y1326677I-141J142D01*
G01Y1326824D01*
X336125Y1326844D01*
Y1327539D01*
G02X336141Y1327616I200J-1D01*
G01X336185Y1327721D01*
X336238Y1327774D01*
G02X336304Y1327818I142J-141D01*
G01X336378Y1327848D01*
X336424Y1327835D01*
G03X336682Y1327772I722J2395D01*
G03X337137Y1327728I467J2458D01*
G01X337162D01*
G03X337921Y1327851I-16J2502D01*
G01X337952Y1327861D01*
X342979D01*
X343140Y1327700D01*
Y1319670D01*
X344290Y1318520D01*
X353133D01*
X353400Y1318787D01*
X358462D01*
X358703Y1318546D01*
G03X358845Y1318487I142J141D01*
G01X363284D01*
X363358Y1318457D01*
X363386Y1318428D01*
X365848Y1315966D01*
G03X365990Y1315907I142J141D01*
G01X372002D01*
G03X372202Y1316107I0J200D01*
G01Y1318698D01*
X370884Y1320016D01*
X368886D01*
X368858Y1320045D01*
X368673Y1320230D01*
Y1320244D01*
X368542Y1320375D01*
G03X368400Y1320434I-142J-141D01*
G01X365576D01*
X365502Y1320464D01*
X365474Y1320493D01*
X365392Y1320575D01*
G02X365333Y1320717I141J142D01*
G01Y1321134D01*
G02X365533Y1321334I200J0D01*
G01X367543D01*
X367553Y1321324D01*
X368604D01*
G03X368746Y1321383I0J200D01*
G01X368858Y1321495D01*
G03X368917Y1321637I-141J142D01*
G01Y1322024D01*
X368925Y1322044D01*
Y1325362D01*
X368917Y1325383D01*
Y1325461D01*
G03X368858Y1325603I-200J0D01*
G01X368793Y1325668D01*
Y1325674D01*
X368773Y1325694D01*
X368737Y1325709D01*
G03X368661Y1325724I-76J-185D01*
G01X365573D01*
G02X365373Y1325924I0J200D01*
G01Y1326481D01*
X365403Y1326555D01*
X365432Y1326583D01*
X365444Y1326595D01*
X365472Y1326624D01*
X365546Y1326654D01*
X368694D01*
G03X368836Y1326713I0J200D01*
G01X368858Y1326735D01*
G03X368917Y1326877I-141J142D01*
G01Y1327024D01*
X368925Y1327044D01*
Y1327739D01*
G02X368941Y1327816I200J-1D01*
G01X368985Y1327921D01*
X369038Y1327974D01*
G02X369104Y1328018I142J-141D01*
G01X369178Y1328048D01*
X369224Y1328035D01*
G03X369482Y1327972I722J2395D01*
G03X369937Y1327928I467J2458D01*
G01X369962D01*
G03X370721Y1328051I-16J2502D01*
G01X370752Y1328061D01*
X375680D01*
X375940Y1327801D01*
Y1319880D01*
X377120Y1318700D01*
X386142D01*
X386420Y1318978D01*
X391433D01*
X391513Y1319058D01*
X396709D01*
X396783Y1319028D01*
X396811Y1318999D01*
X397394Y1318416D01*
G02X397453Y1318274I-141J-142D01*
G01Y1313390D01*
G03X397512Y1313248I200J0D01*
G01X398324Y1312436D01*
G03X398466Y1312377I142J141D01*
G01X418827D01*
G03X419027Y1312577I0J200D01*
G01Y1328720D01*
X418160Y1329587D01*
X397850D01*
X397776Y1329617D01*
X397748Y1329646D01*
X395446Y1331948D01*
G03X395304Y1332007I-142J-141D01*
G01X392990D01*
X392916Y1332037D01*
X392888Y1332066D01*
X392696Y1332258D01*
G02X392637Y1332400I141J142D01*
G01Y1334211D01*
X392662Y1334236D01*
Y1337656D01*
X392667Y1337668D01*
X392696Y1337696D01*
X392848Y1337848D01*
G02X392990Y1337907I142J-141D01*
G01X395044D01*
X395118Y1337877D01*
X395146Y1337848D01*
X397698Y1335296D01*
G03X397840Y1335237I142J141D01*
G01X404637D01*
G03X404837Y1335437I0J200D01*
G01Y1337934D01*
G03X404778Y1338076I-200J0D01*
G01X403446Y1339408D01*
G03X403304Y1339467I-142J-141D01*
G01X400881D01*
X400584Y1339764D01*
X397542D01*
X397381Y1339925D01*
Y1340497D01*
X397521Y1340637D01*
X401147D01*
X401360Y1340850D01*
Y1344890D01*
X401171Y1345079D01*
X397673D01*
X397457Y1345295D01*
Y1345797D01*
X397639Y1345979D01*
X401039D01*
X401370Y1346310D01*
Y1347297D01*
X401460Y1347387D01*
X408234D01*
X408308Y1347357D01*
X408336Y1347328D01*
X408378Y1347286D01*
G02X408437Y1347144I-141J-142D01*
G01Y1339383D01*
X409720Y1338100D01*
X418369D01*
X418650Y1338381D01*
X428346D01*
X428482Y1338517D01*
X429017D01*
X430500Y1340000D01*
Y1359000D01*
X432750Y1361250D01*
X436740D01*
G37*
G36*
G01X319768Y1274785D02*
X290374D01*
X289421Y1275738D01*
Y1281238D01*
X287249Y1283410D01*
X268948D01*
X268171Y1284187D01*
Y1289188D01*
X268520Y1289537D01*
X297822D01*
X299471Y1287888D01*
Y1282888D01*
X300671Y1281688D01*
X319671D01*
X320471Y1280888D01*
Y1275488D01*
X319768Y1274785D01*
G37*
G36*
G01X286598Y1294041D02*
X268881D01*
X268651Y1294271D01*
Y1303532D01*
X266447Y1305736D01*
X263603D01*
Y1305740D01*
X263178Y1306165D01*
Y1307821D01*
X264005Y1308648D01*
X286429D01*
X286720Y1308357D01*
Y1294163D01*
X286598Y1294041D01*
G37*
G36*
G01X262970Y1452895D02*
G03I-519J0D01*
G37*
G36*
G01X269680Y1455495D02*
G03I-519J0D01*
G37*
G36*
G01X274460D02*
G03I-519J0D01*
G37*
G36*
G01Y1450295D02*
G03I-519J0D01*
G37*
G36*
G01X269680D02*
G03I-519J0D01*
G37*
G36*
G01X267770Y1452895D02*
G03I-519J0D01*
G37*
G36*
G01X290537Y1539966D02*
X291993D01*
G02X292135Y1539907I0J-200D01*
G01X292842Y1539200D01*
G02X292901Y1539058I-141J-142D01*
G01Y1535636D01*
G02X292842Y1535494I-200J0D01*
G01X292413Y1535065D01*
G02X292272Y1535006I-142J141D01*
G01X289161D01*
G03X288592Y1534864I0J-1211D01*
G01X288570Y1534853D01*
X288523Y1534841D01*
X287483D01*
G03X287341Y1534782I0J-200D01*
G01X286923Y1534364D01*
G02X286782Y1534306I-141J142D01*
G01X275061D01*
G02X274861Y1534506I0J200D01*
G01Y1539243D01*
G02X274920Y1539385I200J0D01*
G01X275175Y1539640D01*
G02X275317Y1539699I142J-141D01*
G01X278109D01*
G02X278251Y1539640I0J-200D01*
G01X280648Y1537243D01*
G03X280790Y1537184I142J141D01*
G01X283911D01*
G03X284014Y1537180I110J1498D01*
G03X284117Y1537184I-7J1502D01*
G01X286411D01*
G03X286514Y1537180I110J1498D01*
G03X286617Y1537184I-7J1502D01*
G01X287589D01*
G03X287731Y1537243I0J200D01*
G01X290395Y1539907D01*
G02X290537Y1539966I142J-141D01*
G37*
G36*
G01X273770Y1584970D02*
X281614D01*
G02X281756Y1584911I0J-200D01*
G01X285368Y1581299D01*
G03X285510Y1581240I142J141D01*
G01X303197D01*
G02X303339Y1581181I0J-200D01*
G01X304061Y1580459D01*
G02X304120Y1580317I-141J-142D01*
G01Y1571956D01*
G02X304061Y1571814I-200J0D01*
G01X295796Y1563549D01*
G02X295654Y1563490I-142J141D01*
G01X295430D01*
G03X295288Y1563431I0J-200D01*
G01X285733Y1553876D01*
X285657Y1553845D01*
X285617Y1553846D01*
X285586D01*
G03X283584Y1551844I0J-2002D01*
G03X285512Y1549843I2002J0D01*
G01X285551Y1549842D01*
X285621Y1549811D01*
X285841Y1549582D01*
G02X285897Y1549444I-144J-139D01*
G01Y1549413D01*
X286159Y1549151D01*
X286182Y1549032D01*
X286159Y1548975D01*
G03X286002Y1548199I1845J-777D01*
G03X286867Y1546551I2002J0D01*
G01X286882Y1546541D01*
X287995Y1545428D01*
G02X288054Y1545286I-141J-142D01*
G01Y1539065D01*
G02X287995Y1538924I-200J1D01*
G01X287316Y1538244D01*
G02X287174Y1538186I-141J142D01*
G01X281205D01*
G02X281063Y1538244I-1J200D01*
G01X278665Y1540642D01*
G03X278524Y1540700I-141J-142D01*
G01X274862D01*
X274789Y1540670D01*
X274770Y1540651D01*
X273783Y1541638D01*
G02X273724Y1541780I141J142D01*
G01Y1548180D01*
G03X273665Y1548322I-200J0D01*
G01X273509Y1548478D01*
X273479Y1548570D01*
X273487Y1548618D01*
G03X273504Y1548815I-1195J202D01*
G01Y1549354D01*
G02X273519Y1549431I200J1D01*
G01X274228Y1551144D01*
G03X274320Y1551608I-1119J463D01*
G01Y1553173D01*
G03X273966Y1554030I-1211J1D01*
G01X273356Y1554640D01*
G02X273297Y1554781I141J142D01*
G01Y1560167D01*
G03X273238Y1560309I-200J0D01*
G01X271836Y1561711D01*
G02X271777Y1561853I141J142D01*
G01Y1582977D01*
G02X271836Y1583119I200J0D01*
G01X273628Y1584911D01*
G02X273770Y1584970I142J-141D01*
G37*
G36*
G01X266296Y1616788D02*
G03I-518J0D01*
G37*
G36*
G01X271252D02*
G03I-518J0D01*
G37*
G36*
G01X286616Y23965D02*
G03I-720J0D01*
G37*
G36*
G01X286219Y53191D02*
G03I-720J0D01*
G37*
G36*
G01X308313Y82946D02*
X308643D01*
X308943Y82646D01*
Y80206D01*
X308783Y80046D01*
X306263D01*
X305943D01*
X303273Y77376D01*
X297185D01*
X296643Y76834D01*
Y75179D01*
X296149Y74685D01*
X291418D01*
X290553Y75550D01*
Y83406D01*
Y93806D01*
X287853Y96506D01*
X277453D01*
X275853Y98106D01*
Y100006D01*
X277753Y101906D01*
X294775D01*
X299881Y96800D01*
X302881D01*
X303516Y96165D01*
Y90765D01*
X303257Y90506D01*
X295153D01*
X294153Y89506D01*
Y88206D01*
X294953Y87406D01*
X296913D01*
X297343Y86976D01*
Y81476D01*
X297853Y80966D01*
X306333D01*
X307593D01*
X308023Y81396D01*
Y82656D01*
X308313Y82946D01*
G37*
G36*
G01X319853Y53914D02*
Y62606D01*
X321823Y64576D01*
X330076D01*
X331953Y66453D01*
Y74706D01*
Y96506D01*
X325884Y102575D01*
X317616D01*
X316153Y104038D01*
Y112306D01*
X310353Y118106D01*
X287953D01*
X287853Y118206D01*
Y132106D01*
X289853Y134106D01*
X336953D01*
Y53738D01*
X336749Y53534D01*
X320233D01*
X319853Y53914D01*
G37*
G36*
G01X281657Y521803D02*
G03I-510J0D01*
G37*
G36*
G01X281957Y709564D02*
X281666Y709855D01*
Y724049D01*
X281788Y724171D01*
X299505D01*
X299735Y723941D01*
Y715034D01*
X302177Y712592D01*
X302293Y712476D01*
X304318D01*
X305080D01*
X305141Y712415D01*
Y710338D01*
X304367Y709564D01*
X281957D01*
G37*
G36*
G01X333415Y754127D02*
Y748905D01*
X333033Y748522D01*
X311657D01*
X309990Y746855D01*
X309830Y746695D01*
Y738819D01*
X309775Y738764D01*
X308157Y737146D01*
X308023Y737012D01*
X282538D01*
X281833Y737717D01*
Y742849D01*
X282132Y743148D01*
X302785D01*
X303305Y743668D01*
X304238Y744601D01*
X304517Y744879D01*
X304624Y744986D01*
Y751961D01*
X304645Y751982D01*
X304901Y752238D01*
X307507Y754845D01*
X332697D01*
X333415Y754127D01*
G37*
G36*
G01X287463Y1416974D02*
X334408D01*
G02X334550Y1416915I0J-200D01*
G01X338099Y1413366D01*
G02X338158Y1413224I-141J-142D01*
G01Y1386810D01*
G02X338099Y1386668I-200J0D01*
G01X337530Y1386099D01*
G02X337388Y1386040I-142J141D01*
G01X322476D01*
G02X322334Y1386099I0J200D01*
G01X312095Y1396338D01*
G03X311953Y1396397I-142J-141D01*
G01X287372D01*
G02X287230Y1396456I0J200D01*
G01X286522Y1397164D01*
G02X286463Y1397306I141J142D01*
G01Y1415974D01*
G02X286522Y1416116I200J0D01*
G01X287321Y1416915D01*
G02X287463Y1416974I142J-141D01*
G37*
G36*
G01X276370Y1452895D02*
G03I-519J0D01*
G37*
G36*
G01X281140Y1486682D02*
G03I-519J0D01*
G37*
G36*
G01X283740Y1484772D02*
G03I-519J0D01*
G37*
G36*
G01Y1479992D02*
G03I-519J0D01*
G37*
G36*
G01X281140Y1478082D02*
G03I-519J0D01*
G37*
G36*
G01X278540Y1479992D02*
G03I-519J0D01*
G37*
G36*
G01Y1484772D02*
G03I-519J0D01*
G37*
G36*
G01X289094Y1479500D02*
G03I-519J0D01*
G37*
G36*
G01Y1484280D02*
G03I-519J0D01*
G37*
G36*
G01X281140Y1491482D02*
G03I-519J0D01*
G37*
G36*
G01X289094Y1501300D02*
G03I-519J0D01*
G37*
G36*
G01X283740Y1498172D02*
G03I-519J0D01*
G37*
G36*
G01X278540D02*
G03I-519J0D01*
G37*
G36*
G01X283740Y1493392D02*
G03I-519J0D01*
G37*
G36*
G01X278540D02*
G03I-519J0D01*
G37*
G36*
G01X279038Y1520883D02*
X280542D01*
G02X280684Y1520824I0J-200D01*
G01X281115Y1520393D01*
G02X281174Y1520251I-141J-142D01*
G01Y1519245D01*
G03X281233Y1519103I200J0D01*
G01X281690Y1518646D01*
G02X281748Y1518505I-142J-141D01*
G01Y1518250D01*
G03X282250Y1517748I502J0D01*
G01X282494D01*
X282531Y1517733D01*
G03X283000Y1517638I470J1117D01*
G03X283469Y1517733I-1J1212D01*
G01X283506Y1517748D01*
X283750D01*
G03X284234Y1518118I0J502D01*
G01X284252Y1518183D01*
X284359Y1518265D01*
X284841D01*
X284948Y1518183D01*
X284966Y1518118D01*
G03X285450Y1517748I484J132D01*
G01X285694D01*
X285731Y1517733D01*
G03X286200Y1517638I470J1117D01*
G03X286669Y1517733I-1J1212D01*
G01X286706Y1517748D01*
X286950D01*
G03X287434Y1518118I0J502D01*
G01X287452Y1518183D01*
X287559Y1518265D01*
X287837D01*
X287900Y1518244D01*
X287927Y1518223D01*
G03X289460Y1517698I1533J1976D01*
G03X291151Y1518356I0J2502D01*
G02X291286Y1518408I134J-148D01*
G01X293054D01*
X293127Y1518378D01*
X293148Y1518357D01*
Y1516696D01*
G02X293042Y1516519I-200J0D01*
G03X292069Y1515584I1183J-2205D01*
G02X291896Y1515486I-172J102D01*
G01X291552D01*
G02X291379Y1515584I-1J200D01*
G03X289224Y1516816I-2155J-1269D01*
G03Y1511812I0J-2502D01*
G03X290498Y1512161I-1J2502D01*
G01X290558Y1512196D01*
X290693Y1512179D01*
X292229Y1510643D01*
X292256Y1510592D01*
X292262Y1510562D01*
G03X292333Y1510331I1188J239D01*
G01X292348Y1510294D01*
Y1510050D01*
G03X292352Y1509994I501J8D01*
G01X292353Y1509983D01*
Y1509972D01*
G02X292153Y1509772I-200J0D01*
G01X289324D01*
X289222Y1509841D01*
X289200Y1509899D01*
G03X286872Y1511483I-2328J-919D01*
G03X284370Y1508981I0J-2502D01*
G03X284439Y1508397I2502J0D01*
G01X284452Y1508345D01*
X284424Y1508246D01*
X282693Y1506516D01*
G03X282525Y1506305I858J-856D01*
G02X282356Y1506212I-169J107D01*
G01X280137D01*
G02X279995Y1506270I-1J200D01*
G01X279886Y1506380D01*
G02X279827Y1506521I141J142D01*
G01Y1508186D01*
G03X279768Y1508328I-200J0D01*
G01X278690Y1509406D01*
G02X278631Y1509548I141J142D01*
G01Y1520476D01*
G02X278690Y1520618I200J0D01*
G01X278896Y1520824D01*
G02X279038Y1520883I142J-141D01*
G37*
G36*
G01X278356Y1616788D02*
G03I-518J0D01*
G37*
G36*
G01X291876Y21395D02*
G03I-720J0D01*
G37*
G36*
G01X306313Y712560D02*
X307880D01*
X308223Y712217D01*
Y708123D01*
X307606Y707506D01*
X306753Y706653D01*
X304706D01*
X304535Y706824D01*
Y708265D01*
X306209Y709939D01*
Y710332D01*
Y712456D01*
X306313Y712560D01*
G37*
G36*
G01X352537Y1274764D02*
X323185D01*
X322211Y1275738D01*
Y1281238D01*
X320761Y1282688D01*
X301661D01*
X300961Y1283388D01*
Y1289188D01*
X301249Y1289476D01*
X330673D01*
X332261Y1287888D01*
Y1282888D01*
X333461Y1281688D01*
X352461D01*
X353261Y1280888D01*
Y1275488D01*
X352537Y1274764D01*
G37*
G36*
G01X303932Y1462595D02*
G03I-519J0D01*
G37*
G36*
G01X297242Y1459995D02*
G03I-519J0D01*
G37*
G36*
G01X295332Y1462595D02*
G03I-519J0D01*
G37*
G36*
G01X302022Y1459995D02*
G03I-519J0D01*
G37*
G36*
G01X303942Y1455495D02*
G03I-519J0D01*
G37*
G36*
G01X302032Y1452895D02*
G03I-519J0D01*
G37*
G36*
G01X303942Y1450295D02*
G03I-519J0D01*
G37*
G36*
G01X291694Y1477590D02*
G03I-519J0D01*
G37*
G36*
G01X297242Y1465195D02*
G03I-519J0D01*
G37*
G36*
G01X302022D02*
G03I-519J0D01*
G37*
G36*
G01X291694Y1486190D02*
G03I-519J0D01*
G37*
G36*
G01X294294Y1484280D02*
G03I-519J0D01*
G37*
G36*
G01Y1479500D02*
G03I-519J0D01*
G37*
G36*
G01Y1506080D02*
G03I-519J0D01*
G37*
G36*
G01Y1501300D02*
G03I-519J0D01*
G37*
G36*
G01X291694Y1499490D02*
G03I-519J0D01*
G37*
G36*
G01Y1507990D02*
G03I-519J0D01*
G37*
G36*
G01X291069Y1550264D02*
X299114D01*
G02X299256Y1550205I0J-200D01*
G01X299481Y1549980D01*
G02X299540Y1549839I-141J-142D01*
G01Y1541026D01*
G02X299481Y1540885I-200J1D01*
G01X299052Y1540456D01*
G02X298910Y1540397I-142J141D01*
G01X293144D01*
G02X293003Y1540456I1J200D01*
G01X292549Y1540909D01*
G03X292408Y1540968I-142J-141D01*
G01X290651D01*
G02X290451Y1541168I0J200D01*
G01Y1549646D01*
G02X290510Y1549788I200J0D01*
G01X290927Y1550205D01*
G02X291069Y1550264I142J-141D01*
G37*
G36*
G01X311845Y1572360D02*
X366930D01*
G02X367071Y1572301I-1J-200D01*
G01X368606Y1570766D01*
G03X370170Y1570118I1564J1563D01*
G01X371745D01*
G02X371879Y1570066I0J-200D01*
G03X373370Y1569488I1491J1634D01*
G01X375971D01*
G02X376113Y1569430I1J-200D01*
G01X379826Y1565716D01*
G03X381390Y1565068I1564J1563D01*
G01X385194D01*
G02X385336Y1565010I1J-200D01*
G01X386375Y1563970D01*
G03X387939Y1563322I1564J1563D01*
G03X388880Y1563533I-2J2212D01*
G01X388938Y1563560D01*
X389062Y1563538D01*
X390877Y1561723D01*
X390903Y1561614D01*
X390885Y1561559D01*
G03X390759Y1560775I2376J-784D01*
G03X391500Y1558998I2501J0D01*
G01X391528Y1558969D01*
X391559Y1558896D01*
Y1558517D01*
G02X391500Y1558375I-200J0D01*
G01X390907Y1557782D01*
G02X390765Y1557723I-142J141D01*
G01X390386D01*
X390363Y1557728D01*
G03X390082Y1557762I-285J-1178D01*
G01X389126D01*
G02X388955Y1557857I-1J200D01*
G03X386822Y1559052I-2133J-1306D01*
G03X385462Y1558650I0J-2501D01*
G02X385353Y1558618I-109J168D01*
G01X345897D01*
G02X345755Y1558677I0J200D01*
G01X343504Y1560928D01*
G03X343362Y1560987I-142J-141D01*
G01X312455D01*
X312418Y1561002D01*
G03X312226Y1561040I-191J-463D01*
G01X311982D01*
X311945Y1561056D01*
G03X311476Y1561150I-468J-1117D01*
G03X311007Y1561056I-1J-1211D01*
G01X310970Y1561040D01*
X310840D01*
X310724Y1561149D01*
X310720Y1561229D01*
G03X308222Y1563581I-2498J-151D01*
G03X305720Y1561079I0J-2502D01*
G03X307756Y1558621I2502J0D01*
G01X307827Y1558607D01*
X307918Y1558497D01*
Y1557571D01*
G02X307860Y1557430I-200J0D01*
G01X307764Y1557334D01*
G02X307622Y1557275I-142J141D01*
G01X302681D01*
G02X302539Y1557334I0J200D01*
G01X301751Y1558123D01*
G02X301692Y1558265I141J142D01*
G01Y1562207D01*
G02X301751Y1562349I200J0D01*
G01X311703Y1572301D01*
G02X311845Y1572360I142J-141D01*
G37*
G36*
G01X329535Y50376D02*
X488591D01*
G02X500462Y38504I-1J-11872D01*
G01Y36444D01*
G02X500378Y36281I-200J0D01*
G03X499222Y34933I2150J-3014D01*
G01X499191Y34871D01*
X499065Y34812D01*
X498619Y34919D01*
G02X498465Y35113I46J195D01*
G01Y38504D01*
G03X488591Y48378I-9874J0D01*
G01X329535D01*
G03X319661Y38504I0J-9874D01*
G01Y14326D01*
G02X319507Y14132I-200J1D01*
G01X319061Y14025D01*
X318935Y14084D01*
X318904Y14146D01*
G03X317748Y15494I-3306J-1666D01*
G02X317664Y15657I116J163D01*
G01Y38506D01*
G02X329535Y50376I11871J-1D01*
G37*
G36*
G01X318593Y81956D02*
X318093D01*
X317863Y82186D01*
Y85376D01*
Y85836D01*
X318996Y86969D01*
Y90249D01*
Y92986D01*
X319316Y93306D01*
X320553D01*
X321053Y92806D01*
Y88566D01*
Y84416D01*
X318593Y81956D01*
G37*
G36*
G01X316688Y229109D02*
X335828D01*
X337601Y227336D01*
Y216115D01*
X335975Y214489D01*
X319631D01*
X316200Y217920D01*
Y228621D01*
X316688Y229109D01*
G37*
G36*
G01X365684Y284994D02*
X367528D01*
G02X367648Y284954I0J-200D01*
G02X367670Y284935I-119J-160D01*
G01X368272Y284333D01*
G02X368291Y284311I-141J-141D01*
G02X368331Y284191I-160J-120D01*
G01Y274387D01*
G03X368390Y274245I200J0D01*
G01X369592Y273043D01*
G03X369734Y272984I142J141D01*
G01X371888D01*
G02X372008Y272944I0J-200D01*
G02X372030Y272925I-119J-160D01*
G01X372422Y272533D01*
G02X372441Y272511I-141J-141D01*
G02X372481Y272391I-160J-120D01*
G01Y268467D01*
G03X372540Y268325I200J0D01*
G01X378642Y262223D01*
G03X378784Y262164I142J141D01*
G01X389488D01*
G02X389608Y262124I0J-200D01*
G02X389630Y262105I-119J-160D01*
G01X391492Y260243D01*
G02X391511Y260221I-141J-141D01*
G02X391551Y260101I-160J-120D01*
G01Y247757D01*
G02X391511Y247637I-200J0D01*
G02X391492Y247615I-160J119D01*
G01X389790Y245913D01*
G02X389768Y245894I-141J141D01*
G02X389648Y245854I-120J160D01*
G01X380561D01*
G03X380419Y245795I0J-200D01*
G01X380377Y245753D01*
G03X380324Y245658I141J-141D01*
G02X380271Y245564I-194J48D01*
G01X380266Y245559D01*
X380193Y245529D01*
X366701D01*
G03X366559Y245470I0J-200D01*
G01X366284Y245195D01*
G02X366053Y245157I-142J141D01*
G03X365161Y245367I-893J-1792D01*
G03X363159Y243365I0J-2002D01*
G03X363167Y243186I2002J0D01*
G01X363171Y243141D01*
X363156Y243100D01*
G02X363110Y243028I-188J69D01*
G01X361156Y241074D01*
G03X360802Y240219I857J-856D01*
G01Y239796D01*
G02X360762Y239676I-200J0D01*
G02X360743Y239654I-160J119D01*
G01X360607Y239518D01*
G03X360548Y239376I141J-142D01*
G01Y226552D01*
G02X360508Y226432I-200J0D01*
G02X360489Y226410I-160J119D01*
G01X360367Y226288D01*
G02X360345Y226269I-141J141D01*
G02X360225Y226229I-120J160D01*
G01X359921D01*
G02X359801Y226269I0J200D01*
G02X359779Y226288I119J160D01*
G01X359647Y226420D01*
G02X359628Y226442I141J141D01*
G02X359588Y226562I160J120D01*
G01Y233696D01*
G03X359529Y233838I-200J0D01*
G01X358927Y234440D01*
G03X358785Y234499I-142J-141D01*
G01X357381D01*
G03X357239Y234440I0J-200D01*
G01X356656Y233857D01*
G03X356613Y233792I142J-141D01*
G01X356598Y233756D01*
X356568Y233722D01*
Y228521D01*
X356319Y228272D01*
X355872D01*
X355644Y228500D01*
Y234636D01*
X354496Y235784D01*
G03X352141Y238139I-2496J-141D01*
G01X350690Y239590D01*
X343884D01*
X339501Y235207D01*
G02X339482Y235185I-160J119D01*
G01X335125Y230828D01*
G02X335103Y230809I-141J141D01*
G02X334983Y230769I-120J160D01*
G01X317178D01*
G02X317058Y230809I0J200D01*
G02X317036Y230828I119J160D01*
G01X316357Y231507D01*
G02X316338Y231529I141J141D01*
G02X316298Y231649I160J120D01*
G01Y234914D01*
G02X316338Y235034I200J0D01*
G02X316357Y235056I160J-119D01*
G01X317556Y236255D01*
G02X317578Y236274I141J-141D01*
G02X317698Y236314I120J-160D01*
G01X321614D01*
G03X321756Y236373I0J200D01*
G01X321992Y236609D01*
G03X322051Y236751I-141J142D01*
G01Y265151D01*
X324160Y267260D01*
X360926D01*
X360968Y267302D01*
X364392Y270725D01*
G03X364451Y270867I-141J142D01*
G01Y283039D01*
G02X364480Y283142I200J-1D01*
G03X364552Y283402I-429J259D01*
G01Y283862D01*
G02X364592Y283982I200J0D01*
G02X364611Y284004I160J-119D01*
G01X365542Y284935D01*
G02X365564Y284954I141J-141D01*
G02X365684Y284994I120J-160D01*
G37*
G36*
G01X365567Y754736D02*
X366157Y754146D01*
Y748646D01*
X365657Y748146D01*
X336005D01*
X335502Y748649D01*
Y755030D01*
X335346Y755186D01*
X333722Y756810D01*
X333573Y756959D01*
X315331D01*
X315170Y757120D01*
X314657Y757633D01*
Y762940D01*
X315030Y763314D01*
X344068D01*
X345278Y762104D01*
Y756690D01*
X345704Y756264D01*
X346822Y755146D01*
X347232Y754736D01*
X365567D01*
G37*
G36*
G01X333968Y838505D02*
G02I-13779J0D01*
G37*
G36*
G01Y1199923D02*
G02I-13779J0D01*
G37*
G36*
G01X308722Y1450295D02*
G03I-519J0D01*
G37*
G36*
G01X310632Y1452895D02*
G03I-519J0D01*
G37*
G36*
G01X308722Y1455495D02*
G03I-519J0D01*
G37*
G36*
G01X317342Y1469695D02*
G03I-519J0D01*
G37*
G36*
G01X315432Y1472295D02*
G03I-519J0D01*
G37*
G36*
G01X317342Y1474895D02*
G03I-519J0D01*
G37*
G36*
G01X328397Y1527011D02*
X330023D01*
G02X330088Y1527000I0J-200D01*
G01X331002Y1526686D01*
G03X331408Y1526607I487J1420D01*
G01X331447Y1526605D01*
X331516Y1526573D01*
X331732Y1526345D01*
G02X331786Y1526207I-146J-137D01*
G01Y1524099D01*
G02X331732Y1523961I-200J-1D01*
G01X331516Y1523733D01*
X331447Y1523701D01*
X331408Y1523699D01*
G03X331093Y1523648I81J-1499D01*
G01X329871Y1523313D01*
G02X329818Y1523306I-52J193D01*
G01X328131D01*
G02X328061Y1523319I1J200D01*
G01X327290Y1523607D01*
G03X326765Y1523702I-526J-1407D01*
G03X326368Y1523648I2J-1502D01*
G01X325147Y1523313D01*
G02X325094Y1523306I-52J193D01*
G01X323407D01*
G02X323337Y1523319I1J200D01*
G01X322566Y1523607D01*
G03X322041Y1523702I-526J-1407D01*
G03X321644Y1523648I2J-1502D01*
G01X320422Y1523313D01*
G02X320369Y1523306I-52J193D01*
G01X318682D01*
G02X318612Y1523319I1J200D01*
G01X317841Y1523607D01*
G03X317316Y1523702I-526J-1407D01*
G03X316919Y1523648I2J-1502D01*
G01X315698Y1523313D01*
G02X315645Y1523306I-52J193D01*
G01X314242D01*
G02X314100Y1523365I0J200D01*
G01X313938Y1523527D01*
G02X313879Y1523669I141J142D01*
G01Y1526626D01*
G02X314008Y1526813I200J0D01*
G01X314492Y1526998D01*
G02X314564Y1527011I71J-187D01*
G01X315849D01*
G02X315914Y1527000I0J-200D01*
G01X316828Y1526686D01*
G03X317316Y1526604I489J1420D01*
G03X317738Y1526665I-2J1502D01*
G01X318892Y1527003D01*
G02X318948Y1527011I56J-192D01*
G01X320574D01*
G02X320639Y1527000I0J-200D01*
G01X321553Y1526686D01*
G03X322041Y1526604I489J1420D01*
G03X322463Y1526665I-2J1502D01*
G01X323617Y1527003D01*
G02X323673Y1527011I56J-192D01*
G01X325298D01*
G02X325363Y1527000I0J-200D01*
G01X326277Y1526686D01*
G03X326765Y1526604I489J1420D01*
G03X327187Y1526665I-2J1502D01*
G01X328341Y1527003D01*
G02X328397Y1527011I56J-192D01*
G37*
G36*
G01X328390Y596058D02*
X328250Y596198D01*
Y596782D01*
Y620274D01*
X328548Y620572D01*
X330337D01*
X364057D01*
X365761Y618868D01*
Y607579D01*
Y605458D01*
X356361Y596058D01*
X328390D01*
G37*
G36*
G01X384920Y1274839D02*
X355710D01*
X354811Y1275738D01*
Y1281238D01*
X353361Y1282688D01*
X334261D01*
X333561Y1283388D01*
Y1289188D01*
X333850Y1289477D01*
X363272D01*
X364861Y1287888D01*
Y1282888D01*
X366061Y1281688D01*
X384819D01*
X385300Y1281207D01*
Y1275219D01*
X384920Y1274839D01*
G37*
G36*
G01X330742Y1450295D02*
G03I-519J0D01*
G37*
G36*
G01X335522D02*
G03I-519J0D01*
G37*
G36*
G01Y1455495D02*
G03I-519J0D01*
G37*
G36*
G01X330742D02*
G03I-519J0D01*
G37*
G36*
G01X328832Y1452895D02*
G03I-519J0D01*
G37*
G36*
G01X328822Y1459995D02*
G03I-519J0D01*
G37*
G36*
G01X324042D02*
G03I-519J0D01*
G37*
G36*
G01X322132Y1462595D02*
G03I-519J0D01*
G37*
G36*
G01X330732D02*
G03I-519J0D01*
G37*
G36*
G01X324042Y1465195D02*
G03I-519J0D01*
G37*
G36*
G01X328822D02*
G03I-519J0D01*
G37*
G36*
G01X328832Y1472295D02*
G03I-519J0D01*
G37*
G36*
G01X324032D02*
G03I-519J0D01*
G37*
G36*
G01X322122Y1469695D02*
G03I-519J0D01*
G37*
G36*
G01Y1474895D02*
G03I-519J0D01*
G37*
G36*
G01X333197Y1527011D02*
X334747D01*
G02X334812Y1527000I0J-200D01*
G01X335726Y1526686D01*
G03X336177Y1526605I488J1420D01*
G01X336216Y1526604D01*
X336287Y1526573D01*
X336510Y1526345D01*
G02X336566Y1526205I-144J-139D01*
G01Y1524101D01*
G02X336510Y1523961I-200J-1D01*
G01X336287Y1523733D01*
X336216Y1523702D01*
X336177Y1523701D01*
G03X335817Y1523648I37J-1501D01*
G01X334595Y1523313D01*
G02X334542Y1523306I-52J193D01*
G01X333153D01*
G02X333011Y1523365I0J200D01*
G01X332847Y1523529D01*
G02X332788Y1523671I141J142D01*
G01Y1526602D01*
G02X332847Y1526744I200J0D01*
G01X333055Y1526952D01*
G02X333197Y1527011I142J-141D01*
G37*
G36*
G01X350871Y288681D02*
Y277856D01*
X361059D01*
X361381Y277534D01*
X361531Y277384D01*
Y270294D01*
X360511Y269274D01*
X348445D01*
X348010Y269710D01*
Y288710D01*
X348507Y289207D01*
X350345D01*
X350871Y288681D01*
G37*
G36*
G01X378824Y756604D02*
X380324Y755104D01*
X380728Y754700D01*
X398271D01*
X399057Y753914D01*
Y748408D01*
X398907Y748257D01*
X368519D01*
X368169Y748607D01*
Y754988D01*
X368013Y755144D01*
X366389Y756768D01*
X366240Y756917D01*
X347998D01*
X347837Y757078D01*
X347324Y757591D01*
Y762898D01*
X347697Y763272D01*
X377078D01*
X378147Y762203D01*
Y757281D01*
X378824Y756604D01*
G37*
G36*
G01X341562Y1395960D02*
X341972Y1396370D01*
X370757D01*
X372291Y1394836D01*
Y1385964D01*
Y1381087D01*
Y1380342D01*
X371171Y1379222D01*
X342570D01*
X341710Y1380082D01*
X341562Y1380230D01*
Y1395960D01*
G37*
G36*
G01X337432Y1452895D02*
G03I-519J0D01*
G37*
G36*
G01X348932Y1462595D02*
G03I-519J0D01*
G37*
G36*
G01X344142Y1474895D02*
G03I-519J0D01*
G37*
G36*
G01X348922D02*
G03I-519J0D01*
G37*
G36*
G01Y1469695D02*
G03I-519J0D01*
G37*
G36*
G01X344142D02*
G03I-519J0D01*
G37*
G36*
G01X342232Y1472295D02*
G03I-519J0D01*
G37*
G36*
G01X338249Y1527011D02*
X339471D01*
G02X339536Y1527000I0J-200D01*
G01X340450Y1526686D01*
G03X340892Y1526605I489J1420D01*
G01X340931Y1526604D01*
X341002Y1526573D01*
X341223Y1526345D01*
G02X341280Y1526205I-143J-140D01*
G01Y1524101D01*
G02X341223Y1523961I-200J0D01*
G01X341002Y1523733D01*
X340931Y1523702D01*
X340892Y1523701D01*
G03X340541Y1523648I47J-1501D01*
G01X339320Y1523313D01*
G02X339267Y1523306I-52J193D01*
G01X337955D01*
G02X337813Y1523365I0J200D01*
G01X337627Y1523551D01*
G02X337568Y1523693I141J142D01*
G01Y1526330D01*
G02X337627Y1526472I200J0D01*
G01X338107Y1526952D01*
G02X338249Y1527011I142J-141D01*
G37*
G36*
G01X352016Y1527010D02*
X352968D01*
G02X353110Y1526951I0J-200D01*
G01X353368Y1526693D01*
G02X353426Y1526552I-142J-141D01*
G01Y1525527D01*
G03X353485Y1525386I200J1D01*
G01X353491Y1525380D01*
X353521Y1525307D01*
Y1525276D01*
X353858Y1524939D01*
X353931Y1524909D01*
X353962D01*
X354254Y1524617D01*
G03X354395Y1524558I142J141D01*
G01X355518D01*
G02X355718Y1524358I0J-200D01*
G01Y1524090D01*
G02X355652Y1523941I-200J-1D01*
G01X355398Y1523714D01*
X355318Y1523688D01*
X355275Y1523693D01*
G03X355112Y1523702I-164J-1493D01*
G03X354715Y1523648I2J-1502D01*
G01X353493Y1523313D01*
G02X353440Y1523306I-52J193D01*
G01X351753D01*
G02X351683Y1523319I1J200D01*
G01X350912Y1523607D01*
G03X350387Y1523702I-526J-1407D01*
G03X349990Y1523648I2J-1502D01*
G01X348769Y1523313D01*
G02X348716Y1523306I-52J193D01*
G01X347029D01*
G02X346959Y1523319I1J200D01*
G01X346188Y1523607D01*
G03X345663Y1523702I-526J-1407D01*
G03X345266Y1523648I2J-1502D01*
G01X344044Y1523313D01*
G02X343991Y1523306I-52J193D01*
G01X342597D01*
G02X342455Y1523365I0J200D01*
G01X342340Y1523480D01*
G02X342281Y1523622I141J142D01*
G01Y1526271D01*
G02X342340Y1526413I200J0D01*
G01X342878Y1526951D01*
G02X343020Y1527010I142J-141D01*
G01X344199D01*
G02X344264Y1526999I0J-200D01*
G01X345175Y1526686D01*
G03X345663Y1526604I489J1420D01*
G03X346085Y1526665I-2J1502D01*
G01X347236Y1527002D01*
G02X347292Y1527010I56J-192D01*
G01X348923D01*
G02X348988Y1526999I0J-200D01*
G01X349899Y1526686D01*
G03X350387Y1526604I489J1420D01*
G03X350809Y1526665I-2J1502D01*
G01X351960Y1527002D01*
G02X352016Y1527010I56J-192D01*
G37*
G36*
G01X357838Y233069D02*
X358288D01*
X358540Y232817D01*
Y225695D01*
X359006Y225229D01*
X361066D01*
X361548Y225711D01*
Y230899D01*
X361738Y231089D01*
X362358D01*
X362488Y230959D01*
Y221619D01*
X364215Y219892D01*
Y217761D01*
X364616Y217360D01*
X365580D01*
X367307Y215633D01*
Y210024D01*
X366187Y208904D01*
X358234D01*
X357588Y209550D01*
Y222757D01*
G03X357911Y223847I-1678J1090D01*
G03X357588Y224937I-2001J0D01*
G01Y232819D01*
X357838Y233069D01*
G37*
G36*
G01X353878Y229179D02*
X354378D01*
X354608Y228949D01*
Y226199D01*
X353918Y225509D01*
Y221329D01*
Y218329D01*
X353418Y217829D01*
X351918D01*
X351418Y218329D01*
Y222569D01*
Y226719D01*
X353878Y229179D01*
G37*
G36*
G01X382057Y217107D02*
Y211241D01*
G02X381998Y211099I-200J0D01*
G01X380187Y209288D01*
G02X380045Y209229I-142J141D01*
G01X368989D01*
G02X368847Y209288I0J200D01*
G01X368367Y209768D01*
G02X368308Y209909I141J142D01*
G01Y212239D01*
G02X368367Y212380I200J-1D01*
G01X368562Y212575D01*
G02X368704Y212634I142J-141D01*
G01X370668D01*
G03X370810Y212693I0J200D01*
G01X371059Y212942D01*
G03X371118Y213084I-141J142D01*
G01Y216046D01*
G03X371059Y216188I-200J0D01*
G01X370286Y216961D01*
X369457D01*
X368084Y218334D01*
X367807Y218610D01*
Y220167D01*
X368269Y220629D01*
X370307D01*
X377235D01*
G03X377377Y220688I0J200D01*
G01X377434Y220745D01*
X377479Y220771D01*
X377505Y220778D01*
G03X378620Y222229I-387J1451D01*
G03X377634Y223640I-1503J0D01*
G01X377592Y223655D01*
X377577Y223670D01*
G03X377435Y223729I-142J-141D01*
G01X377191D01*
G03X377118Y223731I-78J-1500D01*
G03X377045Y223729I5J-1502D01*
G01X375641D01*
G02X375499Y223788I0J200D01*
G01X375187Y224100D01*
G02X375128Y224242I141J142D01*
G01Y229576D01*
G03X375069Y229718I-200J0D01*
G01X375054Y229732D01*
Y229778D01*
X374938Y229894D01*
X374893D01*
X374677Y230110D01*
G03X374535Y230169I-142J-141D01*
G01X371268D01*
G02X371158Y230202I0J200D01*
G03X369496I-831J-1250D01*
G02X369386Y230169I-110J167D01*
G01X364961D01*
G03X364819Y230110I0J-200D01*
G01X364507Y229798D01*
G03X364448Y229656I141J-142D01*
G01Y228562D01*
G02X364389Y228420I-200J0D01*
G01X364217Y228248D01*
G02X364075Y228189I-142J141D01*
G01X363911D01*
G02X363769Y228248I0J200D01*
G01X363587Y228430D01*
G02X363528Y228572I141J142D01*
G01Y230846D01*
G02X363587Y230988I200J0D01*
G01X363629Y231030D01*
G02X363771Y231089I142J-141D01*
G01X366445D01*
G03X366587Y231148I0J200D01*
G01X369105Y233666D01*
X369118Y233675D01*
G03X369169Y233715I-901J1202D01*
G02X369295Y233759I125J-156D01*
G01X375203D01*
G03X375345Y233818I0J200D01*
G01X375769Y234242D01*
G03X375828Y234384I-141J142D01*
G01Y236676D01*
G02X375887Y236818I200J0D01*
G01X375969Y236900D01*
X376779Y237710D01*
X381340D01*
X382057Y236993D01*
Y217107D01*
G37*
G36*
G01X364535Y570915D02*
Y589841D01*
X362048Y592328D01*
X358429D01*
X357960Y591859D01*
Y585490D01*
X355579Y583109D01*
Y578690D01*
X355988Y578281D01*
X359444D01*
X360853Y576872D01*
Y573111D01*
X358625Y570883D01*
Y570415D01*
X359125Y569915D01*
X363535D01*
X364535Y570915D01*
G37*
G36*
G01X350842Y1459995D02*
G03I-519J0D01*
G37*
G36*
G01X357532Y1462595D02*
G03I-519J0D01*
G37*
G36*
G01X355622Y1459995D02*
G03I-519J0D01*
G37*
G36*
G01X357542Y1455495D02*
G03I-519J0D01*
G37*
G36*
G01X355632Y1452895D02*
G03I-519J0D01*
G37*
G36*
G01X357542Y1450295D02*
G03I-519J0D01*
G37*
G36*
G01X362322D02*
G03I-519J0D01*
G37*
G36*
G01X364232Y1452895D02*
G03I-519J0D01*
G37*
G36*
G01X362322Y1455495D02*
G03I-519J0D01*
G37*
G36*
G01X350832Y1472295D02*
G03I-519J0D01*
G37*
G36*
G01X350842Y1465195D02*
G03I-519J0D01*
G37*
G36*
G01X355622D02*
G03I-519J0D01*
G37*
G36*
G01X366192Y1527011D02*
X367444D01*
G02X367644Y1526811I0J-200D01*
G01Y1523382D01*
X367613Y1523309D01*
X367610Y1523306D01*
X365926D01*
G02X365856Y1523319I1J200D01*
G01X365085Y1523607D01*
G03X364560Y1523702I-526J-1407D01*
G03X364283Y1523676I1J-1502D01*
G01X364234Y1523666D01*
X364139Y1523696D01*
X364013Y1523822D01*
G02X363954Y1523963I141J142D01*
G01Y1526216D01*
G02X364021Y1526365I200J0D01*
G01X364275Y1526592D01*
X364355Y1526618D01*
X364398Y1526613D01*
G03X364560Y1526604I164J1493D01*
G03X364982Y1526665I-2J1502D01*
G01X366136Y1527003D01*
G02X366192Y1527011I56J-192D01*
G37*
G36*
G01X361468D02*
X362417D01*
G02X362559Y1526952I0J-200D01*
G01X362894Y1526617D01*
G02X362953Y1526475I-141J-142D01*
G01Y1523832D01*
G02X362894Y1523690I-200J0D01*
G01X362569Y1523365D01*
G02X362427Y1523306I-142J141D01*
G01X361202D01*
G02X361132Y1523319I1J200D01*
G01X360361Y1523607D01*
G03X359836Y1523702I-526J-1407D01*
G03X359575Y1523679I0J-1492D01*
G01X359527Y1523670D01*
X359434Y1523699D01*
X359356Y1523777D01*
G02X359298Y1523918I142J141D01*
G01Y1526382D01*
G02X359356Y1526523I200J0D01*
G01X359439Y1526606D01*
X359530Y1526635D01*
X359580Y1526627D01*
G03X359836Y1526604I262J1478D01*
G03X360258Y1526665I-2J1502D01*
G01X361412Y1527003D01*
G02X361468Y1527011I56J-192D01*
G37*
G36*
G01X356273Y1526873D02*
X358070D01*
G02X358212Y1526814I0J-200D01*
G01X358237Y1526789D01*
G02X358296Y1526647I-141J-142D01*
G01Y1523865D01*
G02X358237Y1523723I-200J0D01*
G01X357961Y1523447D01*
G02X357819Y1523388I-142J141D01*
G01X357089D01*
G02X356947Y1523447I0J200D01*
G01X356779Y1523615D01*
G02X356720Y1523757I141J142D01*
G01Y1525154D01*
G03X356661Y1525296I-200J0D01*
G01X356456Y1525501D01*
G03X356314Y1525560I-142J-141D01*
G01X354810D01*
G02X354668Y1525619I0J200D01*
G01X354487Y1525800D01*
G02X354428Y1525942I141J142D01*
G01Y1526384D01*
G02X354487Y1526526I200J0D01*
G01X354595Y1526634D01*
X354696Y1526662D01*
X354748Y1526649D01*
G03X355112Y1526604I365J1457D01*
G03X355534Y1526665I-2J1502D01*
G01X356216Y1526865D01*
G02X356273Y1526873I56J-192D01*
G37*
G36*
G01X391401Y276224D02*
Y266174D01*
X390021Y264794D01*
X378651D01*
X373811Y269634D01*
Y272949D01*
X372276Y274484D01*
X371001D01*
X370341Y275144D01*
Y275764D01*
X371711Y277134D01*
X390491D01*
X391401Y276224D01*
G37*
G36*
G01X368946Y290969D02*
X368061Y290084D01*
Y287354D01*
X367461Y286754D01*
X365411D01*
X365251Y286914D01*
Y297194D01*
X366171Y298114D01*
X370171D01*
X371081Y297204D01*
Y291204D01*
X370831Y290954D01*
X370816Y290969D01*
X368946D01*
G37*
G36*
G01X366382Y558388D02*
X387203D01*
X388567Y559752D01*
Y576005D01*
X383454Y581118D01*
X366655D01*
X365564Y580027D01*
Y566116D01*
Y559206D01*
X366382Y558388D01*
G37*
G36*
G01X392795Y1283716D02*
X366684D01*
X365961Y1284439D01*
Y1288788D01*
X366751Y1289578D01*
X387451D01*
X390940Y1293067D01*
Y1297389D01*
X393835Y1300284D01*
X417061D01*
X418061Y1299284D01*
Y1295284D01*
X417123Y1294346D01*
X397023D01*
X395440Y1292763D01*
Y1286361D01*
X392795Y1283716D01*
G37*
G36*
G01X375732Y1462595D02*
G03I-519J0D01*
G37*
G36*
G01X377642Y1459995D02*
G03I-519J0D01*
G37*
G36*
G01X370942Y1474895D02*
G03I-519J0D01*
G37*
G36*
G01X369032Y1472295D02*
G03I-519J0D01*
G37*
G36*
G01X370942Y1469695D02*
G03I-519J0D01*
G37*
G36*
G01X375722Y1474895D02*
G03I-519J0D01*
G37*
G36*
G01X377632Y1472295D02*
G03I-519J0D01*
G37*
G36*
G01X375722Y1469695D02*
G03I-519J0D01*
G37*
G36*
G01X377642Y1465195D02*
G03I-519J0D01*
G37*
G36*
G01X385090Y1527011D02*
X386066D01*
G02X386172Y1526981I1J-200D01*
G01X386444Y1526810D01*
G02X386480Y1526782I-104J-171D01*
G01X386545Y1526717D01*
G02X386604Y1526575I-141J-142D01*
G01Y1523591D01*
G02X386545Y1523449I-200J0D01*
G01X386461Y1523365D01*
G02X386319Y1523306I-142J141D01*
G01X384824D01*
G02X384754Y1523319I1J200D01*
G01X383983Y1523607D01*
G03X383458Y1523702I-526J-1407D01*
G03X383061Y1523648I2J-1502D01*
G01X381840Y1523313D01*
G02X381787Y1523306I-52J193D01*
G01X380100D01*
G02X380030Y1523319I1J200D01*
G01X379259Y1523607D01*
G03X378734Y1523702I-526J-1407D01*
G03X378337Y1523648I2J-1502D01*
G01X377115Y1523313D01*
G02X377062Y1523306I-52J193D01*
G01X375375D01*
G02X375305Y1523319I1J200D01*
G01X374534Y1523607D01*
G03X374009Y1523702I-526J-1407D01*
G03X373612Y1523648I2J-1502D01*
G01X372391Y1523313D01*
G02X372338Y1523306I-52J193D01*
G01X370651D01*
G02X370581Y1523319I1J200D01*
G01X369810Y1523607D01*
G03X369285Y1523702I-526J-1407D01*
G03X369095Y1523689I7J-1502D01*
G01X369052Y1523684D01*
X368971Y1523709D01*
X368713Y1523936D01*
G02X368645Y1524086I132J150D01*
G01Y1526220D01*
G02X368713Y1526370I200J0D01*
G01X368971Y1526597D01*
X369052Y1526622D01*
X369095Y1526617D01*
G03X369285Y1526604I197J1489D01*
G03X369707Y1526665I-2J1502D01*
G01X370861Y1527003D01*
G02X370917Y1527011I56J-192D01*
G01X372542D01*
G02X372607Y1527000I0J-200D01*
G01X373521Y1526686D01*
G03X374009Y1526604I489J1420D01*
G03X374431Y1526665I-2J1502D01*
G01X375585Y1527003D01*
G02X375641Y1527011I56J-192D01*
G01X377267D01*
G02X377332Y1527000I0J-200D01*
G01X378246Y1526686D01*
G03X378734Y1526604I489J1420D01*
G03X379156Y1526665I-2J1502D01*
G01X380310Y1527003D01*
G02X380366Y1527011I56J-192D01*
G01X381991D01*
G02X382056Y1527000I0J-200D01*
G01X382970Y1526686D01*
G03X383458Y1526604I489J1420D01*
G03X383880Y1526665I-2J1502D01*
G01X385034Y1527003D01*
G02X385090Y1527011I56J-192D01*
G37*
G36*
G01X378567Y1650041D02*
X378591Y1650065D01*
X378664Y1650095D01*
X381613D01*
G02X381755Y1650036I0J-200D01*
G01X382202Y1649589D01*
G02X382261Y1649447I-141J-142D01*
G01Y1639091D01*
G02X382202Y1638949I-200J0D01*
G01X381727Y1638474D01*
G02X381585Y1638415I-142J141D01*
G01X378974D01*
G02X378832Y1638474I0J200D01*
G01X378626Y1638680D01*
G02X378567Y1638822I141J142D01*
G01Y1650041D01*
G37*
G36*
G01X372860Y1683284D02*
G03I-510J0D01*
G37*
G36*
G01X393917Y-28508D02*
G03I-630J0D01*
G37*
G36*
G01Y-18508D02*
G03I-630J0D01*
G37*
G36*
G01Y-9234D02*
G03I-630J0D01*
G37*
G36*
G01X403235Y729514D02*
X380827D01*
X380536Y729805D01*
Y743999D01*
X380658Y744121D01*
X398375D01*
X398605Y743891D01*
Y734984D01*
X401163Y732426D01*
X403950D01*
X404084Y732292D01*
Y730363D01*
X403235Y729514D01*
G37*
G36*
G01X408753Y758730D02*
Y748050D01*
Y747751D01*
X411851Y744653D01*
Y738578D01*
X413283Y737146D01*
X433626D01*
X434657Y736115D01*
Y730715D01*
X434270Y730328D01*
X412057D01*
X406157Y736228D01*
Y743146D01*
X401135Y748167D01*
Y755747D01*
X400905Y755977D01*
X399896Y756986D01*
X399180D01*
X381317D01*
X380657Y757646D01*
Y762984D01*
X380934Y763261D01*
X404222D01*
X408753Y758730D01*
G37*
G36*
G01X417611Y1328094D02*
X417902Y1327803D01*
Y1313609D01*
X417780Y1313487D01*
X400063D01*
X399833Y1313717D01*
Y1322624D01*
X397391Y1325066D01*
X397275Y1325182D01*
X395250D01*
X394488D01*
X394340Y1325330D01*
Y1327251D01*
X395183Y1328094D01*
X417611D01*
G37*
G36*
G01X393061Y1325407D02*
X391663D01*
X391345Y1325725D01*
Y1329535D01*
X392815Y1331005D01*
X394862D01*
X395033Y1330834D01*
Y1329393D01*
X393322Y1327682D01*
Y1325668D01*
X393061Y1325407D01*
G37*
G36*
G01X382422Y1459995D02*
G03I-519J0D01*
G37*
G36*
G01X384332Y1462595D02*
G03I-519J0D01*
G37*
G36*
G01X384342Y1455495D02*
G03I-519J0D01*
G37*
G36*
G01X382432Y1452895D02*
G03I-519J0D01*
G37*
G36*
G01X384342Y1450295D02*
G03I-519J0D01*
G37*
G36*
G01X389122D02*
G03I-519J0D01*
G37*
G36*
G01X391032Y1452895D02*
G03I-519J0D01*
G37*
G36*
G01X389122Y1455495D02*
G03I-519J0D01*
G37*
G36*
G01X382422Y1465195D02*
G03I-519J0D01*
G37*
G36*
G01X394548Y1597816D02*
X391717D01*
G02X391575Y1597875I0J200D01*
G01X391314Y1598136D01*
G02X391255Y1598278I141J142D01*
G01Y1602694D01*
G03X391196Y1602836I-200J0D01*
G01X390589Y1603443D01*
G03X390447Y1603502I-142J-141D01*
G01X387088D01*
G02X386946Y1603561I0J200D01*
G01X386464Y1604043D01*
G02X386405Y1604185I141J142D01*
G01Y1611519D01*
G02X386464Y1611661I200J0D01*
G01X386946Y1612143D01*
G02X387088Y1612202I142J-141D01*
G01X394422D01*
G02X394564Y1612143I0J-200D01*
G01X394946Y1611761D01*
G02X395005Y1611619I-141J-142D01*
G01Y1598273D01*
G02X394946Y1598131I-200J0D01*
G01X394690Y1597875D01*
G02X394548Y1597816I-142J141D01*
G37*
G36*
G01X390872Y1619962D02*
X390898Y1619936D01*
G03X392462Y1619288I1564J1563D01*
G01X394000D01*
G03X394089Y1619290I-5J2212D01*
G01X394130Y1619292D01*
X394206Y1619263D01*
X394444Y1619035D01*
G02X394505Y1618891I-139J-144D01*
G01Y1614385D01*
G02X394446Y1614243I-200J0D01*
G01X393864Y1613661D01*
G02X393722Y1613602I-142J141D01*
G01X387288D01*
G02X387146Y1613661I0J200D01*
G01X386664Y1614143D01*
G02X386605Y1614285I141J142D01*
G01Y1618929D01*
G02X386677Y1619082I200J-1D01*
G01X386946Y1619308D01*
X387030Y1619331D01*
X387075Y1619323D01*
G03X387462Y1619288I392J2177D01*
G01X389000D01*
G03X390587Y1619960I-1J2212D01*
G01X390588Y1619961D01*
X390589Y1619962D01*
G02X390872I142J-141D01*
G37*
G36*
G01X387835Y1627212D02*
G03I-510J0D01*
G37*
G36*
G01X397936Y112815D02*
G03I-510J0D01*
G37*
G36*
G01Y116215D02*
G03I-510J0D01*
G37*
G36*
G01X403116Y129465D02*
G03I-510J0D01*
G37*
G36*
G01Y126065D02*
G03I-510J0D01*
G37*
G36*
G01X402853Y563620D02*
X412547D01*
G02X412689Y563561I0J-200D01*
G01X415561Y560689D01*
G02X415620Y560547I-141J-142D01*
G01Y543253D01*
G02X415561Y543111I-200J0D01*
G01X415049Y542599D01*
G02X414907Y542540I-142J141D01*
G01X410543D01*
G02X410401Y542599I0J200D01*
G01X410109Y542891D01*
G02X410050Y543033I141J142D01*
G01Y557777D01*
G03X410052Y557850I-1500J78D01*
G03X410050Y557923I-1502J-5D01*
G01Y557970D01*
X410049Y557971D01*
X410040Y558039D01*
G03X408739Y559340I-1490J-189D01*
G01X408706Y559344D01*
X408647Y559373D01*
X408309Y559711D01*
G03X408167Y559770I-142J-141D01*
G01X402813D01*
G02X402671Y559829I0J200D01*
G01X402140Y560360D01*
X402115Y560475D01*
X402136Y560531D01*
G03X402298Y561415I-2340J886D01*
G03X402022Y562556I-2502J-1D01*
G01X402011Y562578D01*
X402000Y562623D01*
Y562767D01*
G02X402059Y562909I200J0D01*
G01X402711Y563561D01*
G02X402853Y563620I142J-141D01*
G37*
G36*
G01X405279Y732510D02*
X406348D01*
X406960D01*
X407093Y732377D01*
Y728073D01*
X406476Y727456D01*
X405623Y726603D01*
X403576D01*
X403405Y726774D01*
Y728145D01*
X405079Y729819D01*
X405097Y729837D01*
Y732328D01*
X405279Y732510D01*
G37*
G36*
G01X419674Y1296973D02*
Y1301140D01*
X418995Y1301819D01*
X399561D01*
X398761Y1302619D01*
Y1308073D01*
X399691Y1309003D01*
X446267D01*
X447113Y1308157D01*
Y1296391D01*
X446636Y1295914D01*
X420733D01*
X419674Y1296973D01*
G37*
G36*
G01X397742Y1455495D02*
G03I-519J0D01*
G37*
G36*
G01X395832Y1452895D02*
G03I-519J0D01*
G37*
G36*
G01X397742Y1450295D02*
G03I-519J0D01*
G37*
G36*
G01X402522D02*
G03I-519J0D01*
G37*
G36*
G01X404432Y1452895D02*
G03I-519J0D01*
G37*
G36*
G01X402522Y1455495D02*
G03I-519J0D01*
G37*
G36*
G01X409202Y1491482D02*
G03I-519J0D01*
G37*
G36*
G01X406602Y1484772D02*
G03I-519J0D01*
G37*
G36*
G01Y1479992D02*
G03I-519J0D01*
G37*
G36*
G01X409202Y1478082D02*
G03I-519J0D01*
G37*
G36*
G01Y1486682D02*
G03I-519J0D01*
G37*
G36*
G01Y1500082D02*
G03I-519J0D01*
G37*
G36*
G01X406602Y1498172D02*
G03I-519J0D01*
G37*
G36*
G01Y1493392D02*
G03I-519J0D01*
G37*
G36*
G01X405150Y1522520D02*
X405317D01*
G02X405459Y1522461I0J-200D01*
G01X406253Y1521667D01*
G02X406312Y1521526I-141J-142D01*
G01X406427Y1521410D01*
X406466D01*
X406540Y1521380D01*
X406978Y1520942D01*
G03X407120Y1520883I142J141D01*
G01X408604D01*
G02X408746Y1520824I0J-200D01*
G01X409177Y1520393D01*
G02X409236Y1520251I-141J-142D01*
G01Y1519245D01*
G03X409295Y1519103I200J0D01*
G01X409752Y1518646D01*
G02X409810Y1518505I-142J-141D01*
G01Y1518250D01*
G03X410312Y1517748I502J0D01*
G01X410556D01*
X410593Y1517733D01*
G03X411062Y1517638I470J1117D01*
G03X411531Y1517733I-1J1212D01*
G01X411568Y1517748D01*
X411812D01*
G03X412296Y1518118I0J502D01*
G01X412314Y1518183D01*
X412421Y1518265D01*
X412903D01*
X413010Y1518183D01*
X413028Y1518118D01*
G03X413512Y1517748I484J132D01*
G01X413756D01*
X413793Y1517733D01*
G03X414262Y1517638I470J1117D01*
G03X414731Y1517733I-1J1212D01*
G01X414768Y1517748D01*
X415012D01*
G03X415513Y1518236I0J501D01*
G01X415514Y1518275D01*
X415545Y1518345D01*
X416261Y1519061D01*
G02X416403Y1519120I142J-141D01*
G01X423191D01*
G02X423368Y1519015I1J-200D01*
G03X425571Y1517698I2203J1184D01*
G03X427262Y1518356I0J2502D01*
G01X427290Y1518381D01*
X427359Y1518408D01*
X428035D01*
G02X428112Y1518393I1J-200D01*
G01X428973Y1518037D01*
G02X429096Y1517852I-77J-185D01*
G01Y1516601D01*
G02X429003Y1516432I-200J0D01*
G03X427981Y1515161I1332J-2118D01*
G01X427966Y1515119D01*
X427903Y1515056D01*
X427529Y1514921D01*
X427441Y1514929D01*
X427402Y1514952D01*
G03X427056Y1515089I-614J-1045D01*
G02X426928Y1515182I44J195D01*
G03X424775Y1516409I-2153J-1275D01*
G03Y1511405I0J-2502D01*
G03X426497Y1512091I1J2502D01*
G02X426634Y1512146I138J-145D01*
G01X426753Y1512147D01*
G02X426895Y1512088I0J-200D01*
G01X428340Y1510643D01*
X428367Y1510592D01*
X428373Y1510562D01*
G03X428444Y1510331I1188J239D01*
G01X428460Y1510294D01*
Y1510065D01*
G02X428260Y1509865I-200J0D01*
G01X422337D01*
X422320Y1509882D01*
X422272D01*
X422219Y1510000D01*
G03X419934Y1511483I-2285J-1019D01*
G03X417649Y1510001I0J-2503D01*
G02X417466Y1509882I-183J81D01*
G01X417402D01*
G02X417219Y1510001I0J200D01*
G03X414934Y1511483I-2285J-1021D01*
G03X412432Y1508981I0J-2502D01*
G03X412501Y1508397I2502J0D01*
G01X412514Y1508345D01*
X412486Y1508246D01*
X410755Y1506516D01*
G03X410587Y1506305I858J-856D01*
G02X410418Y1506212I-169J107D01*
G01X408199D01*
G02X408057Y1506270I-1J200D01*
G01X407948Y1506380D01*
G02X407889Y1506521I141J142D01*
G01Y1508186D01*
G03X407830Y1508328I-200J0D01*
G01X406752Y1509406D01*
G02X406693Y1509548I141J142D01*
G01Y1517337D01*
G03X406634Y1517479I-200J0D01*
G01X406342Y1517771D01*
G03X406200Y1517830I-142J-141D01*
G01X405755D01*
X405705Y1517843D01*
X405682Y1517857D01*
G03X404686Y1518122I-995J-1737D01*
G03X403810Y1517920I0J-2002D01*
G01X403752Y1517892D01*
X403627Y1517913D01*
X403349Y1518191D01*
G02X403290Y1518333I141J142D01*
G01Y1518652D01*
X403307Y1518707D01*
X403324Y1518733D01*
G03Y1520957I-1666J1112D01*
G02X403290Y1521068I166J112D01*
G01Y1522107D01*
G02X403349Y1522249I200J0D01*
G01X403561Y1522461D01*
G02X403703Y1522520I142J-141D01*
G01X404248D01*
X404276Y1522512D01*
G03X404699Y1522451I424J1441D01*
G03X405122Y1522512I-1J1502D01*
G01X405150Y1522520D01*
G37*
G36*
G01X410988Y1551393D02*
X413843D01*
G02X413985Y1551334I0J-200D01*
G01X414105Y1551214D01*
G02X414164Y1551072I-141J-142D01*
G01Y1549460D01*
X414163Y1549449D01*
G03X414155Y1549295I1494J-155D01*
G03X414163Y1549141I1502J1D01*
G01X414164Y1549130D01*
Y1546960D01*
X414163Y1546949D01*
G03X414155Y1546795I1494J-155D01*
G03X414163Y1546641I1502J1D01*
G01X414164Y1546630D01*
Y1544460D01*
X414163Y1544449D01*
G03X414155Y1544295I1494J-155D01*
G03X414163Y1544141I1502J1D01*
G01X414164Y1544130D01*
Y1541960D01*
X414163Y1541949D01*
G03X414155Y1541795I1494J-155D01*
G03X414163Y1541641I1502J1D01*
G01X414164Y1541630D01*
Y1540918D01*
G03X414223Y1540776I200J0D01*
G01X414261Y1540738D01*
G02X414320Y1540597I-141J-142D01*
G01Y1540411D01*
G03X414821Y1539910I501J0D01*
G01X415007D01*
G02X415148Y1539851I-1J-200D01*
G01X415377Y1539622D01*
G02X415436Y1539480I-141J-142D01*
G01Y1535535D01*
G03X415495Y1535393I200J0D01*
G01X415838Y1535050D01*
G03X415980Y1534991I142J141D01*
G01X416607D01*
X416637Y1534981D01*
G03X417098Y1534909I459J1430D01*
G03X417559Y1534981I2J1502D01*
G01X417589Y1534991D01*
X421417D01*
G02X421559Y1534932I0J-200D01*
G01X423546Y1532945D01*
G02X423605Y1532803I-141J-142D01*
G01Y1529947D01*
G02X423546Y1529806I-200J1D01*
G01X422744Y1529003D01*
X422660Y1528973D01*
X422616Y1528977D01*
G03X422437Y1528985I-179J-1994D01*
G03X421679Y1528836I0J-2003D01*
G01X421642Y1528821D01*
X417124D01*
G02X416982Y1528880I0J200D01*
G01X415990Y1529872D01*
G03X415848Y1529931I-142J-141D01*
G01X413784D01*
X413764Y1529935D01*
G03X413509Y1529962I-254J-1184D01*
G01X411564D01*
G03X411309Y1529935I-1J-1211D01*
G01X411289Y1529931D01*
X408584D01*
G02X408443Y1529990I1J200D01*
G01X408313Y1530120D01*
G03X407456Y1530474I-856J-857D01*
G01X404227D01*
G03X403763Y1530382I-1J-1211D01*
G01X403029Y1530078D01*
G03X402818Y1529965I464J-1119D01*
G02X402706Y1529931I-112J166D01*
G01X398450D01*
G02X398285Y1530017I-1J200D01*
G01X398070Y1530328D01*
X398057Y1530424D01*
X398075Y1530471D01*
G03X398152Y1530895I-1135J425D01*
G01Y1531555D01*
G02X398210Y1531697I200J1D01*
G01X399748Y1533234D01*
G02X399889Y1533293I142J-141D01*
G01X403588D01*
G02X403730Y1533234I0J-200D01*
G01X404495Y1532469D01*
G03X404637Y1532410I142J141D01*
G01X406645D01*
X406694Y1532397D01*
X406717Y1532384D01*
G03X407311Y1532228I595J1056D01*
G01X410601D01*
X410633Y1532217D01*
G03X410800Y1532188I168J473D01*
G01X412000D01*
G03X412502Y1532690I0J502D01*
G01Y1532770D01*
G02X412560Y1532911I200J0D01*
G01X412611Y1532962D01*
G03X412670Y1533104I-141J142D01*
G01Y1533246D01*
G02X412729Y1533387I200J-1D01*
G01X413175Y1533833D01*
G03X413530Y1534690I-857J857D01*
G01Y1536932D01*
G03X413175Y1537789I-1212J0D01*
G01X412410Y1538553D01*
G02X412352Y1538695I142J141D01*
G01Y1538750D01*
G03X411850Y1539252I-502J0D01*
G01X411650D01*
G02X411509Y1539310I0J200D01*
G01X410590Y1540229D01*
G02X410531Y1540371I141J142D01*
G01Y1550936D01*
G02X410590Y1551078I200J0D01*
G01X410846Y1551334D01*
G02X410988Y1551393I142J-141D01*
G37*
G36*
G01X399895Y1604661D02*
X396740D01*
G02X396598Y1604720I0J200D01*
G01X396103Y1605215D01*
G02X396044Y1605357I141J142D01*
G01Y1618870D01*
G02X396103Y1619012I200J0D01*
G01X396554Y1619463D01*
G02X396696Y1619522I142J-141D01*
G01X401061D01*
G02X401203Y1619463I0J-200D01*
G01X401412Y1619254D01*
G02X401471Y1619112I-141J-142D01*
G01Y1606237D01*
G02X401412Y1606095I-200J0D01*
G01X400037Y1604720D01*
G02X399895Y1604661I-142J141D01*
G37*
G36*
G01X414605Y69270D02*
G03I-656J0D01*
G37*
G36*
G01X414996Y124179D02*
G03I-510J0D01*
G37*
G36*
G01X423656Y228147D02*
G03I-720J0D01*
G37*
G36*
G01Y232793D02*
G03I-720J0D01*
G37*
G36*
G01X421008Y244184D02*
G03I-720J0D01*
G37*
G36*
G01X435140Y675897D02*
X447020D01*
X447154Y675763D01*
X453757D01*
X453901Y675619D01*
Y668009D01*
X453857Y667965D01*
X448257D01*
X447891Y667599D01*
Y664069D01*
X445921Y662099D01*
Y655208D01*
X449792Y651337D01*
X453270D01*
X455861Y653928D01*
X463875D01*
X468340Y649463D01*
X479554D01*
X479754Y649263D01*
X486457D01*
X486554Y649166D01*
Y641546D01*
X486473Y641465D01*
X481087D01*
X480331Y640709D01*
Y637508D01*
X478540Y635718D01*
Y627959D01*
X479741Y626758D01*
X499011D01*
X499801Y625968D01*
Y617002D01*
X501440Y615363D01*
X512854D01*
X513054Y615163D01*
X519737D01*
X519854Y615046D01*
Y607446D01*
X519773Y607365D01*
X514237D01*
X513851Y606979D01*
Y603340D01*
X511870Y601359D01*
Y586838D01*
X510212Y585180D01*
X423931D01*
X417130Y591981D01*
Y632888D01*
X433451Y649209D01*
Y674208D01*
X435140Y675897D01*
G37*
G36*
G01X411802Y1479992D02*
G03I-519J0D01*
G37*
G36*
G01Y1484772D02*
G03I-519J0D01*
G37*
G36*
G01X425205Y1484280D02*
G03I-519J0D01*
G37*
G36*
G01Y1479500D02*
G03I-519J0D01*
G37*
G36*
G01X411802Y1493392D02*
G03I-519J0D01*
G37*
G36*
G01Y1498172D02*
G03I-519J0D01*
G37*
G36*
G01X425205Y1506080D02*
G03I-519J0D01*
G37*
G36*
G01Y1501300D02*
G03I-519J0D01*
G37*
G36*
G01X416393Y1552578D02*
X417621D01*
G02X417763Y1552520I1J-200D01*
G01X417920Y1552362D01*
G03X419484Y1551714I1564J1563D01*
G01X419595D01*
X419706Y1551619D01*
X419718Y1551544D01*
G03X421697Y1549842I1979J300D01*
G03X422314Y1549939I1J2002D01*
G02X422533Y1549872I62J-190D01*
G03X422563Y1549834I1586J1221D01*
G02X422608Y1549708I-155J-126D01*
G01Y1549590D01*
G02X422563Y1549464I-200J0D01*
G03X422113Y1548199I1553J-1265D01*
G03X424115Y1546197I2002J0D01*
G03X424508Y1546236I0J2002D01*
G01X424552Y1546245D01*
X424638Y1546223D01*
X424913Y1545998D01*
G02X424986Y1545844I-127J-154D01*
G01Y1536278D01*
G02X424927Y1536136I-200J0D01*
G01X424326Y1535535D01*
G02X424184Y1535476I-142J141D01*
G01X422514D01*
G02X422373Y1535535I1J200D01*
G01X421973Y1535934D01*
G03X421832Y1535992I-141J-142D01*
G01X416638D01*
G02X416438Y1536192I0J200D01*
G01Y1539895D01*
G03X416379Y1540036I-200J-1D01*
G01X415224Y1541191D01*
G02X415166Y1541333I142J141D01*
G01Y1551351D01*
G02X415224Y1551492I200J0D01*
G01X416252Y1552520D01*
G02X416393Y1552578I141J-142D01*
G37*
G36*
G01X424386Y1619064D02*
X424632Y1618818D01*
G02X424690Y1618677I-142J-141D01*
G01Y1606473D01*
G02X424632Y1606332I-200J0D01*
G01X424628Y1606328D01*
X412096D01*
G02X411896Y1606528I0J199D01*
G01Y1619096D01*
X411922Y1619122D01*
X424245D01*
G02X424386Y1619064I0J-200D01*
G37*
G36*
G01X423715Y1623676D02*
X423480D01*
G02X423299Y1623793I1J200D01*
G03X423181Y1624016I-2051J-942D01*
G01X423167Y1624039D01*
X423152Y1624091D01*
Y1624506D01*
G03X422997Y1625327I-2256J-1D01*
G02X423042Y1625542I186J73D01*
G01X423391Y1625891D01*
G03X423450Y1626033I-141J142D01*
G01Y1630967D01*
G03X423391Y1631109I-200J0D01*
G01X421659Y1632841D01*
G02X421600Y1632983I141J142D01*
G01Y1635095D01*
X421682Y1635202D01*
X421747Y1635220D01*
G03Y1638116I-400J1448D01*
G01X421682Y1638134D01*
X421600Y1638241D01*
Y1646017D01*
G02X421659Y1646159I200J0D01*
G01X421841Y1646341D01*
G02X421983Y1646400I142J-141D01*
G01X425917D01*
G02X426059Y1646341I0J-200D01*
G01X426341Y1646059D01*
G02X426400Y1645917I-141J-142D01*
G01Y1625783D01*
G02X426341Y1625641I-200J0D01*
G01X424287Y1623587D01*
G02X424023Y1623570I-142J141D01*
G03X423715Y1623676I-308J-395D01*
G37*
G36*
G01X415283Y1645200D02*
X419917D01*
G02X420059Y1645141I0J-200D01*
G01X420441Y1644759D01*
G02X420500Y1644617I-141J-142D01*
G01Y1638010D01*
G02X420423Y1637852I-200J0D01*
G03Y1635484I924J-1184D01*
G02X420500Y1635326I-123J-158D01*
G01Y1632983D01*
G02X420441Y1632841I-200J0D01*
G01X420159Y1632559D01*
G02X420017Y1632500I-142J141D01*
G01X416983D01*
G02X416841Y1632559I0J200D01*
G01X415092Y1634308D01*
X415078Y1634336D01*
G03X414218Y1635196I-1779J-919D01*
G01X414190Y1635210D01*
X413859Y1635541D01*
G02X413800Y1635683I141J142D01*
G01Y1637197D01*
G02X413870Y1637349I200J0D01*
G01X414135Y1637575D01*
X414219Y1637599D01*
X414263Y1637592D01*
G03X414500Y1637573I238J1483D01*
G03Y1640577I0J1502D01*
G03X414263Y1640558I1J-1502D01*
G01X414219Y1640551D01*
X414135Y1640575D01*
X413870Y1640801D01*
G02X413800Y1640953I130J152D01*
G01Y1643717D01*
G02X413859Y1643859I200J0D01*
G01X415141Y1645141D01*
G02X415283Y1645200I142J-141D01*
G37*
G36*
G01X418022Y1738118D02*
X685326D01*
G02X685511Y1737994I0J-200D01*
G01X685674Y1737594D01*
X685650Y1737476D01*
X685606Y1737433D01*
G03X684404Y1736186I22069J-22475D01*
G02X684256Y1736120I-148J134D01*
G01X609883D01*
X609854Y1736130D01*
G03X609252Y1736222I-601J-1918D01*
G03X608650Y1736130I-1J-2010D01*
G01X608621Y1736120D01*
X594135D01*
X594106Y1736130D01*
G03X593504Y1736222I-601J-1918D01*
G03X592902Y1736130I-1J-2010D01*
G01X592873Y1736120D01*
X578387D01*
X578358Y1736130D01*
G03X577756Y1736222I-601J-1918D01*
G03X577154Y1736130I-1J-2010D01*
G01X577125Y1736120D01*
X563852D01*
X563800Y1736135D01*
X563776Y1736149D01*
G03X563516Y1736222I-261J-428D01*
G01X560500D01*
G03X560240Y1736149I1J-501D01*
G01X560216Y1736135D01*
X560164Y1736120D01*
X542953D01*
X542924Y1736130D01*
G03X542322Y1736222I-601J-1918D01*
G03X541720Y1736130I-1J-2010D01*
G01X541691Y1736120D01*
X527205D01*
X527176Y1736130D01*
G03X526574Y1736222I-601J-1918D01*
G03X525972Y1736130I-1J-2010D01*
G01X525943Y1736120D01*
X511457D01*
X511428Y1736130D01*
G03X510826Y1736222I-601J-1918D01*
G03X510224Y1736130I-1J-2010D01*
G01X510195Y1736120D01*
X496922D01*
X496870Y1736135D01*
X496846Y1736149D01*
G03X496586Y1736222I-261J-428D01*
G01X493570D01*
G03X493310Y1736149I1J-501D01*
G01X493286Y1736135D01*
X493234Y1736120D01*
X419092D01*
G02X418944Y1736186I0J200D01*
G03X417742Y1737433I-23271J-21228D01*
G01X417698Y1737476D01*
X417674Y1737594D01*
X417837Y1737994D01*
G02X418022Y1738118I185J-76D01*
G37*
G36*
G01X431443Y1462595D02*
G03I-519J0D01*
G37*
G36*
G01X433353Y1459995D02*
G03I-519J0D01*
G37*
G36*
G01X440043Y1462595D02*
G03I-519J0D01*
G37*
G36*
G01X438133Y1459995D02*
G03I-519J0D01*
G37*
G36*
G01X440053Y1455495D02*
G03I-519J0D01*
G37*
G36*
G01X438143Y1452895D02*
G03I-519J0D01*
G37*
G36*
G01X440053Y1450295D02*
G03I-519J0D01*
G37*
G36*
G01X427805Y1477590D02*
G03I-519J0D01*
G37*
G36*
G01X433353Y1465195D02*
G03I-519J0D01*
G37*
G36*
G01X438133D02*
G03I-519J0D01*
G37*
G36*
G01X427805Y1486190D02*
G03I-519J0D01*
G37*
G36*
G01X430405Y1484280D02*
G03I-519J0D01*
G37*
G36*
G01Y1479500D02*
G03I-519J0D01*
G37*
G36*
G01Y1506080D02*
G03I-519J0D01*
G37*
G36*
G01Y1501300D02*
G03I-519J0D01*
G37*
G36*
G01X427805Y1499490D02*
G03I-519J0D01*
G37*
G36*
G01Y1507990D02*
G03I-519J0D01*
G37*
G36*
G01X428314Y1550748D02*
X435352D01*
G02X435494Y1550689I0J-200D01*
G01X435707Y1550476D01*
G02X435766Y1550334I-141J-142D01*
G01Y1549976D01*
X435758Y1549948D01*
G03X435710Y1549612I1164J-338D01*
G01Y1545206D01*
G03X435758Y1544870I1212J2D01*
G01X435766Y1544842D01*
Y1541142D01*
G02X435707Y1541000I-200J0D01*
G01X435162Y1540455D01*
G02X435020Y1540396I-142J141D01*
G01X428553D01*
G02X428456Y1540421I0J200D01*
G03X427730Y1540608I-726J-1316D01*
G03X427104Y1540471I1J-1502D01*
G01X427047Y1540445D01*
X426924Y1540467D01*
X426620Y1540771D01*
G03X426478Y1540830I-142J-141D01*
G01X426408Y1540900D01*
Y1548842D01*
G02X426467Y1548983I200J-1D01*
G01X428173Y1550689D01*
G02X428314Y1550748I142J-141D01*
G37*
G36*
G01X428656Y1648430D02*
X435126D01*
G02X435290Y1648345I0J-200D01*
G03X436538Y1647536I1635J1155D01*
G01X436568Y1647530D01*
X436620Y1647502D01*
X439778Y1644344D01*
G02X439837Y1644202I-141J-142D01*
G01Y1638992D01*
G02X439778Y1638850I-200J0D01*
G01X438007Y1637079D01*
G03X437948Y1636937I141J-142D01*
G01Y1626268D01*
G02X437889Y1626126I-200J0D01*
G01X437690Y1625927D01*
G02X437548Y1625868I-142J141D01*
G01X434499D01*
G02X434357Y1625927I0J200D01*
G01X434145Y1626139D01*
G02X434087Y1626281I142J141D01*
G01Y1628052D01*
G03X434028Y1628194I-200J0D01*
G01X431659Y1630563D01*
G02X431600Y1630705I141J142D01*
G01Y1637863D01*
G02X431659Y1638005I200J0D01*
G01X432238Y1638585D01*
G03X432708Y1639437I-1238J1239D01*
G02X432731Y1639494I195J-45D01*
G03X432818Y1639661I-1730J1007D01*
G01X432836Y1639700D01*
X432902Y1639757D01*
X433278Y1639864D01*
X433364Y1639851D01*
X433400Y1639827D01*
G03X434500Y1639498I1100J1674D01*
G03Y1643502I0J2002D01*
G03X432682Y1642339I0J-2002D01*
G01X432664Y1642300D01*
X432598Y1642243D01*
X432222Y1642136D01*
X432136Y1642149D01*
X432100Y1642173D01*
G03X431544Y1642427I-1100J-1673D01*
G01X431519Y1642434D01*
X431476Y1642459D01*
X430995Y1642940D01*
G03X430853Y1642999I-142J-141D01*
G01X428079D01*
G02X427937Y1643058I0J200D01*
G01X427859Y1643136D01*
G02X427800Y1643278I141J142D01*
G01Y1647574D01*
G02X427859Y1647716I200J0D01*
G01X428514Y1648371D01*
G02X428656Y1648430I142J-141D01*
G37*
G36*
G01X437774Y1616166D02*
X431617D01*
G02X431475Y1616225I0J200D01*
G01X430659Y1617041D01*
G03X430517Y1617100I-142J-141D01*
G01X426883D01*
G02X426741Y1617159I0J200D01*
G01X426659Y1617241D01*
G02X426600Y1617383I141J142D01*
G01Y1617917D01*
G02X426659Y1618059I200J0D01*
G01X426741Y1618141D01*
G02X426883Y1618200I142J-141D01*
G01X433117D01*
G03X433259Y1618259I0J200D01*
G01X439992Y1624992D01*
G03X440051Y1625134I-141J142D01*
G01Y1629037D01*
G02X440110Y1629179I200J0D01*
G01X440329Y1629398D01*
G02X440471Y1629457I142J-141D01*
G01X443532D01*
G02X443674Y1629398I0J-200D01*
G01X443837Y1629235D01*
G02X443896Y1629093I-141J-142D01*
G01Y1625179D01*
G02X443837Y1625037I-200J0D01*
G01X442941Y1624141D01*
G03X442882Y1623999I141J-142D01*
G01Y1617811D01*
G02X442823Y1617669I-200J0D01*
G01X442479Y1617325D01*
G02X442337Y1617266I-142J141D01*
G01X439040D01*
G03X438898Y1617207I0J-200D01*
G01X437916Y1616225D01*
G02X437774Y1616166I-142J141D01*
G37*
G36*
G01X429010Y1650000D02*
G03I-510J0D01*
G37*
G36*
G01X450612Y87011D02*
G03I-510J0D01*
G37*
G36*
G01X450924Y92384D02*
G03I-510J0D01*
G37*
G36*
G01X443524D02*
G03I-510J0D01*
G37*
G36*
G01X446507Y170701D02*
G03I-510J0D01*
G37*
G36*
G01X440749Y240381D02*
G03I-720J0D01*
G37*
G36*
G01X444120Y247880D02*
G03I-720J0D01*
G37*
G36*
G01X459760Y320130D02*
X510850D01*
X512230Y318750D01*
Y279960D01*
X511903Y279633D01*
X503744D01*
X502814Y280563D01*
Y305369D01*
X501780Y306403D01*
X499233D01*
X494233D01*
X490273Y310363D01*
X483343D01*
X481863Y311843D01*
X477803D01*
X477263Y311303D01*
Y303483D01*
X476498Y302718D01*
X453928D01*
X452560Y301350D01*
X452380Y301170D01*
Y282140D01*
X452180Y281940D01*
X450380D01*
X448900D01*
X448230Y282610D01*
Y308600D01*
X450380Y310750D01*
X459760Y320130D01*
G37*
G36*
G01X457733Y289555D02*
X458103Y289185D01*
X458263Y289025D01*
Y279330D01*
X458013Y279080D01*
X456860D01*
X456185Y279755D01*
X454085D01*
X453535Y280305D01*
Y289170D01*
X454223Y289858D01*
X457430D01*
X457733Y289555D01*
G37*
G36*
G01X441830Y298170D02*
G03I-510J0D01*
G37*
G36*
G01X477843Y299703D02*
X472243D01*
X470248Y301698D01*
X454358D01*
X454093Y301433D01*
X453687Y301027D01*
Y294739D01*
Y293247D01*
X454621Y292313D01*
X455113D01*
X463633D01*
X470043Y298723D01*
X477843D01*
X477903Y298783D01*
Y299643D01*
X477843Y299703D01*
G37*
G36*
G01X441830Y304170D02*
G03I-510J0D01*
G37*
G36*
G01Y310170D02*
G03I-510J0D01*
G37*
G36*
G01X451791Y566218D02*
Y579538D01*
X453101Y580848D01*
X482191D01*
X483131Y579908D01*
Y566288D01*
Y560268D01*
X481591Y558728D01*
X453221D01*
X451791Y560158D01*
Y566218D01*
G37*
G36*
G01X446227Y687114D02*
X445936Y687405D01*
Y701599D01*
X446058Y701721D01*
X465851D01*
X466157Y701415D01*
Y691315D01*
X467446Y690026D01*
X469246D01*
X469457Y689815D01*
Y687915D01*
X468656Y687114D01*
X446227D01*
G37*
G36*
G01X472657Y712646D02*
X475157Y710146D01*
X475691Y709612D01*
Y696381D01*
X477631Y694441D01*
X498431D01*
X499257Y693615D01*
Y688815D01*
X498420Y687978D01*
X477094D01*
X470157Y694915D01*
Y703093D01*
X467330Y705920D01*
X446883D01*
X446157Y706646D01*
Y711646D01*
X447157Y712646D01*
X472657D01*
G37*
G36*
G01X536251Y794658D02*
X560626Y770283D01*
Y669053D01*
X558891Y667318D01*
X546131D01*
X545238Y666425D01*
Y662744D01*
X544222Y661728D01*
X535975D01*
X535288Y662415D01*
X513757D01*
X513151Y663021D01*
Y682221D01*
X507774Y687598D01*
X507711D01*
X507156Y688153D01*
X501886D01*
X501257Y688782D01*
Y694815D01*
X499494Y696578D01*
X478694D01*
X477957Y697315D01*
Y710715D01*
X474026Y714646D01*
X467726D01*
X467157Y715215D01*
Y721315D01*
X466394Y722078D01*
X445225D01*
X443851Y723452D01*
Y794368D01*
X444142Y794658D01*
X536251D01*
G37*
G36*
G01X444833Y1450295D02*
G03I-519J0D01*
G37*
G36*
G01X446743Y1452895D02*
G03I-519J0D01*
G37*
G36*
G01X444833Y1455495D02*
G03I-519J0D01*
G37*
G36*
G01X453453Y1474895D02*
G03I-519J0D01*
G37*
G36*
G01X451543Y1472295D02*
G03I-519J0D01*
G37*
G36*
G01X453453Y1469695D02*
G03I-519J0D01*
G37*
G36*
G01X464508Y1527011D02*
X466134D01*
G02X466199Y1527000I0J-200D01*
G01X467113Y1526686D01*
G03X467519Y1526607I487J1420D01*
G01X467558Y1526605D01*
X467627Y1526573D01*
X467843Y1526345D01*
G02X467898Y1526207I-145J-138D01*
G01Y1524099D01*
G02X467843Y1523961I-200J0D01*
G01X467627Y1523733D01*
X467558Y1523701D01*
X467519Y1523699D01*
G03X467204Y1523648I81J-1499D01*
G01X465982Y1523313D01*
G02X465929Y1523306I-52J193D01*
G01X464242D01*
G02X464172Y1523319I1J200D01*
G01X463401Y1523607D01*
G03X462876Y1523702I-526J-1407D01*
G03X462479Y1523648I2J-1502D01*
G01X461258Y1523313D01*
G02X461205Y1523306I-52J193D01*
G01X459518D01*
G02X459448Y1523319I1J200D01*
G01X458677Y1523607D01*
G03X458152Y1523702I-526J-1407D01*
G03X457755Y1523648I2J-1502D01*
G01X456533Y1523313D01*
G02X456480Y1523306I-52J193D01*
G01X454793D01*
G02X454723Y1523319I1J200D01*
G01X453952Y1523607D01*
G03X453427Y1523702I-526J-1407D01*
G03X453030Y1523648I2J-1502D01*
G01X451809Y1523313D01*
G02X451756Y1523306I-52J193D01*
G01X450353D01*
G02X450211Y1523365I0J200D01*
G01X450049Y1523527D01*
G02X449990Y1523669I141J142D01*
G01Y1526626D01*
G02X450119Y1526813I200J0D01*
G01X450603Y1526998D01*
G02X450675Y1527011I71J-187D01*
G01X451960D01*
G02X452025Y1527000I0J-200D01*
G01X452939Y1526686D01*
G03X453427Y1526604I489J1420D01*
G03X453849Y1526665I-2J1502D01*
G01X455003Y1527003D01*
G02X455059Y1527011I56J-192D01*
G01X456685D01*
G02X456750Y1527000I0J-200D01*
G01X457664Y1526686D01*
G03X458152Y1526604I489J1420D01*
G03X458574Y1526665I-2J1502D01*
G01X459728Y1527003D01*
G02X459784Y1527011I56J-192D01*
G01X461409D01*
G02X461474Y1527000I0J-200D01*
G01X462388Y1526686D01*
G03X462876Y1526604I489J1420D01*
G03X463298Y1526665I-2J1502D01*
G01X464452Y1527003D01*
G02X464508Y1527011I56J-192D01*
G37*
G36*
G01X444683Y1623900D02*
X448819D01*
X448918Y1623835D01*
X448942Y1623779D01*
G03X449993Y1622998I1197J513D01*
G01X450042Y1622993D01*
X450123Y1622938D01*
X450327Y1622564D01*
X450329Y1622466D01*
X450307Y1622422D01*
G03X450159Y1621796I1254J-627D01*
G03X450676Y1620708I1403J0D01*
G02X450750Y1620553I-126J-155D01*
G01Y1616981D01*
G02X450691Y1616839I-200J0D01*
G01X450333Y1616481D01*
X450258Y1616451D01*
X450216Y1616452D01*
X450180D01*
G03X449822Y1616409I-1J-1502D01*
G01X449799Y1616403D01*
X444551D01*
G02X444409Y1616462I0J200D01*
G01X444148Y1616723D01*
G02X444089Y1616865I141J142D01*
G01Y1623306D01*
G02X444148Y1623448I200J0D01*
G01X444541Y1623841D01*
G02X444683Y1623900I142J-141D01*
G37*
G36*
G01X441488Y1637104D02*
X444134D01*
G02X444275Y1637045I-1J-200D01*
G01X444399Y1636921D01*
G03X445631Y1636298I1564J1564D01*
G01X445706Y1636287D01*
X445802Y1636176D01*
Y1635500D01*
G03X446449Y1633936I2211J-1D01*
G01X446770Y1633615D01*
G02X446829Y1633474I-141J-142D01*
G01Y1631695D01*
G02X446770Y1631553I-200J0D01*
G01X445926Y1630709D01*
G02X445784Y1630650I-142J141D01*
G01X440090D01*
G02X439948Y1630709I0J200D01*
G01X439540Y1631117D01*
G02X439481Y1631259I141J142D01*
G01Y1636569D01*
G02X439540Y1636711I200J0D01*
G01X439640Y1636811D01*
G02X439782Y1636870I142J-141D01*
G01X440070D01*
X440086Y1636886D01*
X441104D01*
G03X441246Y1636945I0J200D01*
G01X441346Y1637045D01*
G02X441488Y1637104I142J-141D01*
G37*
G36*
G01X458012Y87011D02*
G03I-510J0D01*
G37*
G36*
G01X464966Y93101D02*
G03I-510J0D01*
G37*
G36*
G01X457566D02*
G03I-510J0D01*
G37*
G36*
G01X464561Y224799D02*
G03I-510J0D01*
G37*
G36*
G01X464122Y229970D02*
G03I-720J0D01*
G37*
G36*
G01X458451Y237588D02*
G03I-720J0D01*
G37*
G36*
G01X464373Y237390D02*
G03I-720J0D01*
G37*
G36*
G01X468364Y353417D02*
G03I-720J0D01*
G37*
G36*
G01X472493Y689415D02*
Y685887D01*
X470809Y684203D01*
X469114D01*
X468805Y684512D01*
Y685815D01*
X470479Y687489D01*
Y687882D01*
Y689537D01*
X470657Y689715D01*
X472193D01*
X472493Y689415D01*
G37*
G36*
G01X458243Y1462595D02*
G03I-519J0D01*
G37*
G36*
G01X460153Y1459995D02*
G03I-519J0D01*
G37*
G36*
G01X464933D02*
G03I-519J0D01*
G37*
G36*
G01X466843Y1462595D02*
G03I-519J0D01*
G37*
G36*
G01X466853Y1455495D02*
G03I-519J0D01*
G37*
G36*
G01X464943Y1452895D02*
G03I-519J0D01*
G37*
G36*
G01X466853Y1450295D02*
G03I-519J0D01*
G37*
G36*
G01X458233Y1469695D02*
G03I-519J0D01*
G37*
G36*
G01X460143Y1472295D02*
G03I-519J0D01*
G37*
G36*
G01X458233Y1474895D02*
G03I-519J0D01*
G37*
G36*
G01X460153Y1465195D02*
G03I-519J0D01*
G37*
G36*
G01X464933D02*
G03I-519J0D01*
G37*
G36*
G01X469308Y1527011D02*
X470858D01*
G02X470923Y1527000I0J-200D01*
G01X471837Y1526686D01*
G03X472288Y1526605I488J1420D01*
G01X472327Y1526604D01*
X472398Y1526573D01*
X472621Y1526345D01*
G02X472678Y1526205I-143J-140D01*
G01Y1524101D01*
G02X472621Y1523961I-200J0D01*
G01X472398Y1523733D01*
X472327Y1523702D01*
X472288Y1523701D01*
G03X471928Y1523648I37J-1501D01*
G01X470706Y1523313D01*
G02X470653Y1523306I-52J193D01*
G01X469264D01*
G02X469122Y1523365I0J200D01*
G01X468958Y1523529D01*
G02X468899Y1523671I141J142D01*
G01Y1526602D01*
G02X468958Y1526744I200J0D01*
G01X469166Y1526952D01*
G02X469308Y1527011I142J-141D01*
G37*
G36*
G01X466551Y1664913D02*
G03I-510J0D01*
G37*
G36*
G01X465244Y1730518D02*
G03I-510J0D01*
G37*
G36*
G01X485495Y122639D02*
X497725D01*
G02X497867Y122580I0J-200D01*
G01X500229Y120218D01*
G03X500371Y120159I142J141D01*
G01X505418D01*
G02X505603Y120036I0J-200D01*
G01X505626Y119979D01*
X505603Y119861D01*
X503886Y118144D01*
X503700Y117958D01*
X500946D01*
X499635D01*
X499364Y117687D01*
X499165Y117488D01*
Y116988D01*
X499105Y116928D01*
X497264D01*
G03X497064Y116728I1J-201D01*
G01Y116084D01*
G02X496864Y115884I-200J0D01*
G01X496828D01*
Y115862D01*
X496712Y115744D01*
X490244D01*
G02X490102Y115803I0J200D01*
G01X489309Y116596D01*
G02X489250Y116738I141J142D01*
G01Y119243D01*
G03X488749Y119744I-501J0D01*
G01X485149D01*
G03X484648Y119243I0J-501D01*
G01Y115243D01*
G03X485149Y114742I501J0D01*
G01X487654D01*
G02X487796Y114683I0J-200D01*
G01X488802Y113676D01*
G03X489659Y113322I856J857D01*
G01X489787D01*
G02X489955Y113229I-1J-200D01*
G01X490164Y112903D01*
X490171Y112801D01*
X490150Y112755D01*
G03X490040Y112249I1109J-506D01*
G01Y110515D01*
G03X490394Y109658I1211J-1D01*
G01X490691Y109362D01*
G02X490750Y109220I-141J-142D01*
G01Y107959D01*
G03X491251Y107458I501J0D01*
G01X494851D01*
G03X495352Y107959I0J501D01*
G01Y111258D01*
G02X495552Y111458I200J0D01*
G01X495589D01*
G02X495731Y111399I0J-200D01*
G01X496712Y110417D01*
G03X497025Y110191I857J857D01*
G01X497077Y110166D01*
X497136Y110070D01*
Y109890D01*
G03X497336Y109690I199J-1D01*
G01X499434D01*
G03X499634Y109890I0J199D01*
G01Y109946D01*
X499752Y110062D01*
X500303D01*
X500360Y110045D01*
X500385Y110028D01*
G03X500955Y109797I837J1248D01*
G01X501155Y109597D01*
X504158D01*
X504470Y109909D01*
X504634Y110073D01*
G03X505331Y110417I-160J1202D01*
G01X506689Y111775D01*
G02X506907Y111819I142J-141D01*
G01X506963Y111795D01*
X507030Y111696D01*
Y108614D01*
G02X506971Y108472I-200J0D01*
G01X504292Y105793D01*
G02X504150Y105734I-142J141D01*
G01X502380D01*
G02X502238Y105793I0J200D01*
G01X501216Y106815D01*
G03X501074Y106874I-142J-141D01*
G01X497566D01*
G03X497424Y106815I0J-200D01*
G01X495387Y104778D01*
G02X495245Y104719I-142J141D01*
G01X485835D01*
G02X485693Y104778I0J200D01*
G01X481829Y108642D01*
G02X481770Y108784I141J142D01*
G01Y118914D01*
G02X481829Y119056I200J0D01*
G01X485353Y122580D01*
G02X485495Y122639I142J-141D01*
G37*
G36*
G01X471535Y128020D02*
G03I-640J0D01*
G37*
G36*
G01X478935D02*
G03I-640J0D01*
G37*
G36*
G01X482895Y127322D02*
G03I-640J0D01*
G37*
G36*
G01Y135722D02*
G03I-640J0D01*
G37*
G36*
G01X480270Y141942D02*
G03I-640J0D01*
G37*
G36*
G01X484520Y270440D02*
G03I-720J0D01*
G37*
G36*
G01X481375Y287536D02*
G02X481365Y287525I-151J127D01*
G01X481053Y287213D01*
X475764D01*
G02X475625Y287271I1J197D01*
G01X475426Y287470D01*
G02X475368Y287609I139J140D01*
G01Y289327D01*
G02X475426Y289466I197J-1D01*
G01X477074Y291114D01*
X477290D01*
X478307Y292131D01*
Y293266D01*
G03X478327Y293510I-1482J244D01*
G03X478302Y293785I-1501J2D01*
G01Y294877D01*
X478892D01*
X481375Y292395D01*
Y287536D01*
G37*
G36*
G01X478864Y303551D02*
X478315D01*
X478303Y303563D01*
Y310593D01*
X478523Y310813D01*
X481073D01*
X481323Y310563D01*
X481783Y310103D01*
Y306470D01*
X478864Y303551D01*
G37*
G36*
G01X499253Y289493D02*
X491473D01*
X491035Y289931D01*
Y300399D01*
X490731Y300703D01*
X488963D01*
X472693D01*
X472583Y300813D01*
Y301573D01*
X472683Y301673D01*
X483083D01*
X485793Y304383D01*
Y306183D01*
Y306523D01*
X488150Y308880D01*
X490146D01*
X490983Y308043D01*
X494013Y305013D01*
X498563D01*
X500625D01*
X501150Y304488D01*
Y290187D01*
X500456Y289493D01*
X499253D01*
G37*
G36*
G01X501234Y660614D02*
X478827D01*
X478536Y660905D01*
Y675099D01*
X478658Y675221D01*
X498251D01*
X498457Y675015D01*
Y664615D01*
X499546Y663526D01*
X501504D01*
X502091Y662939D01*
Y661471D01*
X501234Y660614D01*
G37*
G36*
G01X480157Y685915D02*
X506314D01*
X511151Y681078D01*
Y661721D01*
X512694Y660178D01*
X530651D01*
X531051Y659778D01*
Y654646D01*
X530820Y654415D01*
X508257D01*
X507294D01*
X506161Y655548D01*
Y664696D01*
X504157Y666700D01*
Y675646D01*
X500025Y679778D01*
X480294D01*
X479657Y680415D01*
Y685415D01*
X480157Y685915D01*
G37*
G36*
G01X471633Y1450295D02*
G03I-519J0D01*
G37*
G36*
G01X473543Y1452895D02*
G03I-519J0D01*
G37*
G36*
G01X471633Y1455495D02*
G03I-519J0D01*
G37*
G36*
G01X480253Y1474895D02*
G03I-519J0D01*
G37*
G36*
G01X478343Y1472295D02*
G03I-519J0D01*
G37*
G36*
G01X480253Y1469695D02*
G03I-519J0D01*
G37*
G36*
G01X474360Y1527011D02*
X475582D01*
G02X475647Y1527000I0J-200D01*
G01X476561Y1526686D01*
G03X477003Y1526605I489J1420D01*
G01X477042Y1526604D01*
X477113Y1526573D01*
X477334Y1526345D01*
G02X477390Y1526205I-144J-139D01*
G01Y1524101D01*
G02X477334Y1523961I-200J-1D01*
G01X477113Y1523733D01*
X477042Y1523702D01*
X477003Y1523701D01*
G03X476652Y1523648I47J-1501D01*
G01X475431Y1523313D01*
G02X475378Y1523306I-52J193D01*
G01X474066D01*
G02X473924Y1523365I0J200D01*
G01X473738Y1523551D01*
G02X473679Y1523693I141J142D01*
G01Y1526330D01*
G02X473738Y1526472I200J0D01*
G01X474218Y1526952D01*
G02X474360Y1527011I142J-141D01*
G37*
G36*
G01X488127Y1527010D02*
X489079D01*
G02X489221Y1526951I0J-200D01*
G01X489479Y1526693D01*
G02X489538Y1526552I-141J-142D01*
G01Y1525527D01*
G03X489596Y1525386I200J0D01*
G01X489602Y1525380D01*
X489632Y1525307D01*
Y1525276D01*
X489969Y1524939D01*
X490042Y1524909D01*
X490073D01*
X490365Y1524617D01*
G03X490506Y1524558I142J141D01*
G01X491630D01*
G02X491830Y1524358I0J-200D01*
G01Y1524090D01*
G02X491763Y1523941I-200J0D01*
G01X491509Y1523714D01*
X491429Y1523688D01*
X491386Y1523693D01*
G03X491223Y1523702I-164J-1493D01*
G03X490826Y1523648I2J-1502D01*
G01X489604Y1523313D01*
G02X489551Y1523306I-52J193D01*
G01X487864D01*
G02X487794Y1523319I1J200D01*
G01X487023Y1523607D01*
G03X486498Y1523702I-526J-1407D01*
G03X486101Y1523648I2J-1502D01*
G01X484880Y1523313D01*
G02X484827Y1523306I-52J193D01*
G01X483140D01*
G02X483070Y1523319I1J200D01*
G01X482299Y1523607D01*
G03X481774Y1523702I-526J-1407D01*
G03X481377Y1523648I2J-1502D01*
G01X480155Y1523313D01*
G02X480102Y1523306I-52J193D01*
G01X478708D01*
G02X478566Y1523365I0J200D01*
G01X478451Y1523480D01*
G02X478392Y1523622I141J142D01*
G01Y1526271D01*
G02X478451Y1526413I200J0D01*
G01X478989Y1526951D01*
G02X479131Y1527010I142J-141D01*
G01X480310D01*
G02X480375Y1526999I0J-200D01*
G01X481286Y1526686D01*
G03X481774Y1526604I489J1420D01*
G03X482196Y1526665I-2J1502D01*
G01X483347Y1527002D01*
G02X483403Y1527010I56J-192D01*
G01X485034D01*
G02X485099Y1526999I0J-200D01*
G01X486010Y1526686D01*
G03X486498Y1526604I489J1420D01*
G03X486920Y1526665I-2J1502D01*
G01X488071Y1527002D01*
G02X488127Y1527010I56J-192D01*
G37*
G36*
G01X763817Y31663D02*
X763943Y31722D01*
X764389Y31615D01*
G02X764543Y31421I-46J-195D01*
G01Y22987D01*
G02X764343Y22787I-200J0D01*
G01X498665D01*
G02X498465Y22987I0J200D01*
G01Y31421D01*
G02X498619Y31615I200J-1D01*
G01X499065Y31722D01*
X499191Y31663D01*
X499222Y31601D01*
G03X500378Y30253I3306J1666D01*
G01X500462Y30091D01*
Y24784D01*
X762546D01*
Y30091D01*
X762630Y30253D01*
G03X763786Y31601I-2150J3014D01*
G01X763817Y31663D01*
G37*
G36*
G01X488520Y131442D02*
G03I-640J0D01*
G37*
G36*
G01X496920D02*
G03I-640J0D01*
G37*
G36*
G01X489220Y141942D02*
G03I-640J0D01*
G37*
G36*
G01X489628Y242754D02*
G03I-720J0D01*
G37*
G36*
G01X488796Y350420D02*
G03I-720J0D01*
G37*
G36*
G01X485043Y1462595D02*
G03I-519J0D01*
G37*
G36*
G01X486953Y1459995D02*
G03I-519J0D01*
G37*
G36*
G01X491733D02*
G03I-519J0D01*
G37*
G36*
G01X493643Y1462595D02*
G03I-519J0D01*
G37*
G36*
G01X493653Y1455495D02*
G03I-519J0D01*
G37*
G36*
G01X491743Y1452895D02*
G03I-519J0D01*
G37*
G36*
G01X493653Y1450295D02*
G03I-519J0D01*
G37*
G36*
G01X498433D02*
G03I-519J0D01*
G37*
G36*
G01Y1455495D02*
G03I-519J0D01*
G37*
G36*
G01X485033Y1474895D02*
G03I-519J0D01*
G37*
G36*
G01X486943Y1472295D02*
G03I-519J0D01*
G37*
G36*
G01X485033Y1469695D02*
G03I-519J0D01*
G37*
G36*
G01X486953Y1465195D02*
G03I-519J0D01*
G37*
G36*
G01X491733D02*
G03I-519J0D01*
G37*
G36*
G01X497579Y1527011D02*
X498528D01*
G02X498670Y1526952I0J-200D01*
G01X498983Y1526639D01*
G02X499042Y1526498I-141J-142D01*
G01Y1523809D01*
G02X498983Y1523668I-200J1D01*
G01X498680Y1523365D01*
G02X498538Y1523306I-142J141D01*
G01X497313D01*
G02X497243Y1523319I1J200D01*
G01X496472Y1523607D01*
G03X495947Y1523702I-526J-1407D01*
G03X495686Y1523679I0J-1492D01*
G01X495638Y1523670D01*
X495545Y1523699D01*
X495467Y1523777D01*
G02X495408Y1523918I141J142D01*
G01Y1526382D01*
G02X495467Y1526523I200J-1D01*
G01X495550Y1526606D01*
X495641Y1526635D01*
X495691Y1526627D01*
G03X495947Y1526604I262J1478D01*
G03X496369Y1526665I-2J1502D01*
G01X497523Y1527003D01*
G02X497579Y1527011I56J-192D01*
G37*
G36*
G01X492384Y1526873D02*
X494181D01*
G02X494323Y1526814I0J-200D01*
G01X494348Y1526789D01*
G02X494407Y1526647I-141J-142D01*
G01Y1523865D01*
G02X494348Y1523723I-200J0D01*
G01X494072Y1523447D01*
G02X493930Y1523388I-142J141D01*
G01X493200D01*
G02X493058Y1523447I0J200D01*
G01X492890Y1523615D01*
G02X492831Y1523757I141J142D01*
G01Y1525154D01*
G03X492772Y1525296I-200J0D01*
G01X492567Y1525501D01*
G03X492425Y1525560I-142J-141D01*
G01X490921D01*
G02X490779Y1525619I0J200D01*
G01X490598Y1525800D01*
G02X490539Y1525942I141J142D01*
G01Y1526384D01*
G02X490598Y1526526I200J0D01*
G01X490706Y1526634D01*
X490807Y1526662D01*
X490859Y1526649D01*
G03X491223Y1526604I365J1457D01*
G03X491645Y1526665I-2J1502D01*
G01X492327Y1526865D01*
G02X492384Y1526873I56J-192D01*
G37*
G36*
G01X531940Y1587647D02*
Y1571493D01*
G02X531881Y1571351I-200J0D01*
G01X531139Y1570609D01*
G02X530997Y1570550I-142J141D01*
G01X500043D01*
G02X499901Y1570609I0J200D01*
G01X498009Y1572501D01*
G02X497950Y1572643I141J142D01*
G01Y1587177D01*
G02X498009Y1587319I200J0D01*
G01X498751Y1588061D01*
G02X498893Y1588120I142J-141D01*
G01X531467D01*
G02X531609Y1588061I0J-200D01*
G01X531881Y1587789D01*
G02X531940Y1587647I-141J-142D01*
G37*
G36*
G01X513294Y94967D02*
G03I-640J0D01*
G37*
G36*
G01X512491Y199576D02*
G03I-720J0D01*
G37*
G36*
G01X500989Y225071D02*
G03I-720J0D01*
G37*
G36*
G01X502438Y240558D02*
G03I-720J0D01*
G37*
G36*
G01X513230Y314610D02*
Y279820D01*
X513566Y279484D01*
X526910D01*
X527110Y279684D01*
Y315044D01*
X526910Y315244D01*
X513864D01*
X513230Y314610D01*
G37*
G36*
G01X512657Y645278D02*
X512157Y645778D01*
Y651415D01*
X513157Y652415D01*
X558357D01*
X562257Y648515D01*
Y636115D01*
X561788Y635646D01*
X540157D01*
X537657Y638146D01*
Y643646D01*
X536025Y645278D01*
X512657D01*
G37*
G36*
G01X503623Y657703D02*
X501743D01*
X501405Y658041D01*
Y659315D01*
X503079Y660989D01*
X503098Y661008D01*
Y663115D01*
X503181Y663198D01*
X504961D01*
X505093Y663066D01*
Y659173D01*
X503623Y657703D01*
G37*
G36*
G01X506771Y865338D02*
G03I-510J0D01*
G37*
G36*
G01X500343Y1452895D02*
G03I-519J0D01*
G37*
G36*
G01X511843Y1462595D02*
G03I-519J0D01*
G37*
G36*
G01X513753Y1459995D02*
G03I-519J0D01*
G37*
G36*
G01X507053Y1474895D02*
G03I-519J0D01*
G37*
G36*
G01X505143Y1472295D02*
G03I-519J0D01*
G37*
G36*
G01X507053Y1469695D02*
G03I-519J0D01*
G37*
G36*
G01X511833Y1474895D02*
G03I-519J0D01*
G37*
G36*
G01X513743Y1472295D02*
G03I-519J0D01*
G37*
G36*
G01X511833Y1469695D02*
G03I-519J0D01*
G37*
G36*
G01X513753Y1465195D02*
G03I-519J0D01*
G37*
G36*
G01X521201Y1527011D02*
X522177D01*
G02X522283Y1526981I1J-200D01*
G01X522555Y1526810D01*
G02X522591Y1526782I-104J-171D01*
G01X522656Y1526717D01*
G02X522715Y1526575I-141J-142D01*
G01Y1523591D01*
G02X522656Y1523449I-200J0D01*
G01X522572Y1523365D01*
G02X522430Y1523306I-142J141D01*
G01X520935D01*
G02X520865Y1523319I1J200D01*
G01X520094Y1523607D01*
G03X519569Y1523702I-526J-1407D01*
G03X519172Y1523648I2J-1502D01*
G01X517951Y1523313D01*
G02X517898Y1523306I-52J193D01*
G01X516211D01*
G02X516141Y1523319I1J200D01*
G01X515370Y1523607D01*
G03X514845Y1523702I-526J-1407D01*
G03X514448Y1523648I2J-1502D01*
G01X513226Y1523313D01*
G02X513173Y1523306I-52J193D01*
G01X511486D01*
G02X511416Y1523319I1J200D01*
G01X510645Y1523607D01*
G03X510120Y1523702I-526J-1407D01*
G03X509723Y1523648I2J-1502D01*
G01X508502Y1523313D01*
G02X508449Y1523306I-52J193D01*
G01X506762D01*
G02X506692Y1523319I1J200D01*
G01X505921Y1523607D01*
G03X505486Y1523699I-525J-1407D01*
G01X505447Y1523701D01*
X505378Y1523733D01*
X505164Y1523961D01*
G02X505110Y1524098I146J137D01*
G01Y1526208D01*
G02X505164Y1526345I200J0D01*
G01X505378Y1526573D01*
X505447Y1526605D01*
X505486Y1526607D01*
G03X505818Y1526665I-91J1499D01*
G01X506972Y1527003D01*
G02X507028Y1527011I56J-192D01*
G01X508653D01*
G02X508718Y1527000I0J-200D01*
G01X509632Y1526686D01*
G03X510120Y1526604I489J1420D01*
G03X510542Y1526665I-2J1502D01*
G01X511696Y1527003D01*
G02X511752Y1527011I56J-192D01*
G01X513378D01*
G02X513443Y1527000I0J-200D01*
G01X514357Y1526686D01*
G03X514845Y1526604I489J1420D01*
G03X515267Y1526665I-2J1502D01*
G01X516421Y1527003D01*
G02X516477Y1527011I56J-192D01*
G01X518102D01*
G02X518167Y1527000I0J-200D01*
G01X519081Y1526686D01*
G03X519569Y1526604I489J1420D01*
G03X519991Y1526665I-2J1502D01*
G01X521145Y1527003D01*
G02X521201Y1527011I56J-192D01*
G37*
G36*
G01X502303D02*
X503788D01*
G02X503930Y1526952I0J-200D01*
G01X504049Y1526833D01*
G02X504108Y1526691I-141J-142D01*
G01Y1523776D01*
G02X504049Y1523634I-200J0D01*
G01X503780Y1523365D01*
G02X503638Y1523306I-142J141D01*
G01X502037D01*
G02X501967Y1523319I1J200D01*
G01X501196Y1523607D01*
G03X500671Y1523702I-526J-1407D01*
G03X500394Y1523676I1J-1502D01*
G01X500345Y1523666D01*
X500250Y1523696D01*
X500102Y1523844D01*
G02X500043Y1523986I141J142D01*
G01Y1526218D01*
G02X500110Y1526368I200J1D01*
G01X500366Y1526595D01*
X500448Y1526620D01*
X500491Y1526615D01*
G03X500671Y1526604I181J1491D01*
G03X501093Y1526665I-2J1502D01*
G01X502247Y1527003D01*
G02X502303Y1527011I56J-192D01*
G37*
G36*
G01X524471Y95445D02*
G03I-640J0D01*
G37*
G36*
G01Y102931D02*
G03I-640J0D01*
G37*
G36*
G01X516660Y102870D02*
G03I-640J0D01*
G37*
G36*
G01X519880Y94967D02*
G03I-640J0D01*
G37*
G36*
G01X516660Y111770D02*
G03I-640J0D01*
G37*
G36*
G01X517082Y865327D02*
G03I-510J0D01*
G37*
G36*
G01X518533Y1459995D02*
G03I-519J0D01*
G37*
G36*
G01X520443Y1462595D02*
G03I-519J0D01*
G37*
G36*
G01X520453Y1455495D02*
G03I-519J0D01*
G37*
G36*
G01X518543Y1452895D02*
G03I-519J0D01*
G37*
G36*
G01X520453Y1450295D02*
G03I-519J0D01*
G37*
G36*
G01X525233D02*
G03I-519J0D01*
G37*
G36*
G01X527143Y1452895D02*
G03I-519J0D01*
G37*
G36*
G01X525233Y1455495D02*
G03I-519J0D01*
G37*
G36*
G01X518533Y1465195D02*
G03I-519J0D01*
G37*
G36*
G01X543917Y88632D02*
G03I-640J0D01*
G37*
G36*
G01X535810Y108730D02*
G03I-640J0D01*
G37*
G36*
G01Y117630D02*
G03I-640J0D01*
G37*
G36*
G01X546760Y329130D02*
X597850D01*
X599230Y327750D01*
Y288960D01*
X598903Y288633D01*
X589703D01*
X589418Y288918D01*
Y314082D01*
X588000Y315500D01*
X586330D01*
X586233Y315403D01*
X581233D01*
X577273Y319363D01*
X570343D01*
X568863Y320843D01*
X564803D01*
X564263Y320303D01*
Y312483D01*
X563498Y311718D01*
X540928D01*
X539560Y310350D01*
Y300573D01*
X539586Y300546D01*
Y289407D01*
X539031Y288852D01*
X535778D01*
X535120Y289510D01*
Y317490D01*
X537560Y319930D01*
X546760Y329130D01*
G37*
G36*
G01X541513Y298761D02*
X545020D01*
X545853Y297928D01*
Y288233D01*
X545603Y287983D01*
X541075D01*
X540825Y288233D01*
Y298073D01*
X541513Y298761D01*
G37*
G36*
G01X564843Y308703D02*
X559243D01*
X557248Y310698D01*
X541358D01*
X541093Y310433D01*
X540687Y310027D01*
Y303739D01*
Y302247D01*
X541621Y301313D01*
X542113D01*
X550633D01*
X557043Y307723D01*
X564843D01*
X564903Y307783D01*
Y308643D01*
X564843Y308703D01*
G37*
G36*
G01X544291Y597288D02*
X538841D01*
X537951Y598178D01*
Y610138D01*
X536651Y611438D01*
X535171D01*
X534771Y611838D01*
Y615488D01*
X535060Y615777D01*
X536832D01*
X539371Y613238D01*
X543471D01*
X544711Y611998D01*
Y608838D01*
Y597708D01*
X544291Y597288D01*
G37*
G36*
G01X533853Y1455495D02*
G03I-519J0D01*
G37*
G36*
G01X531943Y1452895D02*
G03I-519J0D01*
G37*
G36*
G01X533853Y1450295D02*
G03I-519J0D01*
G37*
G36*
G01X538633D02*
G03I-519J0D01*
G37*
G36*
G01X540543Y1452895D02*
G03I-519J0D01*
G37*
G36*
G01X538633Y1455495D02*
G03I-519J0D01*
G37*
G36*
G01X542713Y1484772D02*
G03I-519J0D01*
G37*
G36*
G01Y1479992D02*
G03I-519J0D01*
G37*
G36*
G01Y1498172D02*
G03I-519J0D01*
G37*
G36*
G01Y1493392D02*
G03I-519J0D01*
G37*
G36*
G01X543211Y1520883D02*
X544715D01*
G02X544857Y1520824I0J-200D01*
G01X545288Y1520393D01*
G02X545347Y1520251I-141J-142D01*
G01Y1519245D01*
G03X545406Y1519103I200J0D01*
G01X545863Y1518646D01*
G02X545922Y1518505I-141J-142D01*
G01Y1518250D01*
G03X546423Y1517748I502J0D01*
G01X546667D01*
X546704Y1517733D01*
G03X547173Y1517638I470J1117D01*
G03X547642Y1517733I-1J1212D01*
G01X547679Y1517748D01*
X547923D01*
G03X548407Y1518118I0J502D01*
G01X548425Y1518183D01*
X548532Y1518265D01*
X549014D01*
X549121Y1518183D01*
X549139Y1518118D01*
G03X549623Y1517748I484J132D01*
G01X549867D01*
X549904Y1517733D01*
G03X550373Y1517638I470J1117D01*
G03X550842Y1517733I-1J1212D01*
G01X550879Y1517748D01*
X551123D01*
G03X551607Y1518118I0J502D01*
G01X551625Y1518183D01*
X551732Y1518265D01*
X552010D01*
X552073Y1518244D01*
X552100Y1518223D01*
G03X553633Y1517698I1533J1976D01*
G03X555324Y1518356I0J2502D01*
G02X555459Y1518408I134J-148D01*
G01X557226D01*
X557300Y1518378D01*
X557321Y1518357D01*
Y1516696D01*
G02X557215Y1516519I-200J0D01*
G03X556242Y1515584I1183J-2205D01*
G02X556069Y1515486I-172J102D01*
G01X555725D01*
G02X555552Y1515584I-1J200D01*
G03X553397Y1516816I-2155J-1269D01*
G03Y1511812I0J-2502D01*
G03X554719Y1512190I0J2501D01*
G02X554966Y1512161I105J-170D01*
G01X556388Y1510740D01*
X556417Y1510680D01*
X556421Y1510647D01*
G03X556506Y1510331I1202J154D01*
G01X556522Y1510294D01*
Y1510050D01*
G03X556525Y1509994I501J-1D01*
G01X556526Y1509983D01*
Y1509972D01*
G02X556326Y1509772I-200J0D01*
G01X550591D01*
X550567Y1509748D01*
X550082Y1509852D01*
X550005Y1509919D01*
X549987Y1509967D01*
G03X547645Y1511587I-2342J-883D01*
G03X545143Y1509085I0J-2502D01*
G03X546341Y1506950I2501J0D01*
G02X546436Y1506793I-105J-171D01*
G03X546500Y1506478I1209J82D01*
G01X546512Y1506446D01*
Y1506374D01*
G02X546312Y1506174I-200J0D01*
G01X546288D01*
X546266Y1506179D01*
G03X545988Y1506212I-281J-1179D01*
G01X544310D01*
G02X544168Y1506270I-1J200D01*
G01X544059Y1506380D01*
G02X544000Y1506521I141J142D01*
G01Y1508186D01*
G03X543941Y1508328I-200J0D01*
G01X542863Y1509406D01*
G02X542804Y1509548I141J142D01*
G01Y1520476D01*
G02X542863Y1520618I200J0D01*
G01X543069Y1520824D01*
G02X543211Y1520883I142J-141D01*
G37*
G36*
G01X538828Y1540323D02*
X538843Y1540338D01*
G02X538985Y1540397I142J-141D01*
G01X541584D01*
G02X541726Y1540338I0J-200D01*
G01X544821Y1537243D01*
G03X544963Y1537184I142J141D01*
G01X549042D01*
G02X549189Y1537120I0J-200D01*
G01X549417Y1536875D01*
X549444Y1536797D01*
X549441Y1536755D01*
G03X549437Y1536646I1498J-110D01*
G03X552441I1502J0D01*
G03X552249Y1537381I-1503J0D01*
G01X552216Y1537440D01*
X552234Y1537573D01*
X554634Y1539973D01*
G02X554776Y1540032I142J-141D01*
G01X556380D01*
G02X556522Y1539973I0J-200D01*
G01X557015Y1539480D01*
G02X557074Y1539338I-141J-142D01*
G01Y1535636D01*
G02X557015Y1535494I-200J0D01*
G01X556233Y1534712D01*
G02X556092Y1534654I-141J142D01*
G01X554396D01*
G03X553932Y1534561I0J-1204D01*
G01X551865Y1533705D01*
G02X551789Y1533690I-76J185D01*
G01X546073D01*
G03X545931Y1533631I0J-200D01*
G01X545409Y1533109D01*
G02X545267Y1533050I-142J141D01*
G01X543226D01*
G02X543085Y1533109I1J200D01*
G01X542420Y1533774D01*
G03X541563Y1534128I-856J-857D01*
G01X539259D01*
G02X539118Y1534187I1J200D01*
G01X539093Y1534212D01*
G02X539034Y1534354I141J142D01*
G01Y1535586D01*
G03X538975Y1535728I-200J0D01*
G01X538480Y1536223D01*
G02X538421Y1536365I141J142D01*
G01Y1537765D01*
G02X538480Y1537907I200J0D01*
G01X538769Y1538196D01*
G03X538828Y1538338I-141J142D01*
G01Y1540323D01*
G37*
G36*
G01X537943Y1584970D02*
X545787D01*
G02X545929Y1584911I0J-200D01*
G01X549541Y1581299D01*
G03X549683Y1581240I142J141D01*
G01X563057D01*
G02X563199Y1581181I0J-200D01*
G01X563991Y1580389D01*
G02X564050Y1580247I-141J-142D01*
G01Y1567713D01*
G02X563991Y1567571I-200J0D01*
G01X559969Y1563549D01*
G02X559827Y1563490I-142J141D01*
G01X559603D01*
G03X559461Y1563431I0J-200D01*
G01X549906Y1553876D01*
X549830Y1553845D01*
X549790Y1553846D01*
X549759D01*
G03Y1549842I0J-2002D01*
G01X549780D01*
G02X549920Y1549787I2J-200D01*
G01X550070Y1549645D01*
Y1549612D01*
X550081Y1549601D01*
Y1547899D01*
G03X550140Y1547757I200J0D01*
G01X550236Y1547661D01*
X550260Y1547621D01*
X550267Y1547598D01*
G03X551576Y1546289I1910J601D01*
G01X551599Y1546282D01*
X551639Y1546258D01*
X552164Y1545733D01*
G02X552223Y1545591I-141J-142D01*
G01Y1539061D01*
G02X552164Y1538920I-200J1D01*
G01X551489Y1538244D01*
G02X551347Y1538186I-141J142D01*
G01X545378D01*
G02X545236Y1538244I-1J200D01*
G01X542140Y1541340D01*
G03X541999Y1541398I-141J-142D01*
G01X541980D01*
X541906Y1541429D01*
X541076Y1542259D01*
G03X540934Y1542318I-142J-141D01*
G01X538578D01*
G02X538436Y1542377I0J200D01*
G01X538003Y1542810D01*
G02X537944Y1542952I141J142D01*
G01Y1548133D01*
G03X537885Y1548275I-200J0D01*
G01X537730Y1548430D01*
G02X537672Y1548571I142J141D01*
G01Y1557820D01*
G03X537499Y1558444I-1212J0D01*
G02X537470Y1558547I171J104D01*
G01Y1560167D01*
G03X537411Y1560309I-200J0D01*
G01X536009Y1561711D01*
G02X535950Y1561853I141J142D01*
G01Y1582977D01*
G02X536009Y1583119I200J0D01*
G01X537801Y1584911D01*
G02X537943Y1584970I142J-141D01*
G37*
G36*
G01X554420Y118740D02*
G03I-640J0D01*
G37*
G36*
G01X551145Y114382D02*
G03I-640J0D01*
G37*
G36*
G01X557731D02*
G03I-640J0D01*
G37*
G36*
G01X554420Y127140D02*
G03I-640J0D01*
G37*
G36*
G01X558210Y192240D02*
Y201770D01*
X558940Y202500D01*
X565180D01*
X566270Y201410D01*
Y192570D01*
X565170Y191470D01*
X558980D01*
X558210Y192240D01*
G37*
G36*
G01X550230Y202240D02*
X555580D01*
X556980Y200840D01*
Y188490D01*
X555330Y186840D01*
X553390D01*
X552420Y187810D01*
Y191600D01*
X549460Y194560D01*
Y201470D01*
X550230Y202240D01*
G37*
G36*
G01X553820Y227700D02*
G03I-720J0D01*
G37*
G36*
G01X551920Y377650D02*
G03I-720J0D01*
G37*
G36*
G01X574913Y838505D02*
G02I-13780J0D01*
G37*
G36*
G01Y1199923D02*
G02I-13780J0D01*
G37*
G36*
G01X546450Y1451344D02*
G03I-519J0D01*
G37*
G36*
G01X545333Y1459995D02*
G03I-519J0D01*
G37*
G36*
G01X559505Y1462595D02*
G03I-519J0D01*
G37*
G36*
G01X555867Y1477590D02*
G03I-519J0D01*
G37*
G36*
G01X545313Y1491482D02*
G03I-519J0D01*
G37*
G36*
G01Y1478082D02*
G03I-519J0D01*
G37*
G36*
G01X547913Y1479992D02*
G03I-519J0D01*
G37*
G36*
G01Y1484772D02*
G03I-519J0D01*
G37*
G36*
G01X545313Y1486682D02*
G03I-519J0D01*
G37*
G36*
G01X553267Y1479500D02*
G03I-519J0D01*
G37*
G36*
G01X558467D02*
G03I-519J0D01*
G37*
G36*
G01Y1484280D02*
G03I-519J0D01*
G37*
G36*
G01X555867Y1486190D02*
G03I-519J0D01*
G37*
G36*
G01X553267Y1484280D02*
G03I-519J0D01*
G37*
G36*
G01X547913Y1498172D02*
G03I-519J0D01*
G37*
G36*
G01Y1493392D02*
G03I-519J0D01*
G37*
G36*
G01X558467Y1506080D02*
G03I-519J0D01*
G37*
G36*
G01Y1501300D02*
G03I-519J0D01*
G37*
G36*
G01X555867Y1499490D02*
G03I-519J0D01*
G37*
G36*
G01X553267Y1501300D02*
G03I-519J0D01*
G37*
G36*
G01X555867Y1507990D02*
G03I-519J0D01*
G37*
G36*
G01X555533Y1550570D02*
X563002D01*
G02X563144Y1550511I0J-200D01*
G01X563654Y1550001D01*
G02X563712Y1549860I-142J-141D01*
G01Y1540979D01*
G02X563654Y1540838I-200J0D01*
G01X563450Y1540634D01*
G02X563308Y1540575I-142J141D01*
G01X557419D01*
G02X557278Y1540634I1J200D01*
G01X556936Y1540975D01*
G03X556795Y1541034I-142J-141D01*
G01X554820D01*
G02X554620Y1541234I0J200D01*
G01Y1550079D01*
G02X554679Y1550221I200J0D01*
G01X554779Y1550321D01*
X554838Y1550350D01*
X554871Y1550354D01*
G03X555433Y1550543I-188J1490D01*
G02X555533Y1550570I100J-173D01*
G37*
G36*
G01X565151Y45132D02*
G03I-720J0D01*
G37*
G36*
G01X561888Y100399D02*
G03I-640J0D01*
G37*
G36*
G01X571550Y118310D02*
G03I-640J0D01*
G37*
G36*
G01X561888Y106985D02*
G03I-640J0D01*
G37*
G36*
G01X571550Y127510D02*
G03I-640J0D01*
G37*
G36*
G01X563195Y242721D02*
G03I-720J0D01*
G37*
G36*
G01X568375Y296536D02*
G02X568365Y296525I-151J127D01*
G01X568053Y296213D01*
X562764D01*
G02X562625Y296271I1J197D01*
G01X562426Y296470D01*
G02X562368Y296609I139J140D01*
G01Y298327D01*
G02X562426Y298466I197J-1D01*
G01X564074Y300114D01*
X564290D01*
X565307Y301131D01*
Y302266D01*
G03X565327Y302510I-1482J244D01*
G03X565302Y302785I-1501J2D01*
G01Y303877D01*
X565892D01*
X568375Y301395D01*
Y296536D01*
G37*
G36*
G01X565864Y312551D02*
X565315D01*
X565303Y312563D01*
Y319593D01*
X565523Y319813D01*
X568073D01*
X568323Y319563D01*
X568783Y319103D01*
Y315470D01*
X565864Y312551D01*
G37*
G36*
G01X586260Y298500D02*
X586253Y298493D01*
X578473D01*
X577851Y299115D01*
Y309263D01*
X577411Y309703D01*
X575963D01*
X559693D01*
X559583Y309813D01*
Y310573D01*
X559683Y310673D01*
X570083D01*
X572793Y313383D01*
Y315183D01*
X572815Y315205D01*
Y315515D01*
X575160Y317860D01*
X577166D01*
X577983Y317043D01*
X581013Y314013D01*
X585563D01*
X586987D01*
X588000Y313000D01*
Y299000D01*
X587500Y298500D01*
X586260D01*
G37*
G36*
G01X559609Y1452185D02*
G03I-519J0D01*
G37*
G36*
G01X561415Y1459995D02*
G03I-519J0D01*
G37*
G36*
G01X568115Y1450295D02*
G03I-519J0D01*
G37*
G36*
G01X572895D02*
G03I-519J0D01*
G37*
G36*
G01Y1455495D02*
G03I-519J0D01*
G37*
G36*
G01X568115D02*
G03I-519J0D01*
G37*
G36*
G01X566205Y1452895D02*
G03I-519J0D01*
G37*
G36*
G01X566195Y1459995D02*
G03I-519J0D01*
G37*
G36*
G01X568105Y1462595D02*
G03I-519J0D01*
G37*
G36*
G01X566195Y1465195D02*
G03I-519J0D01*
G37*
G36*
G01X561415D02*
G03I-519J0D01*
G37*
G36*
G01X577255Y1578689D02*
X638001D01*
G02X638143Y1578630I0J-200D01*
G01X644413Y1572360D01*
X648124Y1568648D01*
G03X648266Y1568589I142J141D01*
G01X649989D01*
G02X650146Y1568513I0J-200D01*
G01X650369Y1568231D01*
X650389Y1568143D01*
X650378Y1568097D01*
G03X650338Y1567752I1462J-344D01*
G03X653342I1502J0D01*
G03X653302Y1568097I-1502J1D01*
G01X653291Y1568143D01*
X653311Y1568231D01*
X653534Y1568513D01*
G02X653691Y1568589I157J-124D01*
G01X676081D01*
G02X676244Y1568505I0J-200D01*
G01X676462Y1568199D01*
X676475Y1568104D01*
X676459Y1568058D01*
G03X676348Y1567400I1891J-657D01*
G03X680352I2002J0D01*
G03X680241Y1568058I-2002J1D01*
G01X680225Y1568104D01*
X680238Y1568199D01*
X680456Y1568505D01*
G02X680619Y1568589I163J-116D01*
G01X689195D01*
G02X689337Y1568530I0J-200D01*
G01X693727Y1564140D01*
G02X693786Y1563998I-141J-142D01*
G01Y1559945D01*
G03X693845Y1559803I200J0D01*
G01X699567Y1554081D01*
G02X699626Y1553939I-141J-142D01*
G01Y1530341D01*
G03X699685Y1530199I200J0D01*
G01X700392Y1529492D01*
G03X700534Y1529433I142J141D01*
G01X706317D01*
G02X706459Y1529374I0J-200D01*
G01X728921Y1506912D01*
G02X728980Y1506770I-141J-142D01*
G01Y1472408D01*
X728926Y1472316D01*
X728878Y1472289D01*
G03X728615Y1472090I593J-1057D01*
G01X722497Y1465971D01*
G02X722355Y1465912I-142J141D01*
G01X705226D01*
G02X705030Y1466074I0J200D01*
G01X704941Y1466531D01*
X705010Y1466657D01*
X705077Y1466683D01*
G03X715604Y1482270I-6276J15587D01*
G03X681998I-16803J0D01*
G03X692525Y1466683I16803J0D01*
G01X692592Y1466657D01*
X692661Y1466531D01*
X692572Y1466074D01*
G02X692376Y1465912I-196J38D01*
G01X690019D01*
G03X689162Y1465558I-1J-1211D01*
G01X689153Y1465549D01*
G02X689012Y1465490I-142J141D01*
G01X681973D01*
G02X681831Y1465549I0J200D01*
G01X677839Y1469541D01*
G02X677780Y1469683I141J142D01*
G01Y1503497D01*
G03X677721Y1503639I-200J0D01*
G01X675246Y1506114D01*
X675233Y1506137D01*
G03X675051Y1506319I-434J-252D01*
G01X675028Y1506332D01*
X673981Y1507379D01*
G03X673839Y1507438I-142J-141D01*
G01X673744D01*
G02X673602Y1507497I0J200D01*
G01X673563Y1507536D01*
G02X673504Y1507678I141J142D01*
G01Y1510382D01*
G03X673445Y1510524I-200J0D01*
G01X671985Y1511984D01*
G02X671926Y1512126I141J142D01*
G01Y1516911D01*
G02X671985Y1517053I200J0D01*
G01X672466Y1517534D01*
G02X672608Y1517593I142J-141D01*
G01X675266D01*
G03X675408Y1517652I0J200D01*
G01X676409Y1518653D01*
G03X676468Y1518795I-141J142D01*
G01Y1524229D01*
G03X676409Y1524371I-200J0D01*
G01X674856Y1525924D01*
G02X674797Y1526066I141J142D01*
G01Y1531071D01*
G02X674856Y1531213I200J0D01*
G01X674866Y1531224D01*
X681267D01*
G02X681467Y1531024I0J-200D01*
G01Y1525656D01*
G02X681408Y1525514I-200J0D01*
G01X679724Y1523830D01*
X679666Y1523801D01*
X679633Y1523797D01*
G03X679199Y1523305I67J-497D01*
G01X679198Y1523266D01*
X679169Y1523195D01*
X679149Y1523174D01*
Y1518670D01*
G03X679208Y1518528I200J0D01*
G01X680084Y1517652D01*
G03X680226Y1517593I142J141D01*
G01X688906D01*
G03X689048Y1517652I0J200D01*
G01X690425Y1519029D01*
G03X690484Y1519171I-141J142D01*
G01Y1541253D01*
G02X690543Y1541395I200J0D01*
G01X690569Y1541421D01*
Y1541587D01*
X689916Y1542239D01*
G02X689857Y1542381I141J142D01*
G01Y1553480D01*
G03X689798Y1553622I-200J0D01*
G01X683429Y1559991D01*
G03X683287Y1560050I-142J-141D01*
G01X674523D01*
G02X674369Y1560122I0J200D01*
G01X674143Y1560395D01*
X674121Y1560480D01*
X674130Y1560525D01*
G03X674165Y1560899I-1967J373D01*
G03X672163Y1562901I-2002J0D01*
G03X670934Y1562479I0J-2001D01*
G02X670694Y1562475I-123J158D01*
G03X669524Y1562852I-1169J-1625D01*
G03X668428Y1562525I0J-2002D01*
G02X668196Y1562534I-110J167D01*
G03X666978Y1562947I-1218J-1590D01*
G03X665773Y1562544I0J-2003D01*
G02X665525Y1562549I-121J159D01*
G03X664246Y1563011I-1279J-1539D01*
G03X663151Y1562685I0J-2002D01*
G02X662923Y1562692I-109J168D01*
G03X661731Y1563085I-1191J-1609D01*
G03X659729Y1561083I0J-2002D01*
G03X659800Y1560555I2002J0D01*
G01X659812Y1560510D01*
X659794Y1560419D01*
X659573Y1560129D01*
G02X659414Y1560050I-159J121D01*
G01X657431D01*
G03X657289Y1559991I0J-200D01*
G01X655080Y1557782D01*
G02X654938Y1557723I-142J141D01*
G01X654559D01*
X654536Y1557728D01*
G03X654255Y1557762I-285J-1178D01*
G01X653299D01*
G02X653128Y1557857I-1J200D01*
G03X650995Y1559052I-2133J-1306D01*
G03X649928Y1558813I0J-2501D01*
G02X649843Y1558794I-85J181D01*
G01X633241D01*
G02X633099Y1558853I0J200D01*
G01X631024Y1560928D01*
G03X630882Y1560987I-142J-141D01*
G01X576628D01*
X576591Y1561002D01*
G03X576399Y1561040I-191J-463D01*
G01X576155D01*
X576118Y1561056D01*
G03X575649Y1561150I-468J-1117D01*
G03X575180Y1561056I-1J-1211D01*
G01X575143Y1561040D01*
X575013D01*
X574897Y1561149D01*
X574893Y1561229D01*
G03X572395Y1563581I-2498J-151D01*
G03X569893Y1561079I0J-2502D01*
G03X571929Y1558621I2502J0D01*
G01X572000Y1558607D01*
X572092Y1558497D01*
Y1557571D01*
G02X572033Y1557430I-200J1D01*
G01X571937Y1557334D01*
G02X571795Y1557275I-142J141D01*
G01X566854D01*
G02X566712Y1557334I0J200D01*
G01X564856Y1559190D01*
G03X564714Y1559249I-142J-141D01*
G01X564102D01*
G02X563902Y1559449I0J200D01*
G01Y1561512D01*
G02X563960Y1561654I200J1D01*
G01X569886Y1567580D01*
G02X570029Y1567639I142J-141D01*
G01X570354Y1567637D01*
X570427Y1567606D01*
X570455Y1567577D01*
G03X572243Y1566825I1788J1750D01*
G03Y1571829I0J2502D01*
G03X570110Y1570634I0J-2501D01*
G01X570082Y1570589D01*
X569992Y1570538D01*
X569920D01*
G03X569481Y1570456I-1J-1211D01*
G01X569425Y1570435D01*
X569309Y1570459D01*
X569267Y1570501D01*
G02Y1570784I141J141D01*
G01X577113Y1578630D01*
G02X577255Y1578689I142J-141D01*
G37*
G36*
G01X579341Y45112D02*
G03I-720J0D01*
G37*
G36*
G01X586016Y222954D02*
G03I-720J0D01*
G37*
G36*
G01X582439Y1256235D02*
X598138D01*
X601509Y1259606D01*
X612896D01*
X613781Y1258721D01*
Y1243521D01*
X609690Y1239430D01*
X600956D01*
X596589Y1243797D01*
X581665D01*
X581499Y1243963D01*
Y1255295D01*
X582439Y1256235D01*
G37*
G36*
G01X574805Y1452895D02*
G03I-519J0D01*
G37*
G36*
G01X588215Y1459995D02*
G03I-519J0D01*
G37*
G36*
G01X586305Y1462595D02*
G03I-519J0D01*
G37*
G36*
G01X581515Y1474895D02*
G03I-519J0D01*
G37*
G36*
G01X586295D02*
G03I-519J0D01*
G37*
G36*
G01X588205Y1472295D02*
G03I-519J0D01*
G37*
G36*
G01X586295Y1469695D02*
G03I-519J0D01*
G37*
G36*
G01X581515D02*
G03I-519J0D01*
G37*
G36*
G01X579605Y1472295D02*
G03I-519J0D01*
G37*
G36*
G01X588215Y1465195D02*
G03I-519J0D01*
G37*
G36*
G01X592570Y1527011D02*
X594196D01*
G02X594261Y1527000I0J-200D01*
G01X595175Y1526686D01*
G03X595581Y1526607I487J1420D01*
G01X595620Y1526605D01*
X595689Y1526573D01*
X595905Y1526345D01*
G02X595960Y1526207I-145J-138D01*
G01Y1524099D01*
G02X595905Y1523961I-200J0D01*
G01X595689Y1523733D01*
X595620Y1523701D01*
X595581Y1523699D01*
G03X595266Y1523648I81J-1499D01*
G01X594044Y1523313D01*
G02X593991Y1523306I-52J193D01*
G01X592304D01*
G02X592234Y1523319I1J200D01*
G01X591463Y1523607D01*
G03X590938Y1523702I-526J-1407D01*
G03X590541Y1523648I2J-1502D01*
G01X589320Y1523313D01*
G02X589267Y1523306I-52J193D01*
G01X587580D01*
G02X587510Y1523319I1J200D01*
G01X586739Y1523607D01*
G03X586214Y1523702I-526J-1407D01*
G03X585817Y1523648I2J-1502D01*
G01X584595Y1523313D01*
G02X584542Y1523306I-52J193D01*
G01X582855D01*
G02X582785Y1523319I1J200D01*
G01X582014Y1523607D01*
G03X581489Y1523702I-526J-1407D01*
G03X581092Y1523648I2J-1502D01*
G01X579871Y1523313D01*
G02X579818Y1523306I-52J193D01*
G01X578415D01*
G02X578273Y1523365I0J200D01*
G01X578111Y1523527D01*
G02X578052Y1523669I141J142D01*
G01Y1526626D01*
G02X578181Y1526813I200J0D01*
G01X578665Y1526998D01*
G02X578737Y1527011I71J-187D01*
G01X580022D01*
G02X580087Y1527000I0J-200D01*
G01X581001Y1526686D01*
G03X581489Y1526604I489J1420D01*
G03X581911Y1526665I-2J1502D01*
G01X583065Y1527003D01*
G02X583121Y1527011I56J-192D01*
G01X584747D01*
G02X584812Y1527000I0J-200D01*
G01X585726Y1526686D01*
G03X586214Y1526604I489J1420D01*
G03X586636Y1526665I-2J1502D01*
G01X587790Y1527003D01*
G02X587846Y1527011I56J-192D01*
G01X589471D01*
G02X589536Y1527000I0J-200D01*
G01X590450Y1526686D01*
G03X590938Y1526604I489J1420D01*
G03X591360Y1526665I-2J1502D01*
G01X592514Y1527003D01*
G02X592570Y1527011I56J-192D01*
G37*
G36*
G01X596402Y44842D02*
G03I-720J0D01*
G37*
G36*
G01X603784Y44523D02*
G03I-720J0D01*
G37*
G36*
G01X600004Y32866D02*
G03I-720J0D01*
G37*
G36*
G01X601303Y193185D02*
G03I-510J0D01*
G37*
G36*
G01X597171Y188775D02*
G03I-510J0D01*
G37*
G36*
G01X591020Y190660D02*
G03I-720J0D01*
G37*
G36*
G01X596283Y239128D02*
G03I-720J0D01*
G37*
G36*
G01X600230Y323970D02*
Y288770D01*
X600516Y288484D01*
X613910D01*
X614110Y288684D01*
Y324044D01*
X613910Y324244D01*
X600504D01*
X600230Y323970D01*
G37*
G36*
G01X604003Y419744D02*
G03I-720J0D01*
G37*
G36*
G01X593268Y805986D02*
G03I-656J0D01*
G37*
G36*
G01X620189Y1019214D02*
G02I-13780J0D01*
G37*
G36*
G01X594905Y1462595D02*
G03I-519J0D01*
G37*
G36*
G01X592995Y1459995D02*
G03I-519J0D01*
G37*
G36*
G01X594915Y1455495D02*
G03I-519J0D01*
G37*
G36*
G01X599695D02*
G03I-519J0D01*
G37*
G36*
G01X601605Y1452895D02*
G03I-519J0D01*
G37*
G36*
G01X599695Y1450295D02*
G03I-519J0D01*
G37*
G36*
G01X594915D02*
G03I-519J0D01*
G37*
G36*
G01X593005Y1452895D02*
G03I-519J0D01*
G37*
G36*
G01X592995Y1465195D02*
G03I-519J0D01*
G37*
G36*
G01X602422Y1527011D02*
X603644D01*
G02X603709Y1527000I0J-200D01*
G01X604623Y1526686D01*
G03X605065Y1526605I489J1420D01*
G01X605104Y1526604D01*
X605175Y1526573D01*
X605396Y1526345D01*
G02X605452Y1526205I-144J-139D01*
G01Y1524101D01*
G02X605396Y1523961I-200J-1D01*
G01X605175Y1523733D01*
X605104Y1523702D01*
X605065Y1523701D01*
G03X604714Y1523648I47J-1501D01*
G01X603493Y1523313D01*
G02X603440Y1523306I-52J193D01*
G01X602088D01*
X602015Y1523336D01*
X602004Y1523346D01*
Y1526594D01*
G02X602063Y1526735I200J-1D01*
G01X602280Y1526952D01*
G02X602422Y1527011I142J-141D01*
G37*
G36*
G01X597370D02*
X598920D01*
G02X598985Y1527000I0J-200D01*
G01X599899Y1526686D01*
G03X600387Y1526604I489J1420D01*
G03X600558Y1526614I-2J1502D01*
G01X600601Y1526619D01*
X600681Y1526594D01*
X600936Y1526366D01*
G02X601003Y1526217I-133J-149D01*
G01Y1524089D01*
G02X600936Y1523940I-200J0D01*
G01X600681Y1523712D01*
X600601Y1523687D01*
X600558Y1523692D01*
G03X600387Y1523702I-173J-1492D01*
G03X599990Y1523648I2J-1502D01*
G01X598768Y1523313D01*
G02X598715Y1523306I-52J193D01*
G01X597326D01*
G02X597184Y1523365I0J200D01*
G01X597020Y1523529D01*
G02X596961Y1523671I141J142D01*
G01Y1526602D01*
G02X597020Y1526744I200J0D01*
G01X597228Y1526952D01*
G02X597370Y1527011I142J-141D01*
G37*
G36*
G01X619147Y43432D02*
G03I-720J0D01*
G37*
G36*
G01X619320Y160750D02*
G03I-720J0D01*
G37*
G36*
G01X607127Y228098D02*
X612798D01*
X613518Y227378D01*
Y224966D01*
X614153Y224331D01*
X616734D01*
X616861Y224204D01*
Y223717D01*
X616544Y223400D01*
X613878D01*
X613475Y222997D01*
Y221897D01*
X613116Y221538D01*
X607233D01*
X606916Y221855D01*
Y227887D01*
X607127Y228098D01*
G37*
G36*
G01X615974Y347522D02*
G03I-510J0D01*
G37*
G36*
G01X608591Y359262D02*
G03I-720J0D01*
G37*
G36*
G01X616827Y780364D02*
G03I-656J0D01*
G37*
G36*
G01X607215Y796116D02*
G03I-656J0D01*
G37*
G36*
G01X615015Y1459995D02*
G03I-519J0D01*
G37*
G36*
G01X613105Y1462595D02*
G03I-519J0D01*
G37*
G36*
G01X608315Y1474895D02*
G03I-519J0D01*
G37*
G36*
G01X613095D02*
G03I-519J0D01*
G37*
G36*
G01X615005Y1472295D02*
G03I-519J0D01*
G37*
G36*
G01X613095Y1469695D02*
G03I-519J0D01*
G37*
G36*
G01X608315D02*
G03I-519J0D01*
G37*
G36*
G01X606405Y1472295D02*
G03I-519J0D01*
G37*
G36*
G01X615015Y1465195D02*
G03I-519J0D01*
G37*
G36*
G01X616189Y1527010D02*
X617141D01*
G02X617283Y1526951I0J-200D01*
G01X617541Y1526693D01*
G02X617600Y1526552I-141J-142D01*
G01Y1525527D01*
G03X617658Y1525386I200J0D01*
G01X617664Y1525380D01*
X617694Y1525307D01*
Y1525276D01*
X618031Y1524939D01*
X618104Y1524909D01*
X618135D01*
X618427Y1524617D01*
G03X618568Y1524558I142J141D01*
G01X619692D01*
G02X619892Y1524358I0J-200D01*
G01Y1524090D01*
G02X619825Y1523941I-200J0D01*
G01X619571Y1523714D01*
X619491Y1523688D01*
X619448Y1523693D01*
G03X619285Y1523702I-164J-1493D01*
G03X618888Y1523648I2J-1502D01*
G01X617666Y1523313D01*
G02X617613Y1523306I-52J193D01*
G01X615926D01*
G02X615856Y1523319I1J200D01*
G01X615085Y1523607D01*
G03X614560Y1523702I-526J-1407D01*
G03X614163Y1523648I2J-1502D01*
G01X612942Y1523313D01*
G02X612889Y1523306I-52J193D01*
G01X611202D01*
G02X611132Y1523319I1J200D01*
G01X610361Y1523607D01*
G03X609836Y1523702I-526J-1407D01*
G03X609439Y1523648I2J-1502D01*
G01X608217Y1523313D01*
G02X608164Y1523306I-52J193D01*
G01X606770D01*
G02X606628Y1523365I0J200D01*
G01X606513Y1523480D01*
G02X606454Y1523622I141J142D01*
G01Y1526271D01*
G02X606513Y1526413I200J0D01*
G01X607051Y1526951D01*
G02X607193Y1527010I142J-141D01*
G01X608372D01*
G02X608437Y1526999I0J-200D01*
G01X609348Y1526686D01*
G03X609836Y1526604I489J1420D01*
G03X610258Y1526665I-2J1502D01*
G01X611409Y1527002D01*
G02X611465Y1527010I56J-192D01*
G01X613096D01*
G02X613161Y1526999I0J-200D01*
G01X614072Y1526686D01*
G03X614560Y1526604I489J1420D01*
G03X614982Y1526665I-2J1502D01*
G01X616133Y1527002D01*
G02X616189Y1527010I56J-192D01*
G37*
G36*
G01X625447Y44019D02*
G03I-510J0D01*
G37*
G36*
G01X621110Y36794D02*
G03I-720J0D01*
G37*
G36*
G01X631620Y118920D02*
G03I-720J0D01*
G37*
G36*
G01X631319Y1364820D02*
X627977D01*
X627923Y1364874D01*
Y1365396D01*
X628046Y1365519D01*
X631091D01*
X631156Y1365584D01*
X631495Y1365923D01*
Y1367339D01*
X630857Y1367977D01*
X627994D01*
X627893Y1368078D01*
Y1370157D01*
X627977Y1370241D01*
X631005D01*
X631495Y1370731D01*
Y1379357D01*
X631595Y1379457D01*
X645695D01*
X645786Y1379366D01*
Y1367666D01*
X646364Y1367088D01*
X649301D01*
X649595Y1366794D01*
Y1364957D01*
X649458Y1364820D01*
X646954D01*
X646939Y1364804D01*
X646701Y1365042D01*
X631541D01*
X631319Y1364820D01*
G37*
G36*
G01X621705Y1462595D02*
G03I-519J0D01*
G37*
G36*
G01X619795Y1459995D02*
G03I-519J0D01*
G37*
G36*
G01X621715Y1455495D02*
G03I-519J0D01*
G37*
G36*
G01X626495D02*
G03I-519J0D01*
G37*
G36*
G01X628405Y1452895D02*
G03I-519J0D01*
G37*
G36*
G01X626495Y1450295D02*
G03I-519J0D01*
G37*
G36*
G01X621715D02*
G03I-519J0D01*
G37*
G36*
G01X619805Y1452895D02*
G03I-519J0D01*
G37*
G36*
G01X619795Y1465195D02*
G03I-519J0D01*
G37*
G36*
G01X633205Y1472295D02*
G03I-519J0D01*
G37*
G36*
G01X625641Y1527011D02*
X626590D01*
G02X626732Y1526952I0J-200D01*
G01X627045Y1526639D01*
G02X627104Y1526498I-141J-142D01*
G01Y1523809D01*
G02X627045Y1523668I-200J1D01*
G01X626742Y1523365D01*
G02X626600Y1523306I-142J141D01*
G01X625375D01*
G02X625305Y1523319I1J200D01*
G01X624534Y1523607D01*
G03X624009Y1523702I-526J-1407D01*
G03X623748Y1523679I0J-1492D01*
G01X623700Y1523670D01*
X623607Y1523699D01*
X623529Y1523777D01*
G02X623470Y1523918I141J142D01*
G01Y1526382D01*
G02X623529Y1526523I200J-1D01*
G01X623612Y1526606D01*
X623703Y1526635D01*
X623753Y1526627D01*
G03X624009Y1526604I262J1478D01*
G03X624431Y1526665I-2J1502D01*
G01X625585Y1527003D01*
G02X625641Y1527011I56J-192D01*
G37*
G36*
G01X630365D02*
X631850D01*
G02X631992Y1526952I0J-200D01*
G01X632111Y1526833D01*
G02X632170Y1526691I-141J-142D01*
G01Y1523776D01*
G02X632111Y1523634I-200J0D01*
G01X631842Y1523365D01*
G02X631700Y1523306I-142J141D01*
G01X630099D01*
G02X630029Y1523319I1J200D01*
G01X629258Y1523607D01*
G03X628733Y1523702I-526J-1407D01*
G03X628456Y1523676I1J-1502D01*
G01X628407Y1523666D01*
X628312Y1523696D01*
X628164Y1523844D01*
G02X628105Y1523986I141J142D01*
G01Y1526218D01*
G02X628172Y1526368I200J1D01*
G01X628428Y1526595D01*
X628510Y1526620D01*
X628553Y1526615D01*
G03X628733Y1526604I181J1491D01*
G03X629155Y1526665I-2J1502D01*
G01X630309Y1527003D01*
G02X630365Y1527011I56J-192D01*
G37*
G36*
G01X620446Y1526873D02*
X622243D01*
G02X622385Y1526814I0J-200D01*
G01X622410Y1526789D01*
G02X622469Y1526647I-141J-142D01*
G01Y1523865D01*
G02X622410Y1523723I-200J0D01*
G01X622134Y1523447D01*
G02X621992Y1523388I-142J141D01*
G01X621262D01*
G02X621120Y1523447I0J200D01*
G01X620952Y1523615D01*
G02X620893Y1523757I141J142D01*
G01Y1525154D01*
G03X620834Y1525296I-200J0D01*
G01X620629Y1525501D01*
G03X620487Y1525560I-142J-141D01*
G01X618983D01*
G02X618841Y1525619I0J200D01*
G01X618660Y1525800D01*
G02X618601Y1525942I141J142D01*
G01Y1526384D01*
G02X618660Y1526526I200J0D01*
G01X618768Y1526634D01*
X618869Y1526662D01*
X618921Y1526649D01*
G03X619285Y1526604I365J1457D01*
G03X619707Y1526665I-2J1502D01*
G01X620389Y1526865D01*
G02X620446Y1526873I56J-192D01*
G37*
G36*
G01X642845Y202916D02*
X653077D01*
X653787Y202206D01*
Y198864D01*
X653394Y198471D01*
X642987D01*
X642302Y199156D01*
Y202373D01*
X642845Y202916D01*
G37*
G36*
G01X636676Y228124D02*
X656556D01*
X657064Y227616D01*
Y222602D01*
X658457Y221209D01*
X670637D01*
X670695Y221151D01*
Y220187D01*
X670627Y220119D01*
X664380D01*
X664202Y219941D01*
Y219424D01*
X664378Y219248D01*
X670456D01*
X670656Y219048D01*
Y218373D01*
X670466Y218183D01*
X661641D01*
X659944Y216486D01*
Y214903D01*
X663432Y211415D01*
X670307D01*
X670699Y211023D01*
Y210276D01*
X664402D01*
X664202Y210076D01*
Y209607D01*
X664402Y209407D01*
X670699D01*
Y208308D01*
X664402D01*
X664202Y208108D01*
Y207639D01*
X664402Y207439D01*
X670699D01*
Y206339D01*
X664402D01*
X664202Y206139D01*
Y205670D01*
X664402Y205470D01*
X670699D01*
Y204665D01*
X670379Y204345D01*
X637655D01*
X636524Y205476D01*
Y227972D01*
X636676Y228124D01*
G37*
G36*
G01X636774Y229870D02*
X655543D01*
X656263Y230590D01*
Y246391D01*
X655438Y247216D01*
X637584D01*
X636368Y246000D01*
Y230276D01*
X636774Y229870D01*
G37*
G36*
G01X640827Y391085D02*
G03I-510J0D01*
G37*
G36*
G01X643472Y574185D02*
G03I-656J0D01*
G37*
G36*
G01X634538Y587488D02*
G03I-656J0D01*
G37*
G36*
G01X640138D02*
G03I-656J0D01*
G37*
G36*
G01X646102Y587300D02*
G03I-656J0D01*
G37*
G36*
G01X644305Y674781D02*
G03I-656J0D01*
G37*
G36*
G01X641745Y758808D02*
G02X642042Y758974I200J-9D01*
G02X642055Y758966I-98J-174D01*
G03X642854Y758726I799J1211D01*
G03X644306Y760178I0J1452D01*
G03X644104Y760916I-1451J-1D01*
G02X644267Y761218I172J102D01*
G01X649999D01*
G03X650103Y761248I-1J197D01*
G01X650104Y761249D01*
X650129Y761264D01*
X650154Y761271D01*
G02X650212Y761280I59J-191D01*
G01X650357D01*
G02X650385Y761278I0J-200D01*
G02X650488Y761232I-27J-198D01*
G02X650509Y761211I-131J-152D01*
G02X650532Y761179I-150J-132D01*
G01X650583Y761088D01*
X650584Y761087D01*
X650604Y761051D01*
X650615Y760978D01*
X650611Y760962D01*
X650596Y760897D01*
X650588Y760879D01*
G03X650452Y760266I1316J-614D01*
G03X653356I1452J0D01*
G01Y760272D01*
G03X653272Y760753I-1452J-6D01*
G01X653269Y760762D01*
G02X653287Y760919I192J58D01*
G02X653297Y760935I174J-98D01*
G01X653481Y761195D01*
G02X653644Y761280I164J-115D01*
G01X659848D01*
G02X660044Y761097I0J-196D01*
G01Y759154D01*
G03X660546Y758652I502J0D01*
G01X666446D01*
G03X666948Y759154I0J502D01*
G01Y761097D01*
G02X667144Y761280I196J-13D01*
G01X671931D01*
G03X672007Y761295I0J200D01*
G01X672075Y761323D01*
G02X672151Y761338I76J-185D01*
G01X672180D01*
X672196Y761335D01*
G03X672217Y761332I323J2187D01*
G01X672223D01*
X672235Y761331D01*
G03X672504Y761314I274J2194D01*
G01X677055D01*
G03X677362Y761335I3J2211D01*
G03X677365I2J198D01*
G01X677374Y761338D01*
X679918D01*
G02X679956Y761334I-2J-200D01*
G02X680058Y761281I-37J-196D01*
G01X680080Y761259D01*
G03X680170Y761207I142J141D01*
G01X680171D01*
X680211Y761196D01*
X680240Y761174D01*
G02X680293Y761113I-121J-159D01*
G01X680362Y760992D01*
G02X680376Y760860I-181J-86D01*
G01Y760859D01*
X680366Y760815D01*
X680357Y760795D01*
X680356Y760794D01*
G03X680219Y760179I1315J-616D01*
G01Y760178D01*
G03X683123I1452J0D01*
G01Y760179D01*
G03X683037Y760671I-1452J0D01*
G01X683031Y760688D01*
G02X683056Y760845I194J50D01*
G01X683152Y760983D01*
Y760985D01*
X683244Y761115D01*
G02X683315Y761177I163J-115D01*
G02X683408Y761200I93J-177D01*
G01X689548D01*
G02X689745Y761003I0J-197D01*
G01Y759154D01*
G03X690247Y758653I502J1D01*
G01X696147D01*
G03X696649Y759154I0J502D01*
G01Y761003D01*
G02X696846Y761200I197J0D01*
G01X701621D01*
G03X701697Y761215I0J200D01*
G01X701765Y761243D01*
G02X701841Y761258I76J-185D01*
G01X709630D01*
G02X709683Y761250I-3J-200D01*
G01X709748Y761230D01*
G03X709792Y761221I62J190D01*
G01X709831Y761217D01*
X709870Y761197D01*
X709881Y761190D01*
G02X709947Y761120I-108J-168D01*
G01X710000Y761027D01*
G02X710002Y761023I-178J-91D01*
G03X710004Y761019I180J87D01*
G02X710021Y760880I-178J-92D01*
G01X710009Y760833D01*
X710004Y760823D01*
X710000Y760814D01*
G03X709853Y760186I1306J-637D01*
G01X709854Y760140D01*
G03X711306Y758726I1452J39D01*
G03X712758Y760178I0J1452D01*
G01Y760182D01*
G03X712666Y760686I-1452J-5D01*
G01Y760687D01*
X712665Y760689D01*
G02X712684Y760863I188J67D01*
G01X712780Y761002D01*
X712871Y761134D01*
G02X712888Y761155I164J-115D01*
G02X712942Y761197I148J-135D01*
G02X713026Y761220I94J-177D01*
G01X719250D01*
G02X719446Y761037I0J-196D01*
G01Y759154D01*
G03X719948Y758652I502J0D01*
G01X725848D01*
G03X726350Y759154I0J502D01*
G01Y761037D01*
G02X726546Y761220I196J-13D01*
G01X731331D01*
G03X731407Y761235I0J200D01*
G01X731475Y761263D01*
G02X731551Y761278I76J-185D01*
G01X738661D01*
X738681Y761298D01*
X739274D01*
G02X739300Y761296I-2J-200D01*
G02X739424Y761230I-26J-198D01*
G01X739432Y761221D01*
G02X739434Y761218I-166J-113D01*
G01X739626Y760942D01*
G02X739644Y760904I-171J-104D01*
G01Y760768D01*
X739633Y760737D01*
G03X739555Y760281I1374J-470D01*
G01Y760261D01*
G03X742459I1452J5D01*
G01Y760269D01*
G03X742370Y760767I-1452J-3D01*
G01Y760768D01*
G02X742394Y760950I188J68D01*
G01X742495Y761096D01*
X742580Y761218D01*
G02X742582Y761221I168J-110D01*
G01X742590Y761230D01*
G02X742714Y761296I150J-132D01*
G02X742740Y761298I28J-198D01*
G01X748950D01*
G02X749147Y761101I0J-197D01*
G01Y759154D01*
G03X749649Y758653I502J1D01*
G01X755549D01*
G03X756051Y759154I0J502D01*
G01Y761101D01*
G02X756248Y761298I197J0D01*
G01X768975D01*
G02X769001Y761296I-2J-200D01*
G02X769125Y761230I-26J-198D01*
G01X769133Y761221D01*
G02X769135Y761218I-166J-113D01*
G01X769327Y760942D01*
G02X769345Y760904I-171J-104D01*
G01Y760768D01*
X769334Y760737D01*
G03X769256Y760281I1374J-470D01*
G01Y760261D01*
G03X772160I1452J5D01*
G01Y760269D01*
G03X772071Y760767I-1452J-3D01*
G01Y760768D01*
G02X772095Y760950I188J68D01*
G01X772196Y761096D01*
X772281Y761218D01*
G02X772283Y761221I168J-110D01*
G01X772291Y761230D01*
G02X772415Y761296I150J-132D01*
G02X772441Y761298I28J-198D01*
G01X778652D01*
G02X778848Y761115I0J-196D01*
G01Y759154D01*
G03X779350Y758652I502J0D01*
G01X785250D01*
G03X785752Y759154I0J502D01*
G01Y761115D01*
G02X785948Y761298I196J-13D01*
G01X798681D01*
X798686Y761304D01*
X798874D01*
G02X799038Y761219I0J-200D01*
G02X799047Y761205I-164J-115D01*
G01Y761204D01*
X799048Y761203D01*
X799100Y761112D01*
G02X799121Y761062I-172J-102D01*
G02Y760964I-194J-49D01*
G01X799110Y760918D01*
X799104Y760904D01*
X799100Y760897D01*
G03X798956Y760267I1308J-630D01*
G01Y760266D01*
G03X801860I1452J0D01*
G01Y760268D01*
G03X801772Y760765I-1452J-1D01*
G01X801770Y760772D01*
X801758Y760842D01*
G02X801790Y760950I200J0D01*
G01X801833Y761012D01*
Y761014D01*
X801975Y761218D01*
G02X802046Y761281I164J-114D01*
G02X802130Y761304I94J-177D01*
G01X808352D01*
G02X808548Y761121I0J-196D01*
G01Y759154D01*
G03X809050Y758652I502J0D01*
G01X814280Y758653D01*
G02X814476Y758453I-4J-200D01*
G01Y750227D01*
G02X814466Y750166I-200J1D01*
G01X811225Y742341D01*
G02X811088Y742239I-177J94D01*
G02X811048Y742235I-40J196D01*
G01X676410D01*
G02X676268Y742294I0J200D01*
G01X675622Y742940D01*
G03X672156Y744376I-3466J-3465D01*
G01X642614D01*
G02X642472Y744435I0J200D01*
G01X641803Y745104D01*
G02X641767Y745154I142J140D01*
G02X641745Y745245I178J91D01*
G01Y758799D01*
Y758808D01*
G37*
G36*
G01X714173Y1449730D02*
X802311D01*
G02X802453Y1449671I0J-200D01*
G01X807820Y1444304D01*
G02X807879Y1444162I-141J-142D01*
G01Y1374774D01*
G02X807820Y1374632I-200J0D01*
G01X805927Y1372739D01*
G02X805785Y1372680I-142J141D01*
G01X802023D01*
G03X801881Y1372621I0J-200D01*
G01X797309Y1368049D01*
G02X797167Y1367990I-142J141D01*
G01X777903D01*
G03X777761Y1367931I0J-200D01*
G01X772499Y1362669D01*
G03X772440Y1362527I141J-142D01*
G01Y1349153D01*
G02X772381Y1349011I-200J0D01*
G01X771460Y1348090D01*
G02X771318Y1348031I-142J141D01*
G01X672957D01*
G03X672815Y1347972I0J-200D01*
G01X671610Y1346767D01*
G03X671551Y1346625I141J-142D01*
G01Y1317871D01*
G02X671492Y1317729I-200J0D01*
G01X669810Y1316047D01*
G02X669668Y1315988I-142J141D01*
G01X662354D01*
G03X662212Y1315929I0J-200D01*
G01X660830Y1314547D01*
G03X660771Y1314405I141J-142D01*
G01Y1307761D01*
G03X660830Y1307619I200J0D01*
G01X662695Y1305754D01*
G03X662837Y1305695I142J141D01*
G01X671578D01*
G03X671720Y1305754I0J200D01*
G01X672972Y1307006D01*
G03X673031Y1307148I-141J142D01*
G01Y1309165D01*
G02X673090Y1309307I200J0D01*
G01X673320Y1309537D01*
G02X673462Y1309596I142J-141D01*
G01X764032D01*
X764105Y1309566D01*
X764117Y1309554D01*
X769942D01*
G02X770084Y1309495I0J-200D01*
G01X770902Y1308677D01*
G02X770961Y1308535I-141J-142D01*
G01Y1285711D01*
G02X770902Y1285569I-200J0D01*
G01X769190Y1283857D01*
G02X769048Y1283798I-142J141D01*
G01X642765D01*
G02X642623Y1283857I0J200D01*
G01X635709Y1290771D01*
G02X635650Y1290913I141J142D01*
G01Y1346786D01*
G02X635709Y1346928I200J0D01*
G01X637404Y1348623D01*
G02X637546Y1348682I142J-141D01*
G01X659429D01*
G03X659571Y1348741I0J200D01*
G01X668615Y1357785D01*
G03X668674Y1357927I-141J142D01*
G01Y1395073D01*
G02X668733Y1395215I200J0D01*
G01X672815Y1399297D01*
G02X672957Y1399356I142J-141D01*
G01X693911D01*
G02X694111Y1399156I0J-200D01*
G01Y1383581D01*
G03X694170Y1383439I200J0D01*
G01X695757Y1381852D01*
G03X695899Y1381793I142J141D01*
G01X708493D01*
G02X708635Y1381734I0J-200D01*
G01X710371Y1379998D01*
G03X710513Y1379939I142J141D01*
G01X711358D01*
Y1379952D01*
X716358D01*
G03X716558Y1380152I0J200D01*
G01Y1383316D01*
G03X716499Y1383458I-200J0D01*
G01X715822Y1384135D01*
G03X715680Y1384194I-142J-141D01*
G01X713345D01*
G02X713203Y1384253I0J200D01*
G01X713042Y1384414D01*
G03X712900Y1384473I-142J-141D01*
G01X709534D01*
G02X709392Y1384532I0J200D01*
G01X709391Y1384533D01*
X709361Y1384606D01*
Y1385285D01*
X709391Y1385358D01*
X709397Y1385364D01*
X712978D01*
G03X713120Y1385423I0J200D01*
G01X713208Y1385511D01*
G03X713267Y1385653I-141J142D01*
G01Y1389320D01*
G03X713208Y1389462I-200J0D01*
G01X712941Y1389729D01*
G03X712799Y1389788I-142J-141D01*
G01X709591D01*
G02X709449Y1389847I0J200D01*
G01X709141Y1390155D01*
G02X709082Y1390297I141J142D01*
G01Y1390333D01*
X709378Y1390629D01*
G02X709520Y1390688I142J-141D01*
G01X712436D01*
G03X712578Y1390747I0J200D01*
G01X712656Y1390825D01*
G02X712798Y1390884I142J-141D01*
G01X712954D01*
G03X713096Y1390943I0J200D01*
G01X713208Y1391055D01*
G03X713267Y1391197I-141J142D01*
G01Y1391872D01*
X713269Y1391877D01*
X713369Y1391944D01*
X720095D01*
X720100Y1391942D01*
X720167Y1391842D01*
Y1383373D01*
G03X720226Y1383231I200J0D01*
G01X720607Y1382850D01*
G03X720749Y1382791I142J141D01*
G01X735577D01*
G02X735719Y1382732I0J-200D01*
G01X736560Y1381890D01*
G03X736702Y1381831I142J141D01*
G01X741369D01*
G02X741511Y1381772I0J-200D01*
G01X743182Y1380101D01*
G03X743324Y1380042I142J141D01*
G01X744140D01*
Y1380052D01*
X749140D01*
G03X749340Y1380252I0J200D01*
G01Y1383416D01*
G03X749281Y1383558I-200J0D01*
G01X748604Y1384235D01*
G03X748462Y1384294I-142J-141D01*
G01X745570D01*
G02X745428Y1384353I0J200D01*
G01X745267Y1384514D01*
G03X745125Y1384573I-142J-141D01*
G01X742116D01*
G02X741974Y1384632I0J200D01*
G01X741959Y1384647D01*
G02X741900Y1384789I141J142D01*
G01Y1385260D01*
G02X741959Y1385402I200J0D01*
G01X741981Y1385424D01*
X742054Y1385454D01*
X745750D01*
G03X745892Y1385513I0J200D01*
G01X745990Y1385611D01*
G03X746049Y1385753I-141J142D01*
G01Y1389428D01*
G03X745990Y1389570I-200J0D01*
G01X745720Y1389840D01*
G03X745578Y1389899I-142J-141D01*
G01X742065D01*
G02X741923Y1389958I0J200D01*
G01X741748Y1390133D01*
G02X741689Y1390275I141J142D01*
G01Y1390422D01*
G02X741748Y1390564I200J0D01*
G01X741900Y1390716D01*
G02X742042Y1390775I142J-141D01*
G01X745527D01*
G03X745669Y1390834I0J200D01*
G01X745990Y1391155D01*
G03X746049Y1391297I-141J142D01*
G01Y1391972D01*
X746051Y1391977D01*
X746151Y1392044D01*
X752877D01*
X752882Y1392042D01*
X752949Y1391942D01*
Y1383473D01*
G03X753008Y1383331I200J0D01*
G01X753440Y1382899D01*
G03X753582Y1382840I142J141D01*
G01X763499D01*
G03X763641Y1382899I0J200D01*
G01X763681Y1382939D01*
G02X763823Y1382998I142J-141D01*
G01X767652D01*
X767663Y1382988D01*
X767670Y1382995D01*
X768721D01*
Y1382980D01*
X775680D01*
G03X775822Y1383039I0J200D01*
G01X778372Y1385589D01*
G03X778431Y1385731I-141J142D01*
G01Y1437026D01*
G03X778372Y1437168I-200J0D01*
G01X771389Y1444151D01*
G03X771247Y1444210I-142J-141D01*
G01X724383D01*
G03X724241Y1444151I0J-200D01*
G01X717889Y1437799D01*
G02X717747Y1437740I-142J141D01*
G01X709253D01*
G02X709111Y1437799I0J200D01*
G01X708909Y1438001D01*
G02X708850Y1438143I141J142D01*
G01Y1444407D01*
Y1445552D01*
X713028Y1449730D01*
X714173D01*
G37*
G36*
G01X653195Y1380257D02*
Y1382657D01*
X653795Y1383257D01*
X659095D01*
X660142D01*
X660749Y1383864D01*
Y1386209D01*
X660601Y1386357D01*
X659495D01*
X651053D01*
X650406Y1385710D01*
Y1378633D01*
X649806Y1378033D01*
X647026D01*
X646966Y1377973D01*
Y1377483D01*
X647016Y1377433D01*
X650371D01*
X653195Y1380257D01*
G37*
G36*
G01X649395Y1379057D02*
Y1381757D01*
Y1383057D01*
Y1387157D01*
X648995Y1387557D01*
X648495Y1388057D01*
X642195D01*
X642066D01*
X641834Y1387825D01*
Y1384018D01*
X642295Y1383557D01*
X646295D01*
X646895Y1382957D01*
Y1379057D01*
X646919Y1379033D01*
X649371D01*
X649395Y1379057D01*
G37*
G36*
G01X639905Y1462595D02*
G03I-519J0D01*
G37*
G36*
G01X641815Y1459995D02*
G03I-519J0D01*
G37*
G36*
G01X646595D02*
G03I-519J0D01*
G37*
G36*
G01X648505Y1462595D02*
G03I-519J0D01*
G37*
G36*
G01X648515Y1455495D02*
G03I-519J0D01*
G37*
G36*
G01X646605Y1452895D02*
G03I-519J0D01*
G37*
G36*
G01X648515Y1450295D02*
G03I-519J0D01*
G37*
G36*
G01X635115Y1474895D02*
G03I-519J0D01*
G37*
G36*
G01X639895D02*
G03I-519J0D01*
G37*
G36*
G01X641805Y1472295D02*
G03I-519J0D01*
G37*
G36*
G01X639895Y1469695D02*
G03I-519J0D01*
G37*
G36*
G01X635115D02*
G03I-519J0D01*
G37*
G36*
G01X641815Y1465195D02*
G03I-519J0D01*
G37*
G36*
G01X646595D02*
G03I-519J0D01*
G37*
G36*
G01X649263Y1527011D02*
X650239D01*
G02X650345Y1526981I1J-200D01*
G01X650617Y1526810D01*
G02X650653Y1526782I-104J-171D01*
G01X650718Y1526717D01*
G02X650777Y1526575I-141J-142D01*
G01Y1523591D01*
G02X650718Y1523449I-200J0D01*
G01X650634Y1523365D01*
G02X650492Y1523306I-142J141D01*
G01X648997D01*
G02X648927Y1523319I1J200D01*
G01X648156Y1523607D01*
G03X647631Y1523702I-526J-1407D01*
G03X647234Y1523648I2J-1502D01*
G01X646013Y1523313D01*
G02X645960Y1523306I-52J193D01*
G01X644273D01*
G02X644203Y1523319I1J200D01*
G01X643432Y1523607D01*
G03X642907Y1523702I-526J-1407D01*
G03X642510Y1523648I2J-1502D01*
G01X641288Y1523313D01*
G02X641235Y1523306I-52J193D01*
G01X639548D01*
G02X639478Y1523319I1J200D01*
G01X638707Y1523607D01*
G03X638182Y1523702I-526J-1407D01*
G03X637785Y1523648I2J-1502D01*
G01X636564Y1523313D01*
G02X636511Y1523306I-52J193D01*
G01X634824D01*
G02X634754Y1523319I1J200D01*
G01X633983Y1523607D01*
G03X633548Y1523699I-525J-1407D01*
G01X633509Y1523701D01*
X633440Y1523733D01*
X633226Y1523961D01*
G02X633172Y1524098I146J137D01*
G01Y1526208D01*
G02X633226Y1526345I200J0D01*
G01X633440Y1526573D01*
X633509Y1526605D01*
X633548Y1526607D01*
G03X633880Y1526665I-91J1499D01*
G01X635034Y1527003D01*
G02X635090Y1527011I56J-192D01*
G01X636715D01*
G02X636780Y1527000I0J-200D01*
G01X637694Y1526686D01*
G03X638182Y1526604I489J1420D01*
G03X638604Y1526665I-2J1502D01*
G01X639758Y1527003D01*
G02X639814Y1527011I56J-192D01*
G01X641440D01*
G02X641505Y1527000I0J-200D01*
G01X642419Y1526686D01*
G03X642907Y1526604I489J1420D01*
G03X643329Y1526665I-2J1502D01*
G01X644483Y1527003D01*
G02X644539Y1527011I56J-192D01*
G01X646164D01*
G02X646229Y1527000I0J-200D01*
G01X647143Y1526686D01*
G03X647631Y1526604I489J1420D01*
G03X648053Y1526665I-2J1502D01*
G01X649207Y1527003D01*
G02X649263Y1527011I56J-192D01*
G37*
G36*
G01X650305Y29298D02*
G03I-720J0D01*
G37*
G36*
G01X648997Y44106D02*
G03I-510J0D01*
G37*
G36*
G01X654290Y58363D02*
G03I-720J0D01*
G37*
G36*
G01X661495Y78330D02*
G03I-720J0D01*
G37*
G36*
G01X664132Y154332D02*
X672768D01*
X673400Y153700D01*
Y150400D01*
X670781Y147781D01*
Y145732D01*
X668991Y143942D01*
X662141D01*
X660860Y145223D01*
Y151060D01*
X664132Y154332D01*
G37*
G36*
G01X653523Y443200D02*
G03I-510J0D01*
G37*
G36*
G01X650592Y574185D02*
G03I-656J0D01*
G37*
G36*
G01X651702Y587300D02*
G03I-656J0D01*
G37*
G36*
G01X660718Y672761D02*
G03I-656J0D01*
G37*
G36*
G01X655332Y674806D02*
G03I-656J0D01*
G37*
G36*
G01X652410Y795316D02*
G03I-656J0D01*
G37*
G36*
G01Y832127D02*
G03I-656J0D01*
G37*
G36*
G01Y868938D02*
G03I-656J0D01*
G37*
G36*
G01Y905750D02*
G03I-656J0D01*
G37*
G36*
G01Y942561D02*
G03I-656J0D01*
G37*
G36*
G01Y1089805D02*
G03I-656J0D01*
G37*
G36*
G01Y1126616D02*
G03I-656J0D01*
G37*
G36*
G01Y1163427D02*
G03I-656J0D01*
G37*
G36*
G01Y1200238D02*
G03I-656J0D01*
G37*
G36*
G01Y1237049D02*
G03I-656J0D01*
G37*
G36*
G01X653295Y1450295D02*
G03I-519J0D01*
G37*
G36*
G01X655205Y1452895D02*
G03I-519J0D01*
G37*
G36*
G01X653295Y1455495D02*
G03I-519J0D01*
G37*
G36*
G01X661915D02*
G03I-519J0D01*
G37*
G36*
G01X660005Y1452895D02*
G03I-519J0D01*
G37*
G36*
G01X661915Y1450295D02*
G03I-519J0D01*
G37*
G36*
G01X668594Y1531224D02*
X670450D01*
G02X670650Y1531024I0J-200D01*
G01Y1525814D01*
G02X670591Y1525672I-200J0D01*
G01X669447Y1524528D01*
G03X669388Y1524386I141J-142D01*
G01Y1511858D01*
G02X669329Y1511716I-200J0D01*
G01X668974Y1511361D01*
G02X668832Y1511302I-142J141D01*
G01X664756D01*
G03X664614Y1511243I0J-200D01*
G01X664519Y1511148D01*
G02X664378Y1511090I-141J142D01*
G01X661893D01*
G02X661752Y1511148I0J200D01*
G01X660852Y1512048D01*
G02X660793Y1512190I141J142D01*
G01Y1512660D01*
X660813Y1512721D01*
X660833Y1512747D01*
G03X661274Y1514073I-1770J1325D01*
G03X660990Y1515159I-2211J2D01*
G02X660985Y1515347I174J99D01*
G03X661218Y1516336I-1978J988D01*
G03X660267Y1518153I-2211J0D01*
G01X659902Y1518407D01*
G02X659816Y1518571I114J164D01*
G01Y1519750D01*
G02X659875Y1519892I200J0D01*
G01X661996Y1522013D01*
G03X662055Y1522155I-141J142D01*
G01Y1522658D01*
G02X662114Y1522799I200J-1D01*
G01X662173Y1522858D01*
G03X662528Y1523715I-857J857D01*
G01Y1526304D01*
G02X662586Y1526446I200J1D01*
G01X664430Y1528289D01*
G02X664571Y1528348I142J-141D01*
G01X667476D01*
G03X667618Y1528407I0J200D01*
G01X668335Y1529124D01*
G03X668394Y1529266I-141J142D01*
G01Y1531024D01*
G02X668594Y1531224I200J0D01*
G37*
G36*
G01X664324Y1546131D02*
X668291D01*
G02X668433Y1546072I0J-200D01*
G01X668662Y1545843D01*
G02X668721Y1545701I-141J-142D01*
G01Y1534726D01*
G02X668521Y1534526I-200J0D01*
G01X664250D01*
G03X664049Y1534510I-5J-1211D01*
G01X664013Y1534504D01*
X663941Y1534518D01*
X663655Y1534696D01*
X663610Y1534754D01*
X663600Y1534789D01*
G03X662353Y1535715I-1247J-377D01*
G03X661205Y1535026I0J-1301D01*
G01X661191Y1535000D01*
X661170Y1534979D01*
G02X660887I-141J142D01*
G01X660738Y1535128D01*
G02X660679Y1535270I141J142D01*
G01Y1537459D01*
G03X660620Y1537601I-200J0D01*
G01X660204Y1538017D01*
X660178Y1538126D01*
X660197Y1538181D01*
G03X660274Y1538658I-1424J475D01*
G03X660168Y1539213I-1501J1D01*
G01X660154Y1539249D01*
Y1542723D01*
G02X660213Y1542864I200J-1D01*
G01X662739Y1545391D01*
G02X662804Y1545434I141J-142D01*
G01X663853Y1545869D01*
G03X664192Y1546081I-464J1119D01*
G02X664324Y1546131I132J-150D01*
G37*
G36*
G01X664423Y32574D02*
G03I-720J0D01*
G37*
G36*
G01X669459Y45262D02*
G03I-720J0D01*
G37*
G36*
G01X678314Y36205D02*
G03I-720J0D01*
G37*
G36*
G01X676607Y45262D02*
G03I-720J0D01*
G37*
G36*
G01X674471Y78092D02*
G03I-720J0D01*
G37*
G36*
G01X681354Y114568D02*
Y120868D01*
X680954Y121268D01*
X677254D01*
X676554Y120568D01*
Y115168D01*
X677254Y114468D01*
X681254D01*
X681354Y114568D01*
G37*
G36*
G01X664680Y445711D02*
G03I-510J0D01*
G37*
G36*
G01X668552Y791970D02*
G03I-656J0D01*
G37*
G36*
G01Y828781D02*
G03I-656J0D01*
G37*
G36*
G01Y865592D02*
G03I-656J0D01*
G37*
G36*
G01Y902403D02*
G03I-656J0D01*
G37*
G36*
G01Y939214D02*
G03I-656J0D01*
G37*
G36*
G01Y1086458D02*
G03I-656J0D01*
G37*
G36*
G01Y1123269D02*
G03I-656J0D01*
G37*
G36*
G01Y1160080D02*
G03I-656J0D01*
G37*
G36*
G01Y1196891D02*
G03I-656J0D01*
G37*
G36*
G01Y1233702D02*
G03I-656J0D01*
G37*
G36*
G01X763519Y1310760D02*
X690520D01*
X673679D01*
X673041Y1311398D01*
Y1345818D01*
X674253Y1347030D01*
X678991D01*
X692886D01*
X763995D01*
X769699D01*
X769720Y1347010D01*
X771710D01*
X772370Y1346350D01*
Y1311800D01*
X771330Y1310760D01*
X768173D01*
X763519D01*
G37*
G36*
G01X666695Y1450295D02*
G03I-519J0D01*
G37*
G36*
G01X668605Y1452895D02*
G03I-519J0D01*
G37*
G36*
G01X666695Y1455495D02*
G03I-519J0D01*
G37*
G36*
G01X670775Y1484772D02*
G03I-519J0D01*
G37*
G36*
G01Y1479992D02*
G03I-519J0D01*
G37*
G36*
G01X673375Y1478082D02*
G03I-519J0D01*
G37*
G36*
G01X675631Y1479602D02*
G03I-519J0D01*
G37*
G36*
G01X675975Y1484772D02*
G03I-519J0D01*
G37*
G36*
G01X673375Y1486682D02*
G03I-519J0D01*
G37*
G36*
G01Y1491482D02*
G03I-519J0D01*
G37*
G36*
G01X670775Y1493392D02*
G03I-519J0D01*
G37*
G36*
G01X675975D02*
G03I-519J0D01*
G37*
G36*
G01Y1498172D02*
G03I-519J0D01*
G37*
G36*
G01X670775D02*
G03I-519J0D01*
G37*
G36*
G01X670644Y1665915D02*
X670662Y1665933D01*
G02X670804Y1665992I142J-141D01*
G01X674826D01*
G02X675026Y1665792I0J-200D01*
G01Y1663996D01*
X675030Y1663993D01*
Y1652063D01*
G02X674830Y1651863I-200J0D01*
G01X672229D01*
G02X672092Y1651917I0J200D01*
G03X671068Y1652320I-1024J-1099D01*
G03X671025Y1652319I13J-1502D01*
G01X670984Y1652318D01*
X670910Y1652347D01*
X670675Y1652576D01*
G02X670614Y1652719I139J144D01*
G01Y1652822D01*
G02X670672Y1652963I200J0D01*
G01X670757Y1653048D01*
G02X670887Y1653106I141J-142D01*
G03Y1656106I-84J1500D01*
G02X670757Y1656164I11J200D01*
G01X670672Y1656249D01*
G02X670614Y1656390I142J141D01*
G01Y1665842D01*
X670644Y1665915D01*
G37*
G36*
G01X676028Y1665885D02*
X676047Y1665904D01*
G02X676189Y1665963I142J-141D01*
G01X679826D01*
G02X679968Y1665904I0J-200D01*
G01X680307Y1665565D01*
G02X680366Y1665423I-141J-142D01*
G01Y1655702D01*
G02X680307Y1655560I-200J0D01*
G01X679974Y1655227D01*
X679878Y1655199D01*
X679828Y1655210D01*
G03X679413Y1655253I-413J-1959D01*
G03X677411Y1653251I0J-2002D01*
G03X677807Y1652056I2001J0D01*
G01X677851Y1651996D01*
X677840Y1651848D01*
X677711Y1651719D01*
G02X677569Y1651660I-142J141D01*
G01X676219D01*
G02X676077Y1651719I0J200D01*
G01X676061Y1651735D01*
X676031Y1651808D01*
Y1664408D01*
X676028Y1664411D01*
Y1665885D01*
G37*
G36*
G01X683611Y72642D02*
G03I-720J0D01*
G37*
G36*
G01X681400Y81200D02*
X687000Y75600D01*
Y75572D01*
X688131D01*
X688821Y74882D01*
X690111D01*
X691041D01*
X691521Y75362D01*
Y77732D01*
X688231Y81022D01*
Y85892D01*
X687231Y86892D01*
X684791D01*
X680460D01*
X679940Y86372D01*
Y82660D01*
X681400Y81200D01*
G37*
G36*
G01X692214Y90618D02*
Y110018D01*
X690814D01*
X690514Y109718D01*
Y105485D01*
X688714Y103685D01*
Y91118D01*
X689314Y90518D01*
X692114D01*
X692214Y90618D01*
G37*
G36*
G01X693416Y109916D02*
X707717D01*
G02X707859Y109857I0J-200D01*
G01X708035Y109681D01*
G02X708094Y109539I-141J-142D01*
G01Y101339D01*
G02X708079Y101263I-200J0D01*
G01X708095Y101182D01*
X709360Y99917D01*
G03X709502Y99858I142J141D01*
G01X718061D01*
G02X718203Y99799I0J-200D01*
G01X720800Y97202D01*
G02X720859Y97060I-141J-142D01*
G01Y88803D01*
G02X720366Y88414I-400J0D01*
G03X720016Y88455I-349J-1462D01*
G03X718513Y86974I0J-1503D01*
G01Y86951D01*
G03X718648Y86328I1503J0D01*
G02Y86162I-182J-83D01*
G03X718514Y85542I1368J-620D01*
G01Y85541D01*
G03X720016Y84039I1502J0D01*
G01X720019D01*
G03X720366Y84080I-2J1502D01*
G01X720411Y84091D01*
X720499Y84071D01*
X720783Y83848D01*
G02X720859Y83691I-124J-157D01*
G01Y78365D01*
G02X720800Y78223I-200J0D01*
G01X718709Y76132D01*
X718667Y76117D01*
G03X717852Y75600I749J-2081D01*
G01X717805Y75553D01*
G02X717663Y75494I-142J141D01*
G01X715431D01*
G02X715320Y75528I1J200D01*
G03X714096Y75898I-1225J-1842D01*
G03X712872Y75528I1J-2212D01*
G02X712761Y75494I-112J166D01*
G01X693348D01*
G02X693206Y75553I0J200D01*
G01X692811Y75948D01*
X692782Y75976D01*
X692752Y76050D01*
Y79154D01*
G02X692811Y79296I200J0D01*
G01X692825Y79310D01*
X691049Y81086D01*
G03X690907Y81145I-142J-141D01*
G01X690237D01*
G02X690037Y81345I0J200D01*
G01Y85392D01*
G02X690096Y85534I200J0D01*
G01X692803Y88241D01*
G03X692862Y88383I-141J142D01*
G01Y89766D01*
G02X692920Y89907I200J0D01*
G01X693157Y90145D01*
G03X693216Y90286I-141J142D01*
G01Y109716D01*
G02X693416Y109916I200J0D01*
G37*
G36*
G01X686054Y109768D02*
X683554D01*
X683110Y109324D01*
Y100112D01*
X683254Y99968D01*
X686154D01*
X686654Y100468D01*
Y109168D01*
X686054Y109768D01*
G37*
G36*
G01X679254Y96368D02*
Y109568D01*
X679454Y109768D01*
X681954D01*
X682054Y109668D01*
Y99068D01*
X682854Y98268D01*
X686254D01*
X686554Y97968D01*
Y94968D01*
X686054Y94468D01*
X681154D01*
X679254Y96368D01*
G37*
G36*
G01X717450Y136528D02*
X737972D01*
X743840Y130660D01*
X746788D01*
X748080D01*
X749494Y129246D01*
Y127954D01*
Y110924D01*
G02X749486Y110869I-200J1D01*
G01X749464Y110792D01*
X749451Y110770D01*
G03X749284Y110156I1045J-614D01*
G01Y108174D01*
G02X749270Y108101I-200J1D01*
G01X749231Y108002D01*
X749207Y107975D01*
G03X748699Y106642I1495J-1333D01*
G03X749422Y105102I2002J0D01*
G02X749494Y104948I-128J-154D01*
G01Y97911D01*
G02X749435Y97769I-200J0D01*
G01X749379Y97713D01*
G02X749237Y97654I-142J141D01*
G01X748754D01*
G02X748554Y97854I0J200D01*
G01Y104185D01*
G03X748495Y104327I-200J0D01*
G01X748493Y104329D01*
G02X748434Y104470I141J142D01*
G01Y104488D01*
X748404Y104561D01*
X747626Y105339D01*
X747553Y105370D01*
X747522D01*
X746415D01*
X746405Y105360D01*
X746346Y105331D01*
X746312Y105326D01*
G03X746195Y105269I24J-198D01*
G01X745563Y104637D01*
G03X745504Y104495I141J-142D01*
G01Y99801D01*
G02X745445Y99659I-200J0D01*
G01X745373Y99587D01*
X745345Y99558D01*
X745271Y99528D01*
X744777D01*
G02X744635Y99587I0J200D01*
G01X744623Y99599D01*
G02X744564Y99741I141J142D01*
G01Y108915D01*
G03X744505Y109057I-200J0D01*
G01X742768Y110794D01*
G02X742710Y110935I142J141D01*
G01Y111841D01*
G03X742709Y111871I-890J-15D01*
G01Y114785D01*
X742718Y114814D01*
G03X742756Y115072I-853J257D01*
G01Y116126D01*
X742709D01*
Y116981D01*
G03X742650Y117123I-200J0D01*
G01X741880Y117893D01*
G03X741738Y117952I-142J-141D01*
G01X727874D01*
G03X727732Y117893I0J-200D01*
G01X721030Y111191D01*
X721002Y111162D01*
X720928Y111132D01*
X693234D01*
G02X693092Y111191I0J200D01*
G01X692580Y111703D01*
X692551Y111731D01*
X692521Y111805D01*
Y115909D01*
G02X692580Y116051I200J0D01*
G01X693092Y116563D01*
G02X693234Y116622I142J-141D01*
G01X699708D01*
G02X699850Y116563I0J-200D01*
G01X699851Y116562D01*
X708818D01*
G03X708960Y116621I0J200D01*
G01X715324Y122985D01*
G03X715383Y123127I-141J142D01*
G01Y131810D01*
G02X715420Y131926I200J0D01*
G03X715830Y133208I-1802J1283D01*
G01Y134909D01*
G02X715889Y135051I200J0D01*
G01X717308Y136469D01*
G02X717450Y136528I142J-141D01*
G37*
G36*
G01X682841Y121372D02*
X691641D01*
X692191Y120822D01*
Y118102D01*
X691941Y117852D01*
X682991D01*
X682501Y118342D01*
Y121032D01*
X682841Y121372D01*
G37*
G36*
G01X705846Y134320D02*
X706397D01*
G02X706539Y134261I0J-200D01*
G01X706671Y134129D01*
G02X706730Y133987I-141J-142D01*
G01Y132473D01*
X706751Y132452D01*
Y130665D01*
G02X706692Y130523I-200J0D01*
G01X706096Y129927D01*
G02X705954Y129868I-142J141D01*
G01X704037D01*
G02X703895Y129927I0J200D01*
G01X703613Y130209D01*
G03X703471Y130268I-142J-141D01*
G01X682517D01*
G02X682375Y130327I0J200D01*
G01X682153Y130549D01*
G02X682094Y130691I141J142D01*
G01Y131632D01*
G02X682226Y131820I200J0D01*
G01X683983Y132459D01*
G02X684051Y132472I71J-187D01*
G01X702334D01*
G03X703537Y132819I1J2256D01*
G01X703562Y132835D01*
X703615Y132850D01*
X703857D01*
G03X703999Y132909I0J200D01*
G01X704641Y133551D01*
G02X704671Y133576I142J-140D01*
G01X705735Y134286D01*
G02X705846Y134320I112J-166D01*
G37*
G36*
G01X684011Y153462D02*
X701371D01*
X702991Y151842D01*
Y145471D01*
X699930Y142410D01*
X684813D01*
X683031Y144192D01*
Y152482D01*
X684011Y153462D01*
G37*
G36*
G01X692267Y386834D02*
G03I-720J0D01*
G37*
G36*
G01X692006Y575081D02*
G03I-510J0D01*
G37*
G36*
G01X688734Y675493D02*
G03I-656J0D01*
G37*
G36*
G01X682111Y795316D02*
G03I-656J0D01*
G37*
G36*
G01Y832127D02*
G03I-656J0D01*
G37*
G36*
G01Y868938D02*
G03I-656J0D01*
G37*
G36*
G01Y905750D02*
G03I-656J0D01*
G37*
G36*
G01Y942561D02*
G03I-656J0D01*
G37*
G36*
G01Y1089805D02*
G03I-656J0D01*
G37*
G36*
G01Y1126616D02*
G03I-656J0D01*
G37*
G36*
G01Y1163427D02*
G03I-656J0D01*
G37*
G36*
G01Y1200238D02*
G03I-656J0D01*
G37*
G36*
G01Y1237049D02*
G03I-656J0D01*
G37*
G36*
G01X694392Y32684D02*
G03I-720J0D01*
G37*
G36*
G01X702559Y45112D02*
G03I-720J0D01*
G37*
G36*
G01X708328Y69718D02*
G03I-720J0D01*
G37*
G36*
G01X698120Y345761D02*
G03I-720J0D01*
G37*
G36*
G01X702006Y580556D02*
G03I-510J0D01*
G37*
G36*
G01X698298Y733401D02*
G03I-656J0D01*
G37*
G36*
G01X698253Y791970D02*
G03I-656J0D01*
G37*
G36*
G01Y828781D02*
G03I-656J0D01*
G37*
G36*
G01Y865592D02*
G03I-656J0D01*
G37*
G36*
G01Y902403D02*
G03I-656J0D01*
G37*
G36*
G01Y939214D02*
G03I-656J0D01*
G37*
G36*
G01Y1086458D02*
G03I-656J0D01*
G37*
G36*
G01Y1123269D02*
G03I-656J0D01*
G37*
G36*
G01Y1160080D02*
G03I-656J0D01*
G37*
G36*
G01Y1196891D02*
G03I-656J0D01*
G37*
G36*
G01Y1233702D02*
G03I-656J0D01*
G37*
G36*
G01X706379Y1383408D02*
X697243D01*
G02X697103Y1383466I0J197D01*
G01X695669Y1384900D01*
G02X695611Y1385040I139J140D01*
G01Y1392196D01*
G02X695669Y1392336I197J0D01*
G01X696443Y1393110D01*
G02X696583Y1393168I140J-139D01*
G01X701336D01*
X701351Y1393166D01*
G03X701661Y1393142I309J1977D01*
G03X701971Y1393166I1J2001D01*
G01X701986Y1393168D01*
X702479D01*
G02X702619Y1393110I0J-197D01*
G01X702783Y1392946D01*
G02X702841Y1392806I-139J-140D01*
G01Y1389870D01*
G03X702899Y1389730I197J0D01*
G01X703990Y1388639D01*
G02X704020Y1388600I-140J-139D01*
G03X704689Y1387931I1637J968D01*
G01X704710Y1387919D01*
X704711Y1387918D01*
X704754Y1387894D01*
G03X705657Y1387666I903J1674D01*
G03X706327Y1387788I0J1901D01*
G01X706381Y1387809D01*
X706495Y1387784D01*
X706823Y1387456D01*
G02X706881Y1387316I-139J-140D01*
G01Y1383910D01*
G02X706823Y1383770I-197J0D01*
G01X706519Y1383466D01*
G02X706379Y1383408I-140J139D01*
G37*
G36*
G01X706682Y1552082D02*
G03I-510J0D01*
G37*
G36*
G01X705238Y1669296D02*
X711255D01*
G02X711397Y1669237I0J-200D01*
G01X711951Y1668683D01*
G02X712010Y1668541I-141J-142D01*
G01Y1666358D01*
G03X712455Y1665027I2211J-1D01*
G02X712495Y1664907I-160J-120D01*
G01Y1663699D01*
G02X712436Y1663557I-200J0D01*
G01X712413Y1663534D01*
X712340Y1663504D01*
X709205D01*
G02X709063Y1663563I0J200D01*
G01X707972Y1664654D01*
G03X707830Y1664713I-142J-141D01*
G01X701837D01*
G02X701695Y1664772I0J200D01*
G01X700998Y1665469D01*
G02X700939Y1665611I141J142D01*
G01Y1667996D01*
G02X701139Y1668196I200J0D01*
G01X702920D01*
G03X704484Y1668844I0J2211D01*
G01X704738Y1669098D01*
X704777Y1669123D01*
X704800Y1669130D01*
G03X705148Y1669274I-780J2377D01*
G02X705238Y1669296I91J-178D01*
G37*
G36*
G01X721048Y344824D02*
G03I-720J0D01*
G37*
G36*
G01X712066Y575081D02*
G03I-510J0D01*
G37*
G36*
G01X713936Y636897D02*
G03I-656J0D01*
G37*
G36*
G01X711812Y832127D02*
G03I-656J0D01*
G37*
G36*
G01Y868938D02*
G03I-656J0D01*
G37*
G36*
G01Y905750D02*
G03I-656J0D01*
G37*
G36*
G01Y942561D02*
G03I-656J0D01*
G37*
G36*
G01Y1089805D02*
G03I-656J0D01*
G37*
G36*
G01Y1126616D02*
G03I-656J0D01*
G37*
G36*
G01Y1163427D02*
G03I-656J0D01*
G37*
G36*
G01Y1200238D02*
G03I-656J0D01*
G37*
G36*
G01Y1237049D02*
G03I-656J0D01*
G37*
G36*
G01X735500Y1383916D02*
X721773D01*
X721626Y1384063D01*
Y1391984D01*
X721950Y1392308D01*
X727296D01*
X727813Y1392825D01*
Y1393269D01*
G03X727814Y1393295I-797J44D01*
G01Y1393315D01*
X727817D01*
Y1395890D01*
X729256Y1397329D01*
Y1400829D01*
X729248Y1400837D01*
Y1404491D01*
X724251Y1409488D01*
Y1438678D01*
X727946Y1442373D01*
X769166D01*
X776568Y1434971D01*
Y1386016D01*
X774568Y1384016D01*
X754555D01*
X754408Y1384163D01*
Y1392084D01*
X754732Y1392408D01*
X760078D01*
X760595Y1392925D01*
Y1393369D01*
G03X760596Y1393395I-797J44D01*
G01Y1394263D01*
X760599D01*
Y1395990D01*
X762038Y1397429D01*
Y1400929D01*
X762030Y1400937D01*
Y1404937D01*
X759436Y1407531D01*
X739900D01*
X735900Y1403531D01*
Y1384316D01*
X735500Y1383916D01*
G37*
G36*
G01X718223Y1433488D02*
Y1413988D01*
X717223Y1412988D01*
X709223D01*
X708223Y1413988D01*
Y1433488D01*
Y1435940D01*
X708997Y1436714D01*
X717176D01*
X718223Y1435667D01*
Y1433488D01*
G37*
G36*
G01X710944Y1553532D02*
X717874D01*
G02X718016Y1553473I0J-200D01*
G01X718340Y1553149D01*
G02X718399Y1553007I-141J-142D01*
G01Y1531474D01*
G02X718340Y1531332I-200J0D01*
G01X717813Y1530805D01*
G02X717671Y1530746I-142J141D01*
G01X710944D01*
G02X710802Y1530805I0J200D01*
G01X710614Y1530993D01*
G02X710555Y1531135I141J142D01*
G01Y1535718D01*
X710566Y1535750D01*
G03X710652Y1536250I-1416J501D01*
G03X710566Y1536750I-1502J-1D01*
G01X710555Y1536782D01*
Y1553143D01*
G02X710614Y1553285I200J0D01*
G01X710802Y1553473D01*
G02X710944Y1553532I142J-141D01*
G37*
G36*
G01X724109Y-28508D02*
G03I-630J0D01*
G37*
G36*
G01Y-19234D02*
G03I-630J0D01*
G37*
G36*
G01Y-9234D02*
G03I-630J0D01*
G37*
G36*
G01X729701Y39872D02*
G03I-720J0D01*
G37*
G36*
G01X737511Y39832D02*
G03I-720J0D01*
G37*
G36*
G01X730851Y60757D02*
G03I-720J0D01*
G37*
G36*
G01X737244Y58069D02*
G03I-720J0D01*
G37*
G36*
G01X732065Y83685D02*
G03I-510J0D01*
G37*
G36*
G01X737519Y83169D02*
G03I-510J0D01*
G37*
G36*
G01X742894Y102428D02*
X743224D01*
X743524Y102128D01*
Y99688D01*
X743364Y99528D01*
X740844D01*
X740524D01*
X737854Y96858D01*
X731766D01*
X731224Y96316D01*
Y93858D01*
X731024Y93658D01*
X729180D01*
X728660Y94178D01*
Y95954D01*
X728642Y95972D01*
Y97058D01*
X725134Y100566D01*
Y102888D01*
Y112672D01*
X725161D01*
X725921Y113432D01*
X733861D01*
X734741Y114312D01*
Y115682D01*
X735871Y116812D01*
X738411D01*
X739134Y116089D01*
Y112788D01*
Y110188D01*
X738934Y109988D01*
X729734D01*
X728734Y108988D01*
Y107688D01*
X729534Y106888D01*
X731494D01*
X731924Y106458D01*
Y100958D01*
X732434Y100448D01*
X740914D01*
X742174D01*
X742604Y100878D01*
Y102138D01*
X742894Y102428D01*
G37*
G36*
G01X729220Y533862D02*
G03I-720J0D01*
G37*
G36*
G01X737220D02*
G03I-720J0D01*
G37*
G36*
G01X733220D02*
G03I-720J0D01*
G37*
G36*
G01X724657Y636790D02*
G03I-656J0D01*
G37*
G36*
G01X727954Y791970D02*
G03I-656J0D01*
G37*
G36*
G01Y828781D02*
G03I-656J0D01*
G37*
G36*
G01Y865592D02*
G03I-656J0D01*
G37*
G36*
G01Y902403D02*
G03I-656J0D01*
G37*
G36*
G01Y939214D02*
G03I-656J0D01*
G37*
G36*
G01Y1086458D02*
G03I-656J0D01*
G37*
G36*
G01Y1123269D02*
G03I-656J0D01*
G37*
G36*
G01Y1160080D02*
G03I-656J0D01*
G37*
G36*
G01Y1233702D02*
G03I-656J0D01*
G37*
G36*
G01X741470Y1578390D02*
X743201D01*
X743786Y1577805D01*
Y1576120D01*
X746863Y1573043D01*
X754417D01*
X761659Y1565801D01*
X771821D01*
X777850Y1571830D01*
Y1573850D01*
G02X777909Y1573992I200J0D01*
G01X778191Y1574274D01*
G02X778333Y1574333I142J-141D01*
G01X793407D01*
G03X793549Y1574392I0J200D01*
G01X793551Y1574394D01*
G03X793610Y1574536I-141J142D01*
G01Y1577773D01*
G02X793810Y1577973I200J0D01*
G01X795487D01*
G02X795628Y1577914I-1J-200D01*
G01X795851Y1577691D01*
G02X795910Y1577550I-141J-142D01*
G01Y1573870D01*
X801640Y1568140D01*
X814180D01*
X820150Y1574110D01*
G02X820209Y1574252I200J0D01*
G01X820231Y1574274D01*
G02X820373Y1574333I142J-141D01*
G01X835407D01*
G03X835549Y1574392I0J200D01*
G01X835571Y1574414D01*
G03X835630Y1574556I-141J142D01*
G01Y1577833D01*
G02X835830Y1578033I200J0D01*
G01X837367D01*
G02X837509Y1577974I0J-200D01*
G01X837851Y1577632D01*
G02X837910Y1577490I-141J-142D01*
G01Y1573760D01*
X843570Y1568100D01*
X856130D01*
X862130Y1574100D01*
G02X862189Y1574242I200J0D01*
G01X862221Y1574274D01*
G02X862363Y1574333I142J-141D01*
G01X877417D01*
G03X877559Y1574392I0J200D01*
G01X877561Y1574394D01*
G03X877620Y1574536I-141J142D01*
G01Y1577880D01*
G02X877679Y1578022I200J0D01*
G01X877731Y1578074D01*
G02X877873Y1578133I142J-141D01*
G01X878134D01*
X878152Y1578130D01*
G03X878384Y1578109I233J1280D01*
G01X879131D01*
X879205Y1578079D01*
X879233Y1578050D01*
X879871Y1577412D01*
G02X879930Y1577270I-141J-142D01*
G01Y1574270D01*
X886094Y1568106D01*
X898006D01*
X904233Y1574333D01*
X919397D01*
G03X919539Y1574392I0J200D01*
G01X919551Y1574404D01*
G03X919610Y1574546I-141J142D01*
G01Y1577833D01*
G02X919810Y1578033I200J0D01*
G01X921667D01*
G02X921809Y1577974I0J-200D01*
G01X921871Y1577912D01*
G02X921930Y1577770I-141J-142D01*
G01Y1575310D01*
X924930Y1572310D01*
X934529D01*
X938483Y1568356D01*
Y1524752D01*
X938465Y1524734D01*
Y1509535D01*
X940771Y1507229D01*
X954401D01*
G02X954543Y1507170I0J-200D01*
G01X955074Y1506639D01*
G02X955133Y1506497I-141J-142D01*
G01Y1496473D01*
X955902Y1495704D01*
X965268D01*
X966090Y1496526D01*
Y1506984D01*
G02X966149Y1507126I200J0D01*
G01X966234Y1507211D01*
G02X966376Y1507270I142J-141D01*
G01X978059D01*
G02X978201Y1507211I0J-200D01*
G01X978489Y1506923D01*
G02X978548Y1506781I-141J-142D01*
G01Y1496424D01*
X979268Y1495704D01*
X988634D01*
X989139Y1496209D01*
Y1506740D01*
G02X989198Y1506882I200J0D01*
G01X989589Y1507273D01*
G02X989731Y1507332I142J-141D01*
G01X1001454D01*
G02X1001596Y1507273I0J-200D01*
G01X1001945Y1506924D01*
G02X1002004Y1506782I-141J-142D01*
G01Y1496334D01*
X1002634Y1495704D01*
X1012000D01*
X1012676Y1496380D01*
Y1506984D01*
G02X1012735Y1507126I200J0D01*
G01X1012860Y1507251D01*
G02X1013002Y1507310I142J-141D01*
G01X1024524D01*
G02X1024666Y1507251I0J-200D01*
G01X1025318Y1506599D01*
G02X1025377Y1506457I-141J-142D01*
G01Y1496327D01*
X1026000Y1495704D01*
X1035366D01*
X1035929Y1496267D01*
Y1506863D01*
G02X1035988Y1507005I200J0D01*
G01X1036234Y1507251D01*
G02X1036376Y1507310I142J-141D01*
G01X1048223D01*
G02X1048365Y1507251I0J-200D01*
G01X1048693Y1506923D01*
G02X1048752Y1506781I-141J-142D01*
G01Y1496318D01*
X1049366Y1495704D01*
X1058732D01*
X1059303Y1496275D01*
Y1506659D01*
G02X1059362Y1506801I200J0D01*
G01X1059813Y1507252D01*
G02X1059955Y1507311I142J-141D01*
G01X1071516D01*
G02X1071658Y1507252I0J-200D01*
G01X1072027Y1506883D01*
G02X1072086Y1506741I-141J-142D01*
G01Y1496350D01*
X1072732Y1495704D01*
X1082098D01*
X1082759Y1496365D01*
Y1506904D01*
G02X1082818Y1507046I200J0D01*
G01X1082983Y1507211D01*
G02X1083125Y1507270I142J-141D01*
G01X1094687D01*
G02X1094829Y1507211I0J-200D01*
G01X1095320Y1506720D01*
G02X1095379Y1506578I-141J-142D01*
G01Y1477012D01*
X1089106Y1470739D01*
X945054D01*
G03X944912Y1470798I-142J-141D01*
G01X923748D01*
X923660Y1470886D01*
X892332D01*
X866345Y1496873D01*
Y1496904D01*
X864366Y1498883D01*
Y1527355D01*
X860132Y1531589D01*
X839229D01*
X825818Y1545000D01*
X730146D01*
X726146Y1549000D01*
Y1559004D01*
X729114Y1561972D01*
Y1568244D01*
X728469Y1568890D01*
Y1571107D01*
G03X728478Y1571293I-1995J190D01*
G03X727200Y1573160I-2003J0D01*
G01Y1574170D01*
X727370Y1574340D01*
X741170D01*
X741440Y1574610D01*
Y1578360D01*
X741470Y1578390D01*
G37*
G36*
G01X816670Y1718420D02*
X901350D01*
X904250Y1715520D01*
Y1661611D01*
X935904Y1629957D01*
G03X935963Y1629815I200J0D01*
G01X950208Y1615570D01*
X1100170D01*
X1102560Y1613180D01*
Y1554974D01*
G02X1102501Y1554832I-200J0D01*
G01X1100989Y1553320D01*
G02X1100847Y1553261I-142J141D01*
G01X1094249D01*
G02X1094107Y1553320I0J200D01*
G01X1093730Y1553697D01*
G02X1093671Y1553839I141J142D01*
G01Y1559930D01*
X1092730Y1560871D01*
X1090137D01*
X1089420Y1560154D01*
Y1553747D01*
G02X1089361Y1553605I-200J0D01*
G01X1089076Y1553320D01*
G02X1088934Y1553261I-142J141D01*
G01X1059357D01*
X1057192Y1555426D01*
X1054600D01*
X1052435Y1553261D01*
X1027757D01*
X1025592Y1555426D01*
X1023000D01*
X1020835Y1553261D01*
X996157D01*
X993992Y1555426D01*
X991400D01*
X989235Y1553261D01*
X964529D01*
X962380Y1555410D01*
X959788D01*
X957639Y1553261D01*
X945807D01*
X944622Y1554446D01*
Y1594661D01*
Y1596216D01*
X942863Y1597975D01*
X922703D01*
X919209Y1594481D01*
Y1593416D01*
G03X919150Y1593274I141J-142D01*
G01Y1590727D01*
G02X919091Y1590585I-200J0D01*
G01X918338Y1589832D01*
G03X918279Y1589690I141J-142D01*
G01Y1575810D01*
G02X918220Y1575668I-200J0D01*
G01X918213Y1575661D01*
X904955D01*
X904882Y1575691D01*
X904876Y1575697D01*
Y1589548D01*
G03X904817Y1589690I-200J0D01*
G01X904209Y1590298D01*
G02X904150Y1590440I141J142D01*
G01Y1599650D01*
G03X904091Y1599792I-200J0D01*
G01X895109Y1608774D01*
G03X894967Y1608833I-142J-141D01*
G01X885382D01*
G03X885240Y1608774I0J-200D01*
G01X877099Y1600633D01*
G03X877040Y1600491I141J-142D01*
G01Y1590509D01*
G02X876917Y1590325I-200J1D01*
G01X876846Y1590296D01*
G03X876781Y1590253I76J-185D01*
G01X876344Y1589816D01*
G03X876286Y1589674I142J-141D01*
G01Y1579460D01*
X876281Y1579454D01*
Y1575806D01*
G02X876222Y1575664I-200J0D01*
G01X876209Y1575651D01*
X863000D01*
G02X862858Y1575710I0J200D01*
G01X862843Y1575725D01*
Y1589506D01*
G03X862784Y1589648I-200J0D01*
G01X862219Y1590213D01*
G02X862160Y1590355I141J142D01*
G01Y1599740D01*
G03X862101Y1599882I-200J0D01*
G01X853109Y1608874D01*
G03X852967Y1608933I-142J-141D01*
G01X843456D01*
G03X843314Y1608874I0J-200D01*
G01X835059Y1600619D01*
G03X835000Y1600477I141J-142D01*
G01Y1590414D01*
G02X834941Y1590272I-200J0D01*
G01X834359Y1589690D01*
G03X834300Y1589548I141J-142D01*
G01Y1575902D01*
G02X834241Y1575760I-200J0D01*
G01X834168Y1575687D01*
G02X834026Y1575628I-142J141D01*
G01X821114D01*
G02X820972Y1575687I0J200D01*
G01X820930Y1575729D01*
G02X820871Y1575871I141J142D01*
G01Y1589543D01*
G03X820812Y1589685I-200J0D01*
G01X820189Y1590308D01*
G02X820130Y1590450I141J142D01*
G01Y1599970D01*
G03X820071Y1600112I-200J0D01*
G01X811409Y1608774D01*
G03X811267Y1608833I-142J-141D01*
G01X800533D01*
G03X800391Y1608774I0J-200D01*
G01X793309Y1601692D01*
G03X793250Y1601550I141J-142D01*
G01Y1590545D01*
G02X793191Y1590403I-200J0D01*
G01X792334Y1589546D01*
G03X792275Y1589404I141J-142D01*
G01Y1575735D01*
X792245Y1575662D01*
X792222Y1575639D01*
X779084D01*
G02X778942Y1575698I0J200D01*
G01X778934Y1575706D01*
G02X778875Y1575848I141J142D01*
G01Y1589346D01*
G03X778816Y1589488I-200J0D01*
G01X769933Y1598371D01*
G03X769791Y1598430I-142J-141D01*
G01X751483D01*
G03X751341Y1598371I0J-200D01*
G01X746345Y1593375D01*
X746310Y1593360D01*
G03X745273Y1592323I800J-1837D01*
G01X745258Y1592288D01*
X743059Y1590089D01*
G03X743000Y1589947I141J-142D01*
G01Y1588283D01*
G02X742941Y1588141I-200J0D01*
G01X742930Y1588130D01*
X742857Y1588100D01*
X740583D01*
G03X740441Y1588041I0J-200D01*
G01X740139Y1587739D01*
G03X740080Y1587597I141J-142D01*
G01Y1575813D01*
G02X740021Y1575671I-200J0D01*
G01X740010Y1575660D01*
X726773D01*
X726700Y1575690D01*
X726680Y1575710D01*
Y1589037D01*
G02X726739Y1589179I200J0D01*
G01X727131Y1589571D01*
G03X727190Y1589713I-141J142D01*
G01Y1591957D01*
G02X727249Y1592099I200J0D01*
G01X727841Y1592691D01*
G03X727900Y1592833I-141J142D01*
G01Y1596187D01*
G02X727959Y1596329I200J0D01*
G01X729621Y1597991D01*
G03X729680Y1598133I-141J142D01*
G01Y1601987D01*
G03X729621Y1602129I-200J0D01*
G01X727239Y1604511D01*
G02X727180Y1604653I141J142D01*
G01Y1612510D01*
Y1616919D01*
X728130Y1617869D01*
X732456D01*
X737391D01*
X740535D01*
X743500Y1620834D01*
X769291D01*
X774608Y1626151D01*
Y1659717D01*
X811181Y1696290D01*
Y1698964D01*
G03X811240Y1699106I-141J142D01*
G01Y1712990D01*
X816670Y1718420D01*
G37*
G36*
G01X1092023Y1738118D02*
X1133356D01*
G02X1133541Y1737994I0J-200D01*
G01X1133704Y1737594D01*
X1133680Y1737476D01*
X1133636Y1737433D01*
G03X1132434Y1736185I22078J-22467D01*
G02X1132286Y1736120I-148J135D01*
G01X1093771D01*
G02X1087854Y1730924I-5917J771D01*
G01X769705D01*
G02X763788Y1736120I0J5967D01*
G01X731099D01*
G02X730951Y1736185I0J200D01*
G03X729749Y1737433I-23280J-21219D01*
G01X729705Y1737476D01*
X729681Y1737594D01*
X729844Y1737994D01*
G02X730029Y1738118I185J-76D01*
G01X765536D01*
G02X765736Y1737918I0J-200D01*
G01Y1736890D01*
G03X769705Y1732921I3969J0D01*
G01X1087854D01*
G03X1091823Y1736890I0J3969D01*
G01Y1737918D01*
G02X1092023Y1738118I200J0D01*
G37*
G36*
G01X743561Y39832D02*
G03I-720J0D01*
G37*
G36*
G01X745197Y58373D02*
G03I-720J0D01*
G37*
G36*
G01X752981Y59782D02*
G03I-720J0D01*
G37*
G36*
G01X750481Y71312D02*
X760101D01*
X760162Y71252D01*
X763448D01*
X764700Y70000D01*
Y55271D01*
X761691Y52262D01*
X760071Y50642D01*
X751411D01*
X751462Y50693D01*
Y56393D01*
X751262Y56593D01*
X750800D01*
X750600Y56393D01*
Y50693D01*
X750651Y50642D01*
X749301D01*
X749121Y50822D01*
Y56751D01*
X749642Y57272D01*
X753811D01*
X754531Y57992D01*
Y61372D01*
X753591Y62312D01*
X751462D01*
Y68007D01*
X751262Y68207D01*
X750800D01*
X750600Y68007D01*
Y62312D01*
X749201D01*
X749141Y62372D01*
Y69972D01*
X750481Y71312D01*
G37*
G36*
G01X746830Y104368D02*
X747181D01*
X747433Y104116D01*
Y96815D01*
X747596Y96652D01*
X749922D01*
X750507Y97237D01*
Y102149D01*
X750758Y102400D01*
X751108D01*
X751425Y102083D01*
Y84678D01*
X752398Y83705D01*
Y75801D01*
X752162Y75565D01*
X742655D01*
X742319Y75901D01*
Y84351D01*
X746567Y88599D01*
Y104105D01*
X746830Y104368D01*
G37*
G36*
G01X751851Y132822D02*
X769858D01*
G02X770000Y132763I0J-200D01*
G01X771475Y131288D01*
G02X771534Y131146I-141J-142D01*
G01Y99513D01*
G02X771520Y99439I-200J0D01*
G03X769288Y87795I29267J-11646D01*
G03X771520Y76151I31499J2D01*
G01X771534Y76115D01*
Y73303D01*
G02X771475Y73161I-200J0D01*
G01X771389Y73075D01*
G02X771247Y73016I-142J141D01*
G01X754897D01*
G02X754755Y73075I0J200D01*
G01X754493Y73337D01*
G02X754434Y73479I141J142D01*
G01Y82005D01*
G02X754493Y82147I200J0D01*
G01X755777Y83431D01*
G02X755919Y83490I142J-141D01*
G01X761557D01*
G03X761699Y83549I0J200D01*
G01X766475Y88325D01*
G03X766534Y88467I-141J142D01*
G01Y117493D01*
G03X766475Y117635I-200J0D01*
G01X762677Y121433D01*
G03X762535Y121492I-142J-141D01*
G01X752364D01*
G02X752222Y121551I0J200D01*
G01X750793Y122980D01*
G02X750734Y123122I141J142D01*
G01Y131705D01*
G02X750793Y131847I200J0D01*
G01X751709Y132763D01*
G02X751851Y132822I142J-141D01*
G37*
G36*
G01X745631Y166887D02*
G03I-720J0D01*
G37*
G36*
G01X747425Y315647D02*
G03I-720J0D01*
G37*
G36*
G01X748357Y534874D02*
G03I-720J0D01*
G37*
G36*
G01X741358Y549900D02*
G03I-720J0D01*
G37*
G36*
G01X738980Y553625D02*
G03I-720J0D01*
G37*
G36*
G01X741513Y795316D02*
G03I-656J0D01*
G37*
G36*
G01Y832127D02*
G03I-656J0D01*
G37*
G36*
G01Y868938D02*
G03I-656J0D01*
G37*
G36*
G01Y905750D02*
G03I-656J0D01*
G37*
G36*
G01Y942561D02*
G03I-656J0D01*
G37*
G36*
G01Y1089805D02*
G03I-656J0D01*
G37*
G36*
G01Y1126616D02*
G03I-656J0D01*
G37*
G36*
G01Y1163427D02*
G03I-656J0D01*
G37*
G36*
G01Y1200238D02*
G03I-656J0D01*
G37*
G36*
G01Y1237049D02*
G03I-656J0D01*
G37*
G36*
G01X751540Y1668583D02*
G03I-510J0D01*
G37*
G36*
G01X954080Y146202D02*
X1011026D01*
G02X1022896Y134331I-1J-11871D01*
G01Y109427D01*
G02X1022842Y109291I-200J1D01*
G03X1021606Y107885I23029J-21491D01*
G02X1021384Y107825I-154J128D01*
G01X1021030Y107952D01*
G02X1020898Y108140I68J188D01*
G01Y134331D01*
G03X1011024Y144205I-9874J0D01*
G01X887008D01*
G03X877134Y134331I0J-9874D01*
G01Y54252D01*
G02X871260Y48378I-5874J0D01*
G01X774417D01*
G03X764543Y38504I0J-9874D01*
G01Y35112D01*
G02X764389Y34918I-200J1D01*
G01X763943Y34812D01*
X763817Y34871D01*
X763786Y34933D01*
G03X762630Y36281I-3306J-1666D01*
G02X762546Y36444I116J163D01*
G01Y38506D01*
G02X774417Y50376I11871J-1D01*
G01X871260D01*
G03X875136Y54252I0J3876D01*
G01Y134331D01*
G02X887008Y146202I11872J-1D01*
G01X936076D01*
G02X936276Y146002I0J-200D01*
G01Y145134D01*
X936563Y144847D01*
X953587D01*
X953880Y145140D01*
Y146002D01*
G02X954080Y146202I200J0D01*
G37*
G36*
G01X753174Y101438D02*
X752674D01*
X752444Y101668D01*
Y104858D01*
Y108598D01*
X753411Y109565D01*
Y112382D01*
X753817Y112788D01*
X755134D01*
X755634Y112288D01*
Y108048D01*
Y103898D01*
X753174Y101438D01*
G37*
G36*
G01X763020Y188910D02*
G03I-720J0D01*
G37*
G36*
G01X775327Y274742D02*
Y281762D01*
X774727Y282362D01*
X772427D01*
X772189D01*
X771515Y283036D01*
Y285192D01*
X771145Y285562D01*
X767827D01*
X764727D01*
X762664D01*
X760168D01*
X759314Y284708D01*
Y278433D01*
X759485Y278262D01*
X760552D01*
X762543D01*
X765027D01*
X770127D01*
X772027Y276362D01*
Y274322D01*
X772287Y274062D01*
X774647D01*
X775327Y274742D01*
G37*
G36*
G01X756055Y295589D02*
G03I-720J0D01*
G37*
G36*
G01X754679Y343790D02*
G03I-720J0D01*
G37*
G36*
G01X765220Y534424D02*
G03I-720J0D01*
G37*
G36*
G01X761220Y534352D02*
G03I-720J0D01*
G37*
G36*
G01X754207Y675800D02*
G03I-707J0D01*
G37*
G36*
G01X757655Y791970D02*
G03I-656J0D01*
G37*
G36*
G01Y865592D02*
G03I-656J0D01*
G37*
G36*
G01Y902403D02*
G03I-656J0D01*
G37*
G36*
G01Y939214D02*
G03I-656J0D01*
G37*
G36*
G01Y1086458D02*
G03I-656J0D01*
G37*
G36*
G01Y1123269D02*
G03I-656J0D01*
G37*
G36*
G01Y1160080D02*
G03I-656J0D01*
G37*
G36*
G01Y1196891D02*
G03I-656J0D01*
G37*
G36*
G01Y1233702D02*
G03I-656J0D01*
G37*
G36*
G01X769907Y1484811D02*
X784653D01*
G02X784795Y1484752I0J-200D01*
G01X785437Y1484110D01*
G02X785496Y1483968I-141J-142D01*
G01Y1479914D01*
G02X785437Y1479772I-200J0D01*
G01X784745Y1479080D01*
G02X784603Y1479021I-142J141D01*
G01X756969D01*
G02X756827Y1479080I0J200D01*
G01X756695Y1479212D01*
G02X756636Y1479354I141J142D01*
G01Y1483968D01*
G02X756695Y1484110I200J0D01*
G01X757337Y1484752D01*
G02X757479Y1484811I142J-141D01*
G01X763872D01*
G02X764035Y1484727I0J-200D01*
G03X769744I2855J2029D01*
G02X769907Y1484811I163J-116D01*
G37*
G36*
G01X790479Y1526434D02*
X790415Y1526370D01*
G02X790273Y1526311I-142J141D01*
G01X786259D01*
G02X786117Y1526370I0J200D01*
G01X785575Y1526912D01*
G03X785433Y1526971I-142J-141D01*
G01X772349D01*
G03X772207Y1526912I0J-200D01*
G01X770265Y1524970D01*
G02X770123Y1524911I-142J141D01*
G01X756059D01*
G02X755917Y1524970I0J200D01*
G01X755785Y1525102D01*
G02X755726Y1525244I141J142D01*
G01Y1538938D01*
G02X755785Y1539080I200J0D01*
G01X756827Y1540122D01*
G02X756969Y1540181I142J-141D01*
G01X789753D01*
G02X789895Y1540122I0J-200D01*
G01X790927Y1539090D01*
G02X790986Y1538948I-141J-142D01*
G01Y1528753D01*
G02X790908Y1528595I-200J0D01*
G03X790321Y1527404I915J-1191D01*
G03X790512Y1526673I1502J2D01*
G02X790479Y1526434I-175J-98D01*
G37*
G36*
G01X755918Y1672381D02*
G03I-510J0D01*
G37*
G36*
G01X778921Y135462D02*
X796521D01*
X799121Y132862D01*
Y122370D01*
X796441Y119690D01*
X792308D01*
X790880Y118262D01*
X780421D01*
X778321Y120362D01*
Y134862D01*
X778921Y135462D01*
G37*
G36*
G01X781421Y153662D02*
X798021D01*
X799421Y152262D01*
Y142162D01*
X798221Y140962D01*
X778321D01*
X777421Y141862D01*
Y149662D01*
X781421Y153662D01*
G37*
G36*
G01X872953Y282330D02*
X873466D01*
G02X873606Y282273I0J-200D01*
G01X873659Y282220D01*
G02X873661Y282218I-140J-142D01*
G02X873718Y282078I-143J-140D01*
G01Y275120D01*
G03X873777Y274978I200J0D01*
G01X874040Y274715D01*
G03X874182Y274656I142J141D01*
G01X875882D01*
G03X876024Y274715I0J200D01*
G01X876638Y275329D01*
X876642Y275328D01*
X876745Y275431D01*
G03X876804Y275573I-141J142D01*
G01Y280111D01*
G02X876863Y280253I200J0D01*
G01X877002Y280392D01*
G02X877144Y280451I142J-141D01*
G01X877353D01*
G02X877495Y280392I0J-200D01*
G01X877646Y280241D01*
G02X877705Y280099I-141J-142D01*
G01Y274533D01*
G03X877764Y274391I200J0D01*
G01X877814Y274341D01*
G02X877816Y274339I-140J-142D01*
G02X877873Y274199I-143J-140D01*
G01Y262425D01*
G03X877932Y262283I200J0D01*
G01X878821Y261394D01*
G03X878963Y261335I142J141D01*
G01X892935D01*
G02X893075Y261278I0J-200D01*
G01X893915Y260438D01*
G02X893917Y260436I-140J-142D01*
G02X893974Y260296I-143J-140D01*
G01Y234624D01*
G02X893915Y234482I-200J0D01*
G01X890527Y231094D01*
X886299Y226867D01*
X886271Y226838D01*
X886197Y226808D01*
X867923D01*
G02X867781Y226867I0J200D01*
G01X867299Y227349D01*
X867270Y227377D01*
X867240Y227451D01*
Y229625D01*
G03X867181Y229767I-200J0D01*
G01X865773Y231175D01*
G03X865631Y231234I-142J-141D01*
G01X860749D01*
G02X860607Y231293I0J200D01*
G01X860159Y231741D01*
G02X860100Y231883I141J142D01*
G01Y244665D01*
G03X860041Y244807I-200J0D01*
G01X858509Y246339D01*
Y246392D01*
X779944D01*
G02X779802Y246451I0J200D01*
G01X779527Y246726D01*
G02X779468Y246868I141J142D01*
G01Y257014D01*
G03X779409Y257156I-200J0D01*
G01X778368Y258197D01*
X770412D01*
X769927Y258682D01*
Y266062D01*
X772327Y268462D01*
Y272562D01*
X774927D01*
X775227Y272262D01*
Y269362D01*
X779371Y265218D01*
X787322D01*
X789787Y262753D01*
X801466D01*
X802207Y262012D01*
X852145D01*
G02X852343Y261841I0J-200D01*
G03X855315I1486J216D01*
G02X855513Y262012I198J-29D01*
G01X856989D01*
X857092Y261939D01*
X857113Y261879D01*
G03X859943I1415J503D01*
G01X859964Y261939D01*
X860067Y262012D01*
X867284D01*
G02X867342Y262003I-1J-200D01*
G01X867422Y261979D01*
X867445Y261964D01*
G03X868519Y261652I1073J1689D01*
G01X868521D01*
G03X869616Y261978I0J2002D01*
G01X869617Y261979D01*
X869642Y261995D01*
X869697Y262012D01*
X869748D01*
X872088Y264352D01*
X872107D01*
X872557Y264802D01*
G03X872616Y264944I-141J142D01*
G01Y281993D01*
G02X872673Y282133I200J0D01*
G01X872811Y282271D01*
G02X872813Y282273I142J-140D01*
G02X872953Y282330I140J-143D01*
G37*
G36*
G01X773941Y296262D02*
G03I-720J0D01*
G37*
G36*
G01X779841Y306155D02*
G03I-720J0D01*
G37*
G36*
G01X771214Y795316D02*
G03I-656J0D01*
G37*
G36*
G01Y832127D02*
G03I-656J0D01*
G37*
G36*
G01Y868938D02*
G03I-656J0D01*
G37*
G36*
G01Y905750D02*
G03I-656J0D01*
G37*
G36*
G01Y942561D02*
G03I-656J0D01*
G37*
G36*
G01Y1089805D02*
G03I-656J0D01*
G37*
G36*
G01Y1126616D02*
G03I-656J0D01*
G37*
G36*
G01Y1163427D02*
G03I-656J0D01*
G37*
G36*
G01Y1200238D02*
G03I-656J0D01*
G37*
G36*
G01Y1237049D02*
G03I-656J0D01*
G37*
G36*
G01X808511Y1302648D02*
X776431D01*
X776171Y1302388D01*
Y1291888D01*
Y1285529D01*
X777770Y1283930D01*
X808360D01*
X809171Y1284741D01*
Y1291988D01*
Y1301988D01*
X808511Y1302648D01*
G37*
G36*
G01X809181Y1303758D02*
X774631D01*
X773794Y1304594D01*
Y1361581D01*
X777201Y1364988D01*
X778101Y1365888D01*
X786629D01*
X786929Y1365588D01*
Y1336157D01*
X786835Y1336062D01*
X778275D01*
X777791Y1335578D01*
Y1332098D01*
X778611Y1331278D01*
X780681D01*
X782606Y1329353D01*
Y1316733D01*
X783811Y1315528D01*
X806671D01*
X809472D01*
X810601Y1314399D01*
Y1311598D01*
Y1305178D01*
X809181Y1303758D01*
G37*
G36*
G01X776293Y1517580D02*
X782746D01*
X782786Y1517540D01*
Y1515234D01*
X782726Y1515174D01*
X776287D01*
X773703D01*
X773606Y1515271D01*
Y1517421D01*
X773765Y1517580D01*
X776293D01*
G37*
G36*
G01X782740Y1519117D02*
X771720D01*
X771476Y1519361D01*
Y1523861D01*
X771786Y1524171D01*
X773386D01*
X776027Y1521530D01*
X782747D01*
X782777Y1521500D01*
Y1519154D01*
X782740Y1519117D01*
G37*
G36*
G01X825375Y204724D02*
G03I-19685J0D01*
G37*
G36*
G01X798314Y282233D02*
G03I-720J0D01*
G37*
G36*
G01X796388Y298801D02*
G03I-720J0D01*
G37*
G36*
G01X787356Y791970D02*
G03I-656J0D01*
G37*
G36*
G01Y865592D02*
G03I-656J0D01*
G37*
G36*
G01Y902403D02*
G03I-656J0D01*
G37*
G36*
G01Y939214D02*
G03I-656J0D01*
G37*
G36*
G01Y1086458D02*
G03I-656J0D01*
G37*
G36*
G01Y1160080D02*
G03I-656J0D01*
G37*
G36*
G01Y1196891D02*
G03I-656J0D01*
G37*
G36*
G01Y1233702D02*
G03I-656J0D01*
G37*
G36*
G01X794499Y1327435D02*
X796399D01*
X796599Y1327635D01*
Y1332035D01*
X796299Y1332335D01*
X794599D01*
X794351Y1332087D01*
Y1327583D01*
X794499Y1327435D01*
G37*
G36*
G01X791264Y1337162D02*
Y1341245D01*
X789123Y1343386D01*
Y1343395D01*
X788407Y1344111D01*
Y1365424D01*
X788871Y1365888D01*
X796645D01*
X799371D01*
X799701Y1365558D01*
Y1355358D01*
X792571Y1348227D01*
Y1330825D01*
X793341Y1330055D01*
Y1327677D01*
X793099Y1327435D01*
X791499D01*
X791264Y1327670D01*
Y1337162D01*
G37*
G36*
G01X800581Y1316598D02*
X784241D01*
X783754Y1317085D01*
Y1328131D01*
X785841Y1330218D01*
X788982Y1333360D01*
Y1340015D01*
X789085Y1340118D01*
X790071D01*
X790184Y1340005D01*
Y1326650D01*
X791299Y1325535D01*
X797999D01*
X804535D01*
X805000Y1326000D01*
Y1327500D01*
X805500Y1328000D01*
X807500D01*
X808000Y1327500D01*
Y1317500D01*
X807098Y1316598D01*
X800581D01*
G37*
G36*
G01X796276Y1335036D02*
X797348D01*
G02X797447Y1335010I1J-197D01*
G01X799602Y1333768D01*
G02X799642Y1333737I-100J-170D01*
G01X800487Y1332892D01*
Y1328871D01*
X800287Y1328671D01*
X798487D01*
X798187Y1328971D01*
Y1332692D01*
X797179Y1333700D01*
G03X797039Y1333758I-140J-139D01*
G01X795131D01*
G02X794933Y1333955I-1J197D01*
G01Y1334908D01*
X795061Y1335036D01*
X796276D01*
G37*
G36*
G01X807704Y265653D02*
G03I-720J0D01*
G37*
G36*
G01X803984Y330102D02*
G03I-720J0D01*
G37*
G36*
G01X809121Y341670D02*
G03I-720J0D01*
G37*
G36*
G01X810870Y442079D02*
G03I-510J0D01*
G37*
G36*
G01X800914Y795316D02*
G03I-656J0D01*
G37*
G36*
G01Y832127D02*
G03I-656J0D01*
G37*
G36*
G01Y868938D02*
G03I-656J0D01*
G37*
G36*
G01Y905750D02*
G03I-656J0D01*
G37*
G36*
G01Y942561D02*
G03I-656J0D01*
G37*
G36*
G01Y1126616D02*
G03I-656J0D01*
G37*
G36*
G01Y1163427D02*
G03I-656J0D01*
G37*
G36*
G01Y1200238D02*
G03I-656J0D01*
G37*
G36*
G01Y1237049D02*
G03I-656J0D01*
G37*
G36*
G01X807487Y1329071D02*
X804687D01*
X804387Y1328771D01*
X801787D01*
X801587Y1328971D01*
Y1331071D01*
X801787Y1331271D01*
X807487D01*
X807787Y1330971D01*
Y1329371D01*
X807487Y1329071D01*
G37*
G36*
G01X809081Y1354508D02*
X802941D01*
X802401Y1355048D01*
Y1360588D01*
X802471Y1360658D01*
X809041D01*
X809591Y1360108D01*
Y1355018D01*
X809081Y1354508D01*
G37*
G36*
G01X802061Y1370028D02*
X806728D01*
X808364D01*
X808919Y1369473D01*
Y1367837D01*
Y1362738D01*
X808220Y1362039D01*
X802071D01*
X801727Y1362384D01*
Y1369694D01*
X802061Y1370028D01*
G37*
G36*
G01X823209Y56712D02*
G03I-510J0D01*
G37*
G36*
G01X817042Y284369D02*
G03I-720J0D01*
G37*
G36*
G01X820915Y311830D02*
G03I-510J0D01*
G37*
G36*
G01X817056Y828781D02*
G03I-656J0D01*
G37*
G36*
G01Y865592D02*
G03I-656J0D01*
G37*
G36*
G01Y902403D02*
G03I-656J0D01*
G37*
G36*
G01Y939214D02*
G03I-656J0D01*
G37*
G36*
G01Y1086458D02*
G03I-656J0D01*
G37*
G36*
G01Y1123269D02*
G03I-656J0D01*
G37*
G36*
G01Y1160080D02*
G03I-656J0D01*
G37*
G36*
G01Y1196891D02*
G03I-656J0D01*
G37*
G36*
G01Y1233702D02*
G03I-656J0D01*
G37*
G36*
G01X826622Y1269546D02*
G03I-510J0D01*
G37*
G36*
G01X857040Y1420331D02*
G02I-15800J0D01*
G37*
G36*
G01X833245Y268579D02*
G03I-720J0D01*
G37*
G36*
G01X836883Y279355D02*
G03I-720J0D01*
G37*
G36*
G01X841008Y287593D02*
G03I-720J0D01*
G37*
G36*
G01X833406Y331028D02*
G03I-720J0D01*
G37*
G36*
G01X837560Y382003D02*
G03I-720J0D01*
G37*
G36*
G01X839481Y532538D02*
X852005D01*
X852279Y532812D01*
X857421D01*
X857855Y532378D01*
Y529223D01*
X856850Y528218D01*
X856840D01*
X855273Y526651D01*
X846980D01*
X845413Y528218D01*
X839824D01*
X839252Y528790D01*
Y532309D01*
X839481Y532538D01*
G37*
G36*
G01X832412Y901318D02*
G03I-656J0D01*
G37*
G36*
G01X834523Y1333586D02*
G03I-510J0D01*
G37*
G36*
G01X834577Y1342459D02*
G03I-510J0D01*
G37*
G36*
G01X839694Y1348939D02*
G03I-510J0D01*
G37*
G36*
G01X841709Y1361378D02*
G03I-510J0D01*
G37*
G36*
G01X834530Y1527931D02*
Y1517661D01*
X836330Y1515861D01*
X858585D01*
X860918Y1518194D01*
Y1528455D01*
X859568Y1529805D01*
X836404D01*
X834530Y1527931D01*
G37*
G36*
G01X845396Y-24648D02*
G03I-630J0D01*
G37*
G36*
G01Y-15374D02*
G03I-630J0D01*
G37*
G36*
G01Y-5374D02*
G03I-630J0D01*
G37*
G36*
G01Y5352D02*
G03I-630J0D01*
G37*
G36*
G01Y15352D02*
G03I-630J0D01*
G37*
G36*
G01Y24626D02*
G03I-630J0D01*
G37*
G36*
G01X844471Y217542D02*
X849931D01*
X850651Y216822D01*
Y214322D01*
X851151Y213822D01*
X853941D01*
X854151Y213612D01*
Y213222D01*
X853791Y212862D01*
X851331D01*
X850721Y212252D01*
Y211502D01*
X850221Y211002D01*
X844941D01*
X844221Y211722D01*
Y217292D01*
X844471Y217542D01*
G37*
G36*
G01X851507Y242478D02*
X858107D01*
X859007Y241578D01*
Y230887D01*
X857360Y229240D01*
X851345D01*
X850707Y229878D01*
Y241678D01*
X851507Y242478D01*
G37*
G36*
G01X865444Y293856D02*
Y288330D01*
G02X865385Y288188I-200J0D01*
G01X865303Y288106D01*
G02X865161Y288047I-142J141D01*
G01X856127D01*
G03X855985Y287988I0J-200D01*
G01X855928Y287931D01*
X855883Y287905D01*
X855857Y287898D01*
G03X854742Y286447I387J-1451D01*
G03X855728Y285036I1503J0D01*
G01X855770Y285021D01*
X855785Y285006D01*
G03X855927Y284947I142J141D01*
G01X856171D01*
G03X856244Y284945I78J1500D01*
G03X856317Y284947I-5J1502D01*
G01X857721D01*
G02X857863Y284888I0J-200D01*
G01X858175Y284576D01*
G02X858234Y284434I-141J-142D01*
G01Y279100D01*
G03X858293Y278958I200J0D01*
G01X858304Y278948D01*
Y278894D01*
X858420Y278778D01*
X858474D01*
X858685Y278566D01*
G03X858827Y278507I142J141D01*
G01X863075D01*
X863085Y278506D01*
G03X863230Y278499I145J1495D01*
G03X863375Y278506I0J1502D01*
G01X863385Y278507D01*
X868401D01*
G03X868543Y278566I0J200D01*
G01X868855Y278878D01*
G03X868914Y279020I-141J142D01*
G01Y280114D01*
G02X868973Y280256I200J0D01*
G01X869145Y280428D01*
G02X869287Y280487I142J-141D01*
G01X869451D01*
G02X869593Y280428I0J-200D01*
G01X869775Y280246D01*
G02X869834Y280104I-141J-142D01*
G01Y277830D01*
G02X869775Y277688I-200J0D01*
G01X869733Y277646D01*
G02X869591Y277587I-142J141D01*
G01X866917D01*
G03X866775Y277528I0J-200D01*
G01X864223Y274976D01*
G02X864081Y274917I-142J141D01*
G01X858159D01*
G03X858017Y274858I0J-200D01*
G01X857593Y274434D01*
G03X857534Y274292I141J-142D01*
G01Y272000D01*
G02X857475Y271858I-200J0D01*
G01X857393Y271776D01*
G02X857251Y271717I-142J141D01*
G01X852933D01*
G03X852791Y271658I0J-200D01*
G01X851219Y270086D01*
G03X851160Y269944I141J-142D01*
G01Y265404D01*
G02X851101Y265262I-200J0D01*
G01X850162Y264323D01*
G02X850020Y264264I-142J141D01*
G01X843297D01*
G02X843155Y264323I0J200D01*
G01X842259Y265219D01*
G02X842200Y265361I141J142D01*
G01Y278634D01*
G02X842259Y278776I200J0D01*
G01X843029Y279546D01*
G02X843171Y279605I142J-141D01*
G01X849543D01*
G03X849685Y279664I0J200D01*
G01X851385Y281364D01*
G03X851444Y281506I-141J142D01*
G01Y291264D01*
Y293944D01*
X852330Y294830D01*
X865100D01*
X865444Y294486D01*
Y293856D01*
G37*
G36*
G01X853921Y297462D02*
G03I-720J0D01*
G37*
G36*
G01X857421Y304862D02*
G03I-720J0D01*
G37*
G36*
G01X846995Y335575D02*
G03I-720J0D01*
G37*
G36*
G01X862071Y61672D02*
G03I-720J0D01*
G37*
G36*
G01X867740Y224808D02*
X888940D01*
X888999Y224750D01*
X893620D01*
X895152Y223218D01*
X899461Y213398D01*
Y207432D01*
X897737Y205708D01*
X868840D01*
X867540Y207008D01*
Y224608D01*
X867740Y224808D01*
G37*
G36*
G01X875804Y298389D02*
Y286357D01*
X875420Y285973D01*
Y283864D01*
X875804Y283480D01*
Y275887D01*
X875524Y275607D01*
X875074D01*
X874864Y275817D01*
Y282327D01*
X873804Y283387D01*
X872564D01*
X871814Y282637D01*
Y277777D01*
X871624Y277587D01*
X871004D01*
X870874Y277717D01*
Y287057D01*
X869220Y288711D01*
Y294963D01*
X868253Y295930D01*
X862640D01*
X862300Y296270D01*
Y303406D01*
X862818Y303924D01*
X872752D01*
X873644Y303032D01*
Y300549D01*
X875804Y298389D01*
G37*
G36*
G01X868100Y642420D02*
G03I-510J0D01*
G37*
G36*
G01X865407Y836100D02*
G03I-707J0D01*
G37*
G36*
G01X872893Y1263714D02*
X927962D01*
X930010Y1261666D01*
Y1137458D01*
X934803Y1132665D01*
X946583D01*
X946838Y1132410D01*
Y1085595D01*
X951836Y1080597D01*
Y1062748D01*
X954590Y1059994D01*
X976979D01*
X978203Y1058770D01*
Y1052752D01*
X979120Y1051835D01*
X993909D01*
X995439Y1053365D01*
Y1077027D01*
X993704Y1078762D01*
X980804D01*
X979723Y1079843D01*
Y1096302D01*
X975474Y1100551D01*
X970518D01*
X963342Y1107728D01*
X963282Y1107788D01*
Y1135374D01*
X963228Y1135428D01*
X961990Y1136667D01*
Y1153308D01*
X962488Y1153806D01*
X970687D01*
X971633Y1154752D01*
Y1157427D01*
X971224Y1157836D01*
X968376D01*
X967326Y1158886D01*
Y1208636D01*
X968310Y1209620D01*
X979129D01*
X983107Y1213598D01*
Y1243820D01*
X982264Y1244663D01*
X934864D01*
X934607Y1244920D01*
Y1259083D01*
X935707Y1260183D01*
X1005257D01*
X1014105Y1251335D01*
Y1023481D01*
X1011656Y1021032D01*
X864276D01*
X862746Y1022562D01*
Y1080778D01*
X862541Y1080983D01*
Y1243787D01*
X870930Y1252176D01*
Y1261751D01*
X872893Y1263714D01*
G37*
G36*
G01X879484Y279497D02*
X878984D01*
X878754Y279727D01*
Y283179D01*
X879444Y283869D01*
Y290347D01*
X879944Y290847D01*
X881444D01*
X881944Y290347D01*
Y286107D01*
Y281957D01*
X879484Y279497D01*
G37*
G36*
G01X874604Y453383D02*
G03I-720J0D01*
G37*
G36*
G01X884972Y1446974D02*
G03I-510J0D01*
G37*
G36*
G01X876554Y1444317D02*
G03I-510J0D01*
G37*
G36*
G01X889280Y469527D02*
G03I-720J0D01*
G37*
G36*
G01X900334Y601043D02*
G03I-656J0D01*
G37*
G36*
G01X898480Y909093D02*
G03I-656J0D01*
G37*
G36*
G01X909621Y166976D02*
Y180059D01*
X909861Y180299D01*
X918371D01*
X920728D01*
X921394Y179633D01*
Y167061D01*
X920345Y166012D01*
X910585D01*
X910244Y166353D01*
X909621Y166976D01*
G37*
G36*
G01X948425Y321654D02*
G02I-19685J0D01*
G37*
G36*
G01X907691Y590172D02*
G03I-656J0D01*
G37*
G36*
G01X907390Y619373D02*
G03I-656J0D01*
G37*
G36*
G01X907080Y663930D02*
G03I-510J0D01*
G37*
G36*
G01X906897Y818471D02*
G03I-510J0D01*
G37*
G36*
G01X905375Y921792D02*
G03I-656J0D01*
G37*
G36*
G01X910546Y950217D02*
G03I-656J0D01*
G37*
G36*
G01X910722Y960332D02*
G03I-656J0D01*
G37*
G36*
G01X909859Y970709D02*
G03I-656J0D01*
G37*
G36*
G01X909455Y985291D02*
G03I-656J0D01*
G37*
G36*
G01X951509Y166999D02*
X935384D01*
G03X935242Y166940I0J-200D01*
G01X934020Y165718D01*
G02X933878Y165659I-142J141D01*
G01X928384D01*
G02X928242Y165718I0J200D01*
G01X927890Y166070D01*
G02X927831Y166212I141J142D01*
G01Y179696D01*
G02X927890Y179838I200J0D01*
G01X928322Y180270D01*
G02X928464Y180329I142J-141D01*
G01X938721D01*
X938741Y180309D01*
X946297D01*
X947064Y181076D01*
Y194240D01*
X948421Y195597D01*
X953285D01*
X957040Y199352D01*
X958985D01*
X959189Y199148D01*
Y195891D01*
X959504Y195576D01*
Y194784D01*
Y182433D01*
Y181981D01*
Y181211D01*
X955546Y177253D01*
Y173227D01*
X956654Y172119D01*
X962173D01*
X964018D01*
X964696Y172797D01*
X966154D01*
X967104Y171847D01*
Y168002D01*
X966101Y166999D01*
X951509D01*
G37*
G36*
G01X929085Y191906D02*
X934355D01*
X935616Y193167D01*
X939028D01*
X940242Y191953D01*
Y190907D01*
X939581Y190246D01*
X938927D01*
X938212Y190961D01*
X936636D01*
X935921Y190246D01*
X934541D01*
X934356Y190431D01*
X929192D01*
X928946Y190677D01*
Y191767D01*
X929085Y191906D01*
G37*
G36*
G01X931436Y664791D02*
G03I-510J0D01*
G37*
G36*
G01X924572Y843990D02*
G03I-656J0D01*
G37*
G36*
G01X920572Y908916D02*
G03I-656J0D01*
G37*
G36*
G01X920932Y900554D02*
G03I-656J0D01*
G37*
G36*
G01X929191Y913454D02*
G03I-656J0D01*
G37*
G36*
G01X921065Y918274D02*
G03I-656J0D01*
G37*
G36*
G01X926718Y938727D02*
G03I-656J0D01*
G37*
G36*
G01X926660Y952716D02*
G03I-656J0D01*
G37*
G36*
G01X921244Y1321365D02*
G03I-510J0D01*
G37*
G36*
G01X928375Y1317419D02*
G03I-510J0D01*
G37*
G36*
G01X924186Y1339522D02*
G03I-510J0D01*
G37*
G36*
G01X920264Y1348992D02*
G03I-510J0D01*
G37*
G36*
G01X934958Y578318D02*
G03I-656J0D01*
G37*
G36*
G01X940047Y600571D02*
G03I-656J0D01*
G37*
G36*
G01X946876Y668811D02*
G03I-510J0D01*
G37*
G36*
G01X941047Y859947D02*
G03I-656J0D01*
G37*
G36*
G01X932604Y891397D02*
G03I-656J0D01*
G37*
G36*
G01X932533Y918168D02*
G03I-656J0D01*
G37*
G36*
G01X941170Y918134D02*
G03I-656J0D01*
G37*
G36*
G01X940326Y945169D02*
G03I-656J0D01*
G37*
G36*
G01X943580Y982547D02*
G03I-656J0D01*
G37*
G36*
G01X943791Y977129D02*
G03I-656J0D01*
G37*
G36*
G01X961878Y1158412D02*
X959937Y1156471D01*
Y1149816D01*
X959834Y1149713D01*
X958848D01*
X958735Y1149826D01*
Y1162703D01*
X958250Y1163188D01*
X943949D01*
X943732Y1162971D01*
Y1162358D01*
X943532Y1162158D01*
X941207D01*
X940907Y1162458D01*
Y1178858D01*
X940918Y1178868D01*
Y1180941D01*
X941961Y1181984D01*
X964806D01*
X965507Y1181283D01*
Y1179258D01*
Y1162041D01*
X961878Y1158412D01*
G37*
G36*
G01X941432Y1160958D02*
X946932D01*
X947132Y1160758D01*
Y1158858D01*
X946932Y1158658D01*
X941332D01*
X941132Y1158858D01*
Y1160658D01*
X941432Y1160958D01*
G37*
G36*
G01X976300Y1243173D02*
X934807D01*
X934581Y1242946D01*
Y1214128D01*
X936729Y1211980D01*
X936778Y1212029D01*
X978583D01*
X980607Y1214053D01*
Y1242520D01*
X979954Y1243173D01*
X976300D01*
G37*
G36*
G01X934092Y1325503D02*
G03I-510J0D01*
G37*
G36*
G01X933547Y1315922D02*
G03I-510J0D01*
G37*
G36*
G01X935583Y1466833D02*
Y1456940D01*
X936934Y1455589D01*
X961969D01*
X963170Y1456790D01*
Y1466984D01*
X962121Y1468033D01*
X936783D01*
X935583Y1466833D01*
G37*
G36*
G01X1059278Y1548340D02*
X1075415D01*
G02X1075557Y1548281I0J-200D01*
G01X1077439Y1546399D01*
G02X1077498Y1546257I-141J-142D01*
G01Y1512423D01*
G02X1077439Y1512281I-200J0D01*
G01X1076557Y1511399D01*
X1076529Y1511370D01*
X1076455Y1511340D01*
X943081D01*
G02X942939Y1511399I0J200D01*
G01X941057Y1513281D01*
X941028Y1513309D01*
X940998Y1513383D01*
Y1547257D01*
G02X941057Y1547399I200J0D01*
G01X941939Y1548281D01*
G02X942081Y1548340I142J-141D01*
G01X957686D01*
X959788Y1546238D01*
X962380D01*
X964482Y1548340D01*
X989314D01*
X991400Y1546254D01*
X993992D01*
X996078Y1548340D01*
X1020914D01*
X1023000Y1546254D01*
X1025592D01*
X1027678Y1548340D01*
X1052514D01*
X1054600Y1546254D01*
X1057192D01*
X1059278Y1548340D01*
G37*
G36*
G01X963366Y1627324D02*
X1001157D01*
X1002943Y1629110D01*
Y1643713D01*
Y1647947D01*
X1001050Y1649840D01*
X958650D01*
X941422D01*
X939961Y1648379D01*
Y1633609D01*
X946246Y1627324D01*
X963366D01*
G37*
G36*
G01X961932Y164361D02*
X963456Y165885D01*
X965937D01*
X971323Y160499D01*
X973781Y158041D01*
X975689D01*
X982157D01*
X982469Y157729D01*
Y150933D01*
X981070Y149534D01*
X975586D01*
X956386D01*
X956321Y149599D01*
X955221Y150699D01*
Y163199D01*
Y163742D01*
X955840Y164361D01*
X961932D01*
G37*
G36*
G01X961128Y180895D02*
X965009D01*
G02X965151Y180836I0J-200D01*
G01X965830Y180156D01*
G02X965888Y180015I-142J-141D01*
G01Y179202D01*
G03X965928Y178899I1202J4D01*
G01X965934Y178874D01*
Y178473D01*
G03X965993Y178331I200J0D01*
G01X966448Y177876D01*
G02X966507Y177734I-141J-142D01*
G01Y174123D01*
G02X966448Y173981I-200J0D01*
G01X966421Y173954D01*
G02X966279Y173895I-142J141D01*
G01X963705D01*
G03X963563Y173836I0J-200D01*
G01X963203Y173476D01*
G02X963061Y173417I-142J141D01*
G01X958392D01*
G02X958250Y173476I0J200D01*
G01X958187Y173539D01*
G02X958128Y173681I141J142D01*
G01Y177895D01*
G02X958187Y178037I200J0D01*
G01X960986Y180836D01*
G02X961128Y180895I142J-141D01*
G37*
G36*
G01X956185Y614017D02*
G03I-656J0D01*
G37*
G36*
G01X951755Y632206D02*
G03I-656J0D01*
G37*
G36*
G01X952349Y812730D02*
G03I-510J0D01*
G37*
G36*
G01X958707Y859384D02*
G03I-656J0D01*
G37*
G36*
G01X948716Y891468D02*
G03I-656J0D01*
G37*
G36*
G01X952023Y913648D02*
G03I-656J0D01*
G37*
G36*
G01X957655Y1152669D02*
Y1148586D01*
X959796Y1146445D01*
Y1146436D01*
X960512Y1145720D01*
Y1136374D01*
X962257Y1134629D01*
Y1106618D01*
X970108Y1098767D01*
X973463D01*
X974828Y1097402D01*
Y1062463D01*
X973827Y1061462D01*
X973093D01*
X957903D01*
X955825D01*
X955192D01*
X953522Y1063132D01*
Y1081439D01*
X948267Y1086694D01*
Y1087230D01*
Y1132206D01*
X949299Y1133238D01*
X956348Y1140287D01*
Y1141604D01*
Y1159006D01*
X955578Y1159776D01*
Y1162154D01*
X955820Y1162396D01*
X957420D01*
X957655Y1162161D01*
Y1152669D01*
G37*
G36*
G01X954420Y1162396D02*
X952520D01*
X952320Y1162196D01*
Y1157796D01*
X952620Y1157496D01*
X954320D01*
X954568Y1157744D01*
Y1162248D01*
X954420Y1162396D01*
G37*
G36*
G01X951994Y1156196D02*
X954220D01*
X954620Y1155796D01*
Y1154896D01*
X954420Y1154696D01*
X951032D01*
X948532Y1157196D01*
Y1160958D01*
X948732Y1161158D01*
X950332D01*
X950632Y1160858D01*
X950732Y1160758D01*
Y1157458D01*
X951994Y1156196D01*
G37*
G36*
G01X960980Y1499540D02*
Y1497880D01*
X961220Y1497640D01*
X963470D01*
X964540Y1498710D01*
Y1502010D01*
X964270Y1502280D01*
X962620D01*
X962250Y1501910D01*
Y1500530D01*
Y1500060D01*
X961930Y1499740D01*
X961180D01*
X960980Y1499540D01*
G37*
G36*
G01X957400Y1507240D02*
Y1498320D01*
X958040Y1497680D01*
X959860D01*
X959980Y1497800D01*
Y1500030D01*
X960300Y1500350D01*
Y1507330D01*
X960270Y1507360D01*
X957520D01*
X957400Y1507240D01*
G37*
G36*
G01X1042590Y1681006D02*
Y1716694D01*
X1040533Y1718751D01*
X957289D01*
X956849Y1718311D01*
X954620Y1716082D01*
Y1672942D01*
Y1660991D01*
Y1655290D01*
X956012Y1653898D01*
X961713D01*
X1007627D01*
X1013129D01*
X1040828D01*
X1041350Y1654420D01*
Y1661110D01*
X1042590Y1662350D01*
Y1681006D01*
G37*
G36*
G01X967717Y211834D02*
X974856D01*
G02X974998Y211775I0J-200D01*
G01X975001Y211772D01*
G02X975060Y211630I-141J-142D01*
G01Y209925D01*
G03X975119Y209783I200J0D01*
G01X975913Y208989D01*
G03X976055Y208930I142J141D01*
G01X981097D01*
G02X981239Y208871I0J-200D01*
G01X981281Y208829D01*
G03X981423Y208770I142J141D01*
G01X990217D01*
G02X990359Y208711I0J-200D01*
G01X990381Y208689D01*
X995148D01*
G02X995290Y208630I0J-200D01*
G01X995412Y208508D01*
G02X995471Y208366I-141J-142D01*
G01Y194282D01*
G02X995412Y194140I-200J0D01*
G01X995220Y193948D01*
X995192Y193919D01*
X995118Y193889D01*
X986664D01*
G03X986522Y193830I0J-200D01*
G01X985245Y192553D01*
G02X985103Y192494I-142J141D01*
G01X984097D01*
G03X983955Y192435I0J-200D01*
G01X982689Y191169D01*
G03X982630Y191027I141J-142D01*
G01Y188643D01*
G02X982571Y188501I-200J0D01*
G01X981860Y187790D01*
G02X981718Y187731I-142J141D01*
G01X980505D01*
G03X980363Y187672I0J-200D01*
G01X978960Y186268D01*
G03X978901Y186126I141J-142D01*
G01Y174316D01*
G03X978960Y174174I200J0D01*
G01X980834Y172300D01*
G03X980976Y172241I142J141D01*
G01X981041D01*
X981150Y172153D01*
X981165Y172084D01*
G03X981492Y171485I1184J258D01*
G01X986293Y166684D01*
G03X986912Y166353I856J857D01*
G01X986942Y166347D01*
X986992Y166320D01*
X986993Y166319D01*
X987066Y166289D01*
X987861D01*
G02X987966Y166260I1J-200D01*
G03X988751Y166038I786J1281D01*
G03X989536Y166260I-1J1503D01*
G02X989641Y166289I104J-171D01*
G01X993632D01*
G02X993774Y166230I0J-200D01*
G01X993847Y166157D01*
G03X993989Y166098I142J141D01*
G01X998599D01*
G02X998741Y166039I0J-200D01*
G01X998852Y165928D01*
G02X998911Y165786I-141J-142D01*
G01Y165472D01*
G02X998852Y165330I-200J0D01*
G01X998640Y165118D01*
X998612Y165089D01*
X998538Y165059D01*
X991644D01*
G03X991502Y165000I0J-200D01*
G01X991060Y164558D01*
G03X991001Y164416I141J-142D01*
G01Y163029D01*
X991020Y163010D01*
Y162984D01*
X991616Y162388D01*
G02X991635Y162365I-144J-138D01*
G01X991661Y162331D01*
X991845Y162147D01*
G03X991987Y162088I142J141D01*
G01X996484D01*
G02X996626Y162029I0J-200D01*
G01X996769Y161886D01*
G02X996828Y161744I-141J-142D01*
G01Y161535D01*
G02X996769Y161393I-200J0D01*
G01X996619Y161243D01*
G02X996477Y161184I-142J141D01*
G01X990924D01*
G03X990782Y161125I0J-200D01*
G01X990137Y160479D01*
X990109Y160450D01*
X990035Y160420D01*
X986445D01*
G03X984883Y159773I1J-2211D01*
G01X984615Y159505D01*
G02X984473Y159446I-142J141D01*
G01X975829D01*
G02X975687Y159505I0J200D01*
G01X973688Y161505D01*
X969513Y165679D01*
G02X969454Y165821I141J142D01*
G01Y176473D01*
G03X969395Y176615I-200J0D01*
G01X966949Y179061D01*
G02X966890Y179203I141J142D01*
G01Y180448D01*
G03X966831Y180590I-200J0D01*
G01X966150Y181271D01*
G02X966091Y181413I141J142D01*
G01Y194722D01*
G02X966150Y194864I200J0D01*
G01X966831Y195545D01*
G03X966890Y195687I-141J142D01*
G01Y211007D01*
G02X966949Y211149I200J0D01*
G01X967575Y211775D01*
G02X967717Y211834I142J-141D01*
G37*
G36*
G01X968557Y220857D02*
X971423D01*
X972432Y219848D01*
Y214669D01*
X971686Y213923D01*
X967227D01*
X966736Y214414D01*
Y217854D01*
X967575Y219875D01*
X968557Y220857D01*
G37*
G36*
G01X974126Y317648D02*
G03I-510J0D01*
G37*
G36*
G01X996876Y169683D02*
Y169353D01*
X996576Y169053D01*
X994136D01*
X993976Y169213D01*
Y171733D01*
Y172053D01*
X991306Y174723D01*
Y180811D01*
X990764Y181353D01*
X988306D01*
X988106Y181553D01*
Y184684D01*
X989721Y186299D01*
X1002921D01*
X1010821Y178399D01*
Y173727D01*
X1010537Y173443D01*
X1007236D01*
X1004636D01*
X1004436Y173643D01*
Y180084D01*
X1003321Y181199D01*
X1001452D01*
X1000906Y180653D01*
X995406D01*
X994896Y180143D01*
Y171663D01*
Y170403D01*
X995326Y169973D01*
X996586D01*
X996876Y169683D01*
G37*
G36*
G01X995546Y209716D02*
Y211063D01*
X995246Y211363D01*
X991013D01*
X989213Y213163D01*
X976646D01*
X976152Y212668D01*
Y210167D01*
X976382Y209940D01*
X981750D01*
X981870Y209820D01*
X990680D01*
X990810Y209690D01*
X995520D01*
X995546Y209716D01*
G37*
G36*
G01X995296Y215823D02*
Y218323D01*
X994696Y218923D01*
X986893D01*
X986830Y218860D01*
Y215470D01*
X987077Y215223D01*
X994696D01*
X995296Y215823D01*
G37*
G36*
G01X981896Y222623D02*
X995096D01*
X995296Y222423D01*
Y220086D01*
X995210Y220000D01*
X985240D01*
X984730Y219490D01*
Y215408D01*
X984036Y214714D01*
X979766D01*
X979375Y215105D01*
Y215610D01*
Y221837D01*
X980161Y222623D01*
X981896D01*
G37*
G36*
G01X988970Y354725D02*
G03I-510J0D01*
G37*
G36*
G01X982820Y398016D02*
X989167D01*
X989836Y398685D01*
Y409334D01*
X989460Y409710D01*
X984072D01*
X982193Y407831D01*
Y398643D01*
X982820Y398016D01*
G37*
G36*
G01X991541Y528574D02*
G03I-510J0D01*
G37*
G36*
G01X979425Y1054184D02*
Y1076084D01*
Y1076484D01*
X980125Y1077184D01*
X980525D01*
X992609D01*
X993400Y1076393D01*
Y1054345D01*
X992839Y1053784D01*
X979825D01*
X979425Y1054184D01*
G37*
G36*
G01X984346Y1499540D02*
Y1497880D01*
X984586Y1497640D01*
X986836D01*
X987906Y1498710D01*
Y1502010D01*
X987636Y1502280D01*
X985986D01*
X985616Y1501910D01*
Y1500530D01*
Y1500060D01*
X985296Y1499740D01*
X984546D01*
X984346Y1499540D01*
G37*
G36*
G01X980766Y1507240D02*
Y1498320D01*
X981406Y1497680D01*
X983226D01*
X983346Y1497800D01*
Y1500030D01*
X983666Y1500350D01*
Y1507330D01*
X983636Y1507360D01*
X980886D01*
X980766Y1507240D01*
G37*
G36*
G01X995886Y159403D02*
Y159903D01*
X996116Y160133D01*
X999306D01*
X1003046D01*
X1004000Y159179D01*
X1007000D01*
X1007236Y158943D01*
Y157443D01*
X1006736Y156943D01*
X1002496D01*
X998346D01*
X995886Y159403D01*
G37*
G36*
G01X997004Y209299D02*
X1001338D01*
G02X1001480Y209240I0J-200D01*
G01X1002162Y208558D01*
G02X1002221Y208416I-141J-142D01*
G01Y193282D01*
G03X1002280Y193140I200J0D01*
G01X1004362Y191058D01*
G03X1004504Y190999I142J141D01*
G01X1018438D01*
G02X1018580Y190940I0J-200D01*
G01X1020362Y189158D01*
G02X1020421Y189016I-141J-142D01*
G01Y187882D01*
G03X1020480Y187740I200J0D01*
G01X1021362Y186858D01*
G03X1021504Y186799I142J141D01*
G01X1025038D01*
G02X1025180Y186740I0J-200D01*
G01X1025562Y186358D01*
G02X1025621Y186216I-141J-142D01*
G01Y160722D01*
G02X1025562Y160580I-200J0D01*
G01X1024440Y159458D01*
G02X1024298Y159399I-142J141D01*
G01X1019032D01*
X1017987Y160444D01*
Y162467D01*
X1017355Y163099D01*
X1016118D01*
X992404D01*
G02X992263Y163158I1J200D01*
G01X992022Y163399D01*
Y163425D01*
X992021D01*
Y163716D01*
G02X992080Y163858I200J0D01*
G01X992162Y163940D01*
G02X992304Y163999I142J-141D01*
G01X999638D01*
G03X999780Y164058I0J200D01*
G01X999962Y164240D01*
G03X1000021Y164382I-141J142D01*
G01Y166716D01*
G03X999962Y166858I-200J0D01*
G01X999780Y167040D01*
G03X999638Y167099I-142J-141D01*
G01X998631D01*
G03X998600Y167100I-54J-1200D01*
G01X994403D01*
G02X994262Y167158I0J200D01*
G01X993980Y167440D01*
G02X993921Y167582I141J142D01*
G01Y167716D01*
G02X993980Y167858I200J0D01*
G01X994062Y167940D01*
G02X994204Y167999I142J-141D01*
G01X1007038D01*
G03X1007180Y168058I0J200D01*
G01X1008362Y169240D01*
G02X1008504Y169299I142J-141D01*
G01X1011338D01*
G03X1011480Y169358I0J200D01*
G01X1011712Y169590D01*
G03X1011771Y169732I-141J142D01*
G01Y173218D01*
X1011801Y173291D01*
X1011822Y173312D01*
Y178771D01*
X1011792Y178844D01*
X1011771Y178865D01*
Y178916D01*
G03X1011712Y179058I-200J0D01*
G01X1003530Y187240D01*
G03X1003388Y187299I-142J-141D01*
G01X1003337D01*
X1003336Y187300D01*
X997802D01*
G02X997661Y187359I1J200D01*
G01X996880Y188140D01*
G02X996821Y188282I141J142D01*
G01Y208716D01*
G03X996762Y208858I-200J0D01*
G01X996751Y208869D01*
X996721Y208942D01*
Y209016D01*
G02X996780Y209158I200J0D01*
G01X996862Y209240D01*
G02X997004Y209299I142J-141D01*
G37*
G36*
G01X1004621Y219299D02*
X1006421D01*
X1006921Y218799D01*
Y210489D01*
X1006141Y209709D01*
X1003411D01*
X1003321Y209799D01*
Y212399D01*
X1004221Y213299D01*
Y218899D01*
X1004621Y219299D01*
G37*
G36*
G01X1000096Y220523D02*
X1006396D01*
X1006796Y220923D01*
Y224623D01*
X1006096Y225323D01*
X1000696D01*
X999996Y224623D01*
Y220623D01*
X1000096Y220523D01*
G37*
G36*
G01X993970Y354725D02*
G03I-510J0D01*
G37*
G36*
G01X998970D02*
G03I-510J0D01*
G37*
G36*
G01X997998Y370287D02*
G03I-510J0D01*
G37*
G36*
G01X992743Y373679D02*
G03I-510J0D01*
G37*
G36*
G01X1001381Y382070D02*
Y375651D01*
X1003809Y373223D01*
Y365589D01*
X1007580D01*
X1008005Y366014D01*
Y374463D01*
X1005610Y376858D01*
Y381414D01*
X1004799Y382225D01*
X1001536D01*
X1001381Y382070D01*
G37*
G36*
G01X1001372Y398028D02*
Y406070D01*
X1002721Y407419D01*
X1010215D01*
X1011589Y406045D01*
Y401499D01*
X1011115Y401025D01*
X1007068D01*
X1005319Y399276D01*
Y398153D01*
X1004994Y397828D01*
X1001572D01*
X1001372Y398028D01*
G37*
G36*
G01X992757Y485369D02*
G03I-720J0D01*
G37*
G36*
G01X998566Y518214D02*
G03I-510J0D01*
G37*
G36*
G01X1009554Y508795D02*
X1005359D01*
X1005206Y508948D01*
Y515012D01*
X1005481Y515287D01*
X1018280D01*
X1018955Y515962D01*
Y530878D01*
G02X1019160Y531373I700J0D01*
G01X1020988Y533201D01*
X1033829D01*
X1034029Y533001D01*
Y532001D01*
X1033829Y531801D01*
X1023792D01*
X1023506Y531515D01*
Y530897D01*
X1023761Y530642D01*
X1033829D01*
X1034029Y530442D01*
Y529442D01*
X1033829Y529242D01*
X1020755D01*
X1020355Y528842D01*
Y518330D01*
X1020839Y517846D01*
X1033829D01*
X1034029Y517646D01*
Y516646D01*
X1033829Y516446D01*
X1023792D01*
X1023554Y516208D01*
Y515494D01*
X1023761Y515287D01*
X1033829D01*
X1034029Y515087D01*
Y514087D01*
X1033829Y513887D01*
X1010924D01*
X1009706Y512669D01*
Y508947D01*
X1009554Y508795D01*
G37*
G36*
G01X998566Y523874D02*
G03I-510J0D01*
G37*
G36*
G01X999541Y528574D02*
G03I-510J0D01*
G37*
G36*
G01X1032040Y1420331D02*
G02I-15800J0D01*
G37*
G36*
G01X1004132Y1507240D02*
Y1498320D01*
X1004772Y1497680D01*
X1006592D01*
X1006712Y1497800D01*
Y1500030D01*
X1007032Y1500350D01*
Y1507330D01*
X1007002Y1507360D01*
X1004252D01*
X1004132Y1507240D01*
G37*
G36*
G01X1019247Y153711D02*
X1024601D01*
X1024831Y153481D01*
Y146531D01*
X1024378Y146078D01*
X1023911Y145611D01*
X1019937D01*
X1019470Y146078D01*
X1019017Y146531D01*
Y153481D01*
X1019247Y153711D01*
G37*
G36*
G01X1015796Y216423D02*
Y209374D01*
X1015396Y208974D01*
Y197923D01*
X1015397D01*
X1016521Y196799D01*
X1024096D01*
X1024896Y197599D01*
Y215723D01*
Y219223D01*
X1024336Y219783D01*
X1016136D01*
X1015796Y219443D01*
Y216423D01*
G37*
G36*
G01X1012730Y243638D02*
G03I-510J0D01*
G37*
G36*
G01X1012721Y547574D02*
G03I-510J0D01*
G37*
G36*
G01X1015571D02*
G03I-510J0D01*
G37*
G36*
G01X1016471Y554432D02*
G03I-510J0D01*
G37*
G36*
G01X1014006Y1312502D02*
G03I-510J0D01*
G37*
G36*
G01X1013506Y1306502D02*
G03I-510J0D01*
G37*
G36*
G01X1014006Y1325502D02*
G03I-510J0D01*
G37*
G36*
G01X1012006Y1335002D02*
G03I-510J0D01*
G37*
G36*
G01X1014006Y1344502D02*
G03I-510J0D01*
G37*
G36*
G01X1007712Y1499540D02*
Y1497880D01*
X1007952Y1497640D01*
X1010202D01*
X1011272Y1498710D01*
Y1502010D01*
X1011002Y1502280D01*
X1009352D01*
X1008982Y1501910D01*
Y1500530D01*
Y1500060D01*
X1008662Y1499740D01*
X1007912D01*
X1007712Y1499540D01*
G37*
G36*
G01X1021030Y67638D02*
X1021384Y67765D01*
G02X1021606Y67705I68J-188D01*
G03X1022842Y66299I24265J20085D01*
G02X1022896Y66163I-146J-137D01*
G01Y54252D01*
G03X1026772Y50376I3876J0D01*
G01X1169041D01*
G02X1169183Y50317I0J-200D01*
G01X1169574Y49925D01*
G03X1170431Y49570I857J857D01*
G01X1175710D01*
X1187885D01*
X1188691Y50376D01*
X1518118D01*
G02X1529990Y38504I0J-11872D01*
G01Y15657D01*
G02X1529906Y15494I-200J0D01*
G03X1528749Y14146I2149J-3015D01*
G01X1528718Y14084D01*
X1528592Y14025D01*
X1528146Y14132D01*
G02X1527992Y14326I46J195D01*
G01Y38504D01*
G03X1518118Y48378I-9874J0D01*
G01X1026772D01*
G02X1020898Y54252I0J5874D01*
G01Y67450D01*
G02X1021030Y67638I200J0D01*
G37*
G36*
G01X1021730Y243638D02*
G03I-510J0D01*
G37*
G36*
G01X1022971Y558932D02*
G03I-510J0D01*
G37*
G36*
G01X1028089D02*
G03I-510J0D01*
G37*
G36*
G01X1033089Y559934D02*
G03I-510J0D01*
G37*
G36*
G01X1036301Y773582D02*
G03I-656J0D01*
G37*
G36*
G01X1043428Y1381880D02*
X1057768D01*
X1059268Y1380380D01*
Y1379145D01*
X1064526Y1373886D01*
Y1364384D01*
X1065097Y1363813D01*
X1072260D01*
X1074175Y1361898D01*
X1080696D01*
Y1364872D01*
X1079471Y1366097D01*
X1076825D01*
X1076711Y1366211D01*
Y1366225D01*
X1076475Y1366461D01*
X1073665D01*
X1073635Y1366491D01*
Y1367298D01*
X1073662Y1367325D01*
X1077013D01*
X1077328Y1367640D01*
Y1371610D01*
X1077160Y1371778D01*
X1073500D01*
X1073411Y1371867D01*
Y1372505D01*
X1073541Y1372635D01*
X1077203D01*
X1077358Y1372790D01*
Y1373864D01*
X1077459Y1373965D01*
G03X1077520Y1373953I513J2448D01*
G03X1077975Y1373909I467J2458D01*
G01X1078000D01*
G03X1078759Y1374032I-16J2502D01*
G01X1078789Y1374042D01*
X1083880D01*
X1084022Y1373983D01*
X1084246Y1373759D01*
Y1368209D01*
X1084244Y1368207D01*
Y1366258D01*
X1085844Y1364658D01*
X1100015D01*
X1100115Y1364558D01*
X1104308D01*
X1106968Y1361898D01*
X1113236D01*
X1113328Y1361990D01*
Y1364660D01*
X1111936Y1366052D01*
X1109470D01*
X1109311Y1366211D01*
Y1366225D01*
X1109093Y1366443D01*
X1106143D01*
X1105971Y1366615D01*
Y1367215D01*
X1106091Y1367335D01*
X1109603D01*
X1109988Y1367720D01*
Y1371570D01*
X1109790Y1371768D01*
X1106087D01*
X1106011Y1371844D01*
Y1372505D01*
X1106141Y1372635D01*
X1109763D01*
X1109938Y1372810D01*
Y1373914D01*
X1110002Y1373978D01*
G03X1110120Y1373953I577J2434D01*
G03X1110575Y1373909I467J2458D01*
G01X1110600D01*
G03X1111359Y1374032I-16J2502D01*
G01X1111389Y1374042D01*
X1116480D01*
X1116622Y1373983D01*
X1116846Y1373759D01*
Y1368209D01*
X1116841Y1368204D01*
Y1366137D01*
X1118248Y1364730D01*
X1127180D01*
X1127418Y1364968D01*
X1132205D01*
X1132683Y1364490D01*
X1137183D01*
X1139785Y1361888D01*
X1145836D01*
X1145988Y1362040D01*
Y1364730D01*
X1144696Y1366022D01*
X1142200D01*
X1142011Y1366211D01*
Y1366225D01*
X1141791Y1366445D01*
X1138841D01*
X1138671Y1366615D01*
Y1367215D01*
X1138771Y1367315D01*
X1140881D01*
X1140891Y1367305D01*
X1142313D01*
X1142648Y1367640D01*
Y1371540D01*
X1142418Y1371770D01*
X1138821D01*
X1138711Y1371880D01*
Y1372505D01*
X1138841Y1372635D01*
X1142513D01*
X1142588Y1372710D01*
Y1373721D01*
X1142820Y1373953D01*
G03X1143275Y1373909I467J2458D01*
G01X1143300D01*
G03X1144059Y1374032I-16J2502D01*
G01X1144089Y1374042D01*
X1149180D01*
X1149322Y1373983D01*
X1149439Y1373866D01*
Y1365868D01*
X1150547Y1364760D01*
X1159850D01*
X1160248Y1365158D01*
X1164703D01*
X1165293Y1364568D01*
X1169699D01*
X1172379Y1361888D01*
X1178766D01*
X1178888Y1362010D01*
Y1364810D01*
X1177616Y1366082D01*
X1175040D01*
X1174911Y1366211D01*
Y1366225D01*
X1174683Y1366453D01*
X1171733D01*
X1171571Y1366615D01*
Y1367215D01*
X1171693Y1367337D01*
X1175305D01*
X1175518Y1367550D01*
Y1371660D01*
X1175408Y1371770D01*
X1171698D01*
X1171611Y1371857D01*
Y1372505D01*
X1171741Y1372635D01*
X1175353D01*
X1175538Y1372820D01*
Y1373771D01*
X1175720Y1373953D01*
G03X1176175Y1373909I467J2458D01*
G01X1176200D01*
G03X1176959Y1374032I-16J2502D01*
G01X1176989Y1374042D01*
X1182080D01*
X1182222Y1373983D01*
X1182446Y1373759D01*
Y1365832D01*
X1183568Y1364710D01*
X1192760D01*
X1192938Y1364888D01*
X1199345D01*
X1199825Y1364408D01*
X1202475D01*
X1204995Y1361888D01*
X1211638D01*
Y1364820D01*
X1210398Y1366060D01*
X1207783D01*
X1207395Y1366448D01*
X1204610D01*
X1204515Y1366543D01*
Y1367248D01*
X1204603Y1367336D01*
X1207894D01*
X1208388Y1367830D01*
Y1371550D01*
X1208167Y1371771D01*
X1204547D01*
X1204411Y1371907D01*
Y1372505D01*
X1204541Y1372635D01*
X1208223D01*
X1208348Y1372760D01*
Y1373895D01*
X1208426Y1373973D01*
G03X1208520Y1373953I567J2436D01*
G03X1208975Y1373909I467J2458D01*
G01X1209000D01*
G03X1209759Y1374032I-16J2502D01*
G01X1209789Y1374042D01*
X1214880D01*
X1215022Y1373983D01*
X1215246Y1373759D01*
Y1366008D01*
X1216564Y1364690D01*
X1225910D01*
X1226098Y1364878D01*
X1241074D01*
X1244984Y1368788D01*
X1247526D01*
X1257536D01*
X1263616Y1362708D01*
Y1352108D01*
X1254496Y1342988D01*
X1239259D01*
X1237145Y1340874D01*
Y1337741D01*
X1236620Y1337216D01*
X1206495D01*
X1204525Y1335246D01*
Y1328648D01*
X1206105Y1327068D01*
X1224695D01*
X1225535Y1326228D01*
Y1321338D01*
X1224945Y1320748D01*
X1173745D01*
X1173125Y1321368D01*
Y1326558D01*
X1173635Y1327068D01*
X1192765D01*
X1194055Y1328358D01*
Y1335818D01*
X1192657Y1337216D01*
X1029962D01*
X1028018Y1339160D01*
Y1366470D01*
X1043428Y1381880D01*
G37*
G36*
G01X1031078Y1499540D02*
Y1497880D01*
X1031318Y1497640D01*
X1033568D01*
X1034638Y1498710D01*
Y1502010D01*
X1034368Y1502280D01*
X1032718D01*
X1032348Y1501910D01*
Y1500530D01*
Y1500060D01*
X1032028Y1499740D01*
X1031278D01*
X1031078Y1499540D01*
G37*
G36*
G01X1027498Y1507240D02*
Y1498320D01*
X1028138Y1497680D01*
X1029958D01*
X1030078Y1497800D01*
Y1500030D01*
X1030398Y1500350D01*
Y1507330D01*
X1030368Y1507360D01*
X1027618D01*
X1027498Y1507240D01*
G37*
G36*
G01X1077344Y204724D02*
G03I-19685J0D01*
G37*
G36*
G01X1044522Y268659D02*
G03I-510J0D01*
G37*
G36*
G01X1064560Y397893D02*
X1052399D01*
X1051450Y396944D01*
Y384172D01*
X1046496Y379218D01*
X1037248D01*
X1036794Y378764D01*
Y375833D01*
X1037538Y375089D01*
X1064620D01*
X1065075Y375544D01*
Y378599D01*
X1064539Y379135D01*
X1055827D01*
X1053886Y381076D01*
Y393297D01*
X1054134Y393545D01*
X1056342D01*
X1059191Y390696D01*
X1066190D01*
X1067489Y391995D01*
Y394947D01*
X1068439Y395897D01*
X1073826D01*
X1075314D01*
X1075954Y396537D01*
Y398333D01*
Y400872D01*
X1074698Y402128D01*
X1068795D01*
X1064560Y397893D01*
G37*
G36*
G01X1045525Y444404D02*
G03I-510J0D01*
G37*
G36*
G01X1037722Y510940D02*
G03I-510J0D01*
G37*
G36*
G01X1041764Y523874D02*
G03I-510J0D01*
G37*
G36*
G01X1040607Y529508D02*
G03I-510J0D01*
G37*
G36*
G01X1043690Y547027D02*
G03I-510J0D01*
G37*
G36*
G01X1041400Y735717D02*
G03I-510J0D01*
G37*
G36*
G01X1041721Y832126D02*
G03I-656J0D01*
G37*
G36*
G01Y868937D02*
G03I-656J0D01*
G37*
G36*
G01Y905749D02*
G03I-656J0D01*
G37*
G36*
G01Y942560D02*
G03I-656J0D01*
G37*
G36*
G01Y1089804D02*
G03I-656J0D01*
G37*
G36*
G01Y1126615D02*
G03I-656J0D01*
G37*
G36*
G01Y1163426D02*
G03I-656J0D01*
G37*
G36*
G01Y1200237D02*
G03I-656J0D01*
G37*
G36*
G01Y1237048D02*
G03I-656J0D01*
G37*
G36*
G01X1093656Y1335882D02*
X1067999D01*
X1065939D01*
X1046307D01*
X1045399Y1334974D01*
Y1321911D01*
X1046300Y1321010D01*
X1072860D01*
X1073305Y1321455D01*
Y1327618D01*
X1074915Y1329228D01*
X1093485D01*
X1094140Y1329883D01*
Y1335398D01*
X1093656Y1335882D01*
G37*
G36*
G01X1054865Y258698D02*
G03I-510J0D01*
G37*
G36*
G01X1052005Y265133D02*
G03I-510J0D01*
G37*
G36*
G01X1066062Y271441D02*
G03I-510J0D01*
G37*
G36*
G01X1056444Y385488D02*
G03I-510J0D01*
G37*
G36*
G01X1053579Y415018D02*
X1065119D01*
X1065543Y414594D01*
Y411821D01*
X1064794Y411072D01*
X1058100D01*
X1056152Y409124D01*
Y404603D01*
X1055752Y404203D01*
X1051931D01*
X1051631Y404503D01*
Y413070D01*
X1053579Y415018D01*
G37*
G36*
G01X1057027Y512787D02*
G03I-510J0D01*
G37*
G36*
G01X1062347Y519703D02*
G03I-510J0D01*
G37*
G36*
G01X1064124Y733409D02*
G03I-510J0D01*
G37*
G36*
G01X1057863Y791969D02*
G03I-656J0D01*
G37*
G36*
G01Y828780D02*
G03I-656J0D01*
G37*
G36*
G01Y865591D02*
G03I-656J0D01*
G37*
G36*
G01Y902402D02*
G03I-656J0D01*
G37*
G36*
G01Y939213D02*
G03I-656J0D01*
G37*
G36*
G01Y1086457D02*
G03I-656J0D01*
G37*
G36*
G01Y1123268D02*
G03I-656J0D01*
G37*
G36*
G01Y1233701D02*
G03I-656J0D01*
G37*
G36*
G01X1070936Y1318936D02*
X1194862D01*
G02X1195004Y1318877I0J-200D01*
G01X1196240Y1317641D01*
G02X1196299Y1317499I-141J-142D01*
G01Y1280955D01*
G02X1196220Y1280797I-200J1D01*
G03Y1274597I2370J-3100D01*
G02X1196299Y1274439I-121J-159D01*
G01Y1267731D01*
G02X1196240Y1267589I-200J0D01*
G01X1194341Y1265690D01*
G02X1194199Y1265631I-142J141D01*
G01X1061375D01*
G02X1061233Y1265690I0J200D01*
G01X1059454Y1267469D01*
G02X1059395Y1267611I141J142D01*
G01Y1274532D01*
G02X1059468Y1274687I200J0D01*
G03X1060888Y1277697I-2482J3011D01*
G03X1059468Y1280707I-3902J-1D01*
G02X1059395Y1280862I127J155D01*
G01Y1305414D01*
G02X1059445Y1305546I200J0D01*
G03X1060072Y1307203I-1874J1656D01*
G03X1059843Y1308251I-2502J2D01*
G02X1059883Y1308476I181J84D01*
G01X1060356Y1308949D01*
G02X1060498Y1309008I142J-141D01*
G01X1067736D01*
G03X1067878Y1309067I0J200D01*
G01X1070240Y1311429D01*
G03X1070299Y1311571I-141J142D01*
G01Y1318299D01*
G02X1070358Y1318441I200J0D01*
G01X1070794Y1318877D01*
G02X1070936Y1318936I142J-141D01*
G37*
G36*
G01X1064210Y1435890D02*
X1064211Y1435889D01*
G02X1064270Y1435747I-141J-142D01*
G01Y1384993D01*
G02X1064211Y1384851I-200J0D01*
G01X1063979Y1384619D01*
G02X1063837Y1384560I-142J141D01*
G01X1059383D01*
G02X1059241Y1384619I0J200D01*
G01X1056759Y1387101D01*
G02X1056700Y1387243I141J142D01*
G01Y1434627D01*
G02X1056759Y1434769I200J0D01*
G01X1057821Y1435831D01*
G02X1057963Y1435890I142J-141D01*
G01X1064210D01*
G37*
G36*
G01X1070503Y1365418D02*
X1066908D01*
X1066002Y1366324D01*
Y1374300D01*
X1065614Y1374688D01*
X1061060Y1379242D01*
Y1383071D01*
G02X1061118Y1383211I197J0D01*
G01X1061387Y1383480D01*
G02X1061527Y1383538I140J-139D01*
G01X1067403D01*
G02X1067543Y1383480I0J-197D01*
G01X1067797Y1383226D01*
G02X1067855Y1383086I-139J-140D01*
G01Y1370570D01*
G03X1067913Y1370430I197J0D01*
G01X1068317Y1370026D01*
G03X1068457Y1369968I140J139D01*
G01X1068739D01*
X1068792Y1369952D01*
X1068816Y1369937D01*
G03X1069839Y1369638I1024J1603D01*
G03X1070548Y1369776I-2J1902D01*
G01X1070604Y1369798D01*
X1070718Y1369775D01*
X1070847Y1369646D01*
G02X1070905Y1369506I-139J-140D01*
G01Y1365820D01*
G02X1070847Y1365680I-197J0D01*
G01X1070643Y1365476D01*
G02X1070503Y1365418I-140J139D01*
G37*
G36*
G01X1054444Y1499540D02*
Y1497880D01*
X1054684Y1497640D01*
X1056934D01*
X1058004Y1498710D01*
Y1502010D01*
X1057734Y1502280D01*
X1056084D01*
X1055714Y1501910D01*
Y1500530D01*
Y1500060D01*
X1055394Y1499740D01*
X1054644D01*
X1054444Y1499540D01*
G37*
G36*
G01X1050864Y1507240D02*
Y1498320D01*
X1051504Y1497680D01*
X1053324D01*
X1053444Y1497800D01*
Y1500030D01*
X1053764Y1500350D01*
Y1507330D01*
X1053734Y1507360D01*
X1050984D01*
X1050864Y1507240D01*
G37*
G36*
G01X1068653Y383688D02*
G03I-510J0D01*
G37*
G36*
G01X1073714Y383417D02*
G03I-510J0D01*
G37*
G36*
G01X1069483Y389734D02*
G03I-656J0D01*
G37*
G36*
G01X1075456Y391262D02*
G03I-656J0D01*
G37*
G36*
G01X1078074Y411322D02*
G03I-656J0D01*
G37*
G36*
G01Y416763D02*
G03I-656J0D01*
G37*
G36*
G01Y421922D02*
G03I-656J0D01*
G37*
G36*
G01X1071422Y795315D02*
G03I-656J0D01*
G37*
G36*
G01Y832126D02*
G03I-656J0D01*
G37*
G36*
G01Y868937D02*
G03I-656J0D01*
G37*
G36*
G01Y905749D02*
G03I-656J0D01*
G37*
G36*
G01Y942560D02*
G03I-656J0D01*
G37*
G36*
G01Y1089804D02*
G03I-656J0D01*
G37*
G36*
G01Y1126615D02*
G03I-656J0D01*
G37*
G36*
G01Y1163426D02*
G03I-656J0D01*
G37*
G36*
G01Y1200237D02*
G03I-656J0D01*
G37*
G36*
G01Y1237048D02*
G03I-656J0D01*
G37*
G36*
G01X1126599Y1335882D02*
X1105799D01*
X1097799D01*
X1095899Y1333982D01*
Y1328982D01*
X1094699Y1327782D01*
X1075699D01*
X1074899Y1326982D01*
Y1325682D01*
Y1321582D01*
X1075453Y1321028D01*
X1105145D01*
X1105949Y1321832D01*
Y1327332D01*
X1106499Y1327882D01*
X1107399Y1328782D01*
X1126499D01*
X1127199Y1329482D01*
Y1330382D01*
Y1335282D01*
X1126599Y1335882D01*
G37*
G36*
G01X1077810Y1499540D02*
Y1497880D01*
X1078050Y1497640D01*
X1080300D01*
X1081370Y1498710D01*
Y1502010D01*
X1081100Y1502280D01*
X1079450D01*
X1079080Y1501910D01*
Y1500530D01*
Y1500060D01*
X1078760Y1499740D01*
X1078010D01*
X1077810Y1499540D01*
G37*
G36*
G01X1074230Y1507240D02*
Y1498320D01*
X1074870Y1497680D01*
X1076690D01*
X1076810Y1497800D01*
Y1500030D01*
X1077130Y1500350D01*
Y1507330D01*
X1077100Y1507360D01*
X1074350D01*
X1074230Y1507240D01*
G37*
G36*
G01X1082367Y269856D02*
G03I-510J0D01*
G37*
G36*
G01X1084329Y353094D02*
G03I-510J0D01*
G37*
G36*
G01X1115620Y390046D02*
X1124537D01*
X1125528Y391037D01*
Y402060D01*
Y405116D01*
X1125116Y405528D01*
X1118799D01*
X1117602Y404331D01*
Y398593D01*
X1114794Y395785D01*
X1111285D01*
X1110653Y395153D01*
Y379837D01*
Y377373D01*
X1109451Y376171D01*
X1093835D01*
X1093730Y376066D01*
Y374655D01*
X1093945Y374440D01*
X1121771D01*
X1121776Y374444D01*
X1122145D01*
X1122378Y374677D01*
Y378269D01*
Y378622D01*
X1122100Y378900D01*
X1115829D01*
X1114699Y380030D01*
Y389085D01*
X1115620Y390006D01*
Y390046D01*
G37*
G36*
G01X1094378Y427960D02*
G03I-656J0D01*
G37*
G36*
G01X1081643Y461516D02*
G03I-510J0D01*
G37*
G36*
G01X1087510Y477500D02*
G03I-510J0D01*
G37*
G36*
G01X1089240Y509362D02*
G03I-510J0D01*
G37*
G36*
G01X1082142Y648854D02*
G03I-510J0D01*
G37*
G36*
G01X1087564Y791969D02*
G03I-656J0D01*
G37*
G36*
G01Y828780D02*
G03I-656J0D01*
G37*
G36*
G01Y865591D02*
G03I-656J0D01*
G37*
G36*
G01Y902402D02*
G03I-656J0D01*
G37*
G36*
G01Y939213D02*
G03I-656J0D01*
G37*
G36*
G01Y1086457D02*
G03I-656J0D01*
G37*
G36*
G01Y1123268D02*
G03I-656J0D01*
G37*
G36*
G01Y1233701D02*
G03I-656J0D01*
G37*
G36*
G01X1198399Y1390714D02*
Y1366381D01*
X1198076Y1366058D01*
X1184265D01*
X1184049Y1366274D01*
Y1373949D01*
X1184373Y1374273D01*
X1189691D01*
X1190206Y1374787D01*
Y1377856D01*
X1191713Y1379363D01*
Y1385754D01*
X1190060Y1387408D01*
X1183889D01*
X1183545Y1387752D01*
X1182909Y1388388D01*
X1168686D01*
X1165499Y1385201D01*
Y1366881D01*
X1164776Y1366158D01*
X1151375D01*
X1151149Y1366384D01*
Y1373949D01*
X1151473Y1374273D01*
X1156791D01*
X1157311Y1374792D01*
Y1377861D01*
X1158813Y1379363D01*
Y1385068D01*
X1158799Y1385082D01*
Y1386499D01*
X1156958Y1388340D01*
X1136048D01*
X1132699Y1384991D01*
Y1366581D01*
X1132356Y1366238D01*
X1118715D01*
X1118449Y1366504D01*
Y1373949D01*
X1118773Y1374273D01*
X1124091D01*
X1124459Y1374640D01*
X1124599Y1374780D01*
Y1377849D01*
X1126113Y1379363D01*
Y1384868D01*
X1126099Y1384882D01*
Y1386428D01*
X1124199Y1388328D01*
X1103066D01*
X1100099Y1385361D01*
Y1366592D01*
X1099785Y1366278D01*
X1086025D01*
X1085849Y1366454D01*
Y1373949D01*
X1086173Y1374273D01*
X1091491D01*
X1091859Y1374640D01*
X1091999Y1374780D01*
Y1378906D01*
X1093131Y1380038D01*
Y1386686D01*
X1089375Y1390442D01*
Y1415592D01*
X1090890Y1417107D01*
X1150305D01*
X1172766D01*
X1182154Y1407719D01*
Y1396506D01*
X1185649Y1393011D01*
X1185662D01*
X1186500Y1392173D01*
X1187188Y1391485D01*
X1197628D01*
X1198399Y1390714D01*
G37*
G36*
G01X1093490Y1544240D02*
X1101071D01*
X1103795D01*
X1103911Y1544124D01*
X1104700Y1543335D01*
Y1540611D01*
Y1513400D01*
X1102640Y1511340D01*
X1082698D01*
X1081698Y1512340D01*
Y1544040D01*
X1081898Y1544240D01*
X1089150D01*
X1089450Y1543940D01*
Y1541450D01*
X1089780Y1541120D01*
X1092810D01*
X1093150Y1541460D01*
Y1543900D01*
X1093490Y1544240D01*
G37*
G36*
G01X1090653Y1643625D02*
G03I-510J0D01*
G37*
G36*
G01X1091536Y1653031D02*
G03I-510J0D01*
G37*
G36*
G01X1092540Y1720841D02*
G03I-510J0D01*
G37*
G36*
G01X1101122Y795315D02*
G03I-656J0D01*
G37*
G36*
G01Y832126D02*
G03I-656J0D01*
G37*
G36*
G01Y868937D02*
G03I-656J0D01*
G37*
G36*
G01Y905749D02*
G03I-656J0D01*
G37*
G36*
G01Y942560D02*
G03I-656J0D01*
G37*
G36*
G01Y1089804D02*
G03I-656J0D01*
G37*
G36*
G01Y1126615D02*
G03I-656J0D01*
G37*
G36*
G01Y1163426D02*
G03I-656J0D01*
G37*
G36*
G01Y1200237D02*
G03I-656J0D01*
G37*
G36*
G01Y1237048D02*
G03I-656J0D01*
G37*
G36*
G01X1159199Y1335882D02*
X1138399D01*
X1130399D01*
X1128499Y1333982D01*
Y1328982D01*
X1127299Y1327782D01*
X1108299D01*
X1107499Y1326982D01*
Y1325682D01*
Y1321582D01*
X1108063Y1321018D01*
X1137736D01*
X1138549Y1321832D01*
Y1327332D01*
X1139099Y1327882D01*
X1139999Y1328782D01*
X1159099D01*
X1159799Y1329482D01*
Y1330382D01*
Y1335282D01*
X1159199Y1335882D01*
G37*
G36*
G01X1097596Y1507240D02*
Y1498320D01*
X1098236Y1497680D01*
X1100056D01*
X1100176Y1497800D01*
Y1500030D01*
X1100496Y1500350D01*
Y1507330D01*
X1100466Y1507360D01*
X1097716D01*
X1097596Y1507240D01*
G37*
G36*
G01X1101176Y1499540D02*
Y1497880D01*
Y1495334D01*
X1101520Y1494990D01*
X1103250D01*
X1103510Y1495250D01*
Y1497640D01*
Y1499510D01*
X1103280Y1499740D01*
X1102126D01*
X1101376D01*
X1101176Y1499540D01*
G37*
G36*
G01X1106267Y1622431D02*
X1111061D01*
G02X1111203Y1622372I0J-200D01*
G01X1112213Y1621362D01*
G02X1112272Y1621220I-141J-142D01*
G01Y1615234D01*
G02X1112213Y1615092I-200J0D01*
G01X1111430Y1614309D01*
G02X1111288Y1614250I-142J141D01*
G01X1106718D01*
G02X1106576Y1614309I0J200D01*
G01X1106562Y1614324D01*
Y1614755D01*
G03X1106503Y1614896I-200J-1D01*
G01X1105889Y1615510D01*
G02X1105830Y1615652I141J142D01*
G01Y1621994D01*
G02X1105889Y1622136I200J0D01*
G01X1106125Y1622372D01*
G02X1106267Y1622431I142J-141D01*
G37*
G36*
G01X1114084Y1631823D02*
X1118194D01*
G02X1118336Y1631764I0J-200D01*
G01X1118458Y1631642D01*
G02X1118517Y1631500I-141J-142D01*
G01Y1625699D01*
G02X1118458Y1625557I-200J0D01*
G01X1118006Y1625105D01*
G02X1117864Y1625046I-142J141D01*
G01X1105998D01*
G02X1105798Y1625246I0J200D01*
G01Y1630009D01*
G02X1105848Y1630141I200J0D01*
G03X1106002Y1630334I-1649J1474D01*
G02X1106024Y1630361I165J-112D01*
G01X1106659Y1630996D01*
G02X1106801Y1631055I142J-141D01*
G01X1113150D01*
G03X1113292Y1631114I0J200D01*
G01X1113942Y1631764D01*
G02X1114084Y1631823I142J-141D01*
G37*
G36*
G01X1117484Y1691392D02*
Y1683960D01*
G02X1117425Y1683818I-200J0D01*
G01X1117086Y1683479D01*
G03X1117027Y1683337I141J-142D01*
G01Y1679430D01*
G02X1116968Y1679288I-200J0D01*
G01X1116821Y1679141D01*
G02X1116679Y1679082I-142J141D01*
G01X1108527D01*
G02X1108385Y1679141I0J200D01*
G01X1107974Y1679552D01*
G02X1107915Y1679694I141J142D01*
G01Y1685879D01*
G03X1107856Y1686021I-200J0D01*
G01X1106877Y1687000D01*
G02X1106818Y1687142I141J142D01*
G01Y1691172D01*
G02X1106877Y1691314I200J0D01*
G01X1107440Y1691877D01*
G02X1107582Y1691936I142J-141D01*
G01X1116940D01*
G02X1117082Y1691877I0J-200D01*
G01X1117425Y1691534D01*
G02X1117484Y1691392I-141J-142D01*
G37*
G36*
G01X1115777Y1695460D02*
X1114591Y1694274D01*
G02X1114449Y1694215I-142J141D01*
G01X1107640D01*
G02X1107498Y1694274I0J200D01*
G01X1107313Y1694459D01*
G02X1107254Y1694601I141J142D01*
G01Y1699690D01*
G02X1107313Y1699832I200J0D01*
G01X1107913Y1700432D01*
G02X1108055Y1700491I142J-141D01*
G01X1114525D01*
G02X1114667Y1700432I0J-200D01*
G01X1115777Y1699322D01*
G02X1115836Y1699180I-141J-142D01*
G01Y1695602D01*
G02X1115777Y1695460I-200J0D01*
G37*
G36*
G01X1117264Y791969D02*
G03I-656J0D01*
G37*
G36*
G01Y828780D02*
G03I-656J0D01*
G37*
G36*
G01Y865591D02*
G03I-656J0D01*
G37*
G36*
G01Y902402D02*
G03I-656J0D01*
G37*
G36*
G01Y939213D02*
G03I-656J0D01*
G37*
G36*
G01Y1086457D02*
G03I-656J0D01*
G37*
G36*
G01Y1233701D02*
G03I-656J0D01*
G37*
G36*
G01X1148435Y1437743D02*
Y1426760D01*
Y1423007D01*
X1147868Y1422440D01*
X1118048D01*
X1116028D01*
X1115358Y1423110D01*
Y1437590D01*
X1116158Y1438390D01*
X1147788D01*
X1148435Y1437743D01*
G37*
G36*
G01X1166367Y1575452D02*
X1166123D01*
G03X1165622Y1574952I0J-501D01*
G01Y1573750D01*
G03X1166123Y1573248I502J0D01*
G01X1166367D01*
X1166404Y1573233D01*
G03X1166873Y1573138I470J1117D01*
G01X1167947D01*
G02X1168147Y1572938I0J-200D01*
G01Y1572462D01*
G02X1167947Y1572262I-200J0D01*
G01X1166873D01*
G03X1166404Y1572167I1J-1212D01*
G01X1166367Y1572152D01*
X1166123D01*
G03X1165622Y1571652I0J-501D01*
G01Y1570450D01*
G03X1166123Y1569948I502J0D01*
G01X1166367D01*
X1166404Y1569933D01*
G03X1166873Y1569838I470J1117D01*
G01X1167947D01*
G02X1168147Y1569638I0J-200D01*
G01Y1565232D01*
G02X1168088Y1565090I-200J0D01*
G01X1167818Y1564820D01*
G02X1167676Y1564762I-141J142D01*
G01X1166873D01*
G03X1166404Y1564667I1J-1212D01*
G01X1166367Y1564652D01*
X1166123D01*
G03X1165622Y1564152I0J-501D01*
G01Y1563087D01*
G02X1165554Y1562937I-200J0D01*
G03X1164871Y1561431I1319J-1506D01*
G03X1166873Y1559429I2002J0D01*
G03X1167601Y1559566I0J2003D01*
G02X1167788Y1559545I74J-186D01*
G01X1168060Y1559359D01*
G02X1168147Y1559194I-113J-165D01*
G01Y1558070D01*
G02X1168060Y1557904I-200J-1D01*
G01X1167787Y1557718D01*
G02X1167602Y1557697I-112J165D01*
G01X1167601D01*
G03X1166691Y1557869I-912J-2330D01*
G03Y1552865I0J-2502D01*
G03X1167322Y1552946I-1J2503D01*
G02X1167475Y1552925I51J-194D01*
G03X1168090Y1552756I617J1042D01*
G01X1168897D01*
G02X1168974Y1552741I1J-200D01*
G01X1171760Y1551587D01*
G03X1172224Y1551494I464J1111D01*
G01X1172444D01*
G02X1172644Y1551294I0J-200D01*
G01Y1549591D01*
G02X1172563Y1549430I-200J0D01*
G03X1171863Y1548630I1490J-2010D01*
G01X1171837Y1548583D01*
X1171747Y1548529D01*
X1171348Y1548520D01*
G02X1171172Y1548616I-5J200D01*
G03X1169035Y1549816I-2137J-1303D01*
G03Y1544812I0J-2502D01*
G03X1170309Y1545161I-1J2502D01*
G02X1170552Y1545130I101J-172D01*
G01X1172018Y1543664D01*
G02X1172073Y1543562I-141J-142D01*
G03X1172144Y1543331I1188J239D01*
G01X1172160Y1543294D01*
Y1543145D01*
G02X1172101Y1543003I-200J0D01*
G01X1171562Y1542464D01*
X1171457Y1542437D01*
X1171404Y1542452D01*
G03X1170986Y1542510I-416J-1462D01*
G03X1169466Y1540991I0J-1520D01*
G01Y1540989D01*
G03X1169468Y1540899I1520J-11D01*
G01X1169471Y1540848D01*
X1169428Y1540756D01*
X1169117Y1540527D01*
G02X1168927Y1540501I-119J161D01*
G03X1168389Y1540600I-540J-1421D01*
G01X1168386D01*
G03X1166866Y1539080I0J-1520D01*
G01Y1539078D01*
G03X1167133Y1538218I1520J1D01*
G02X1167110Y1537963I-164J-114D01*
G01X1166299Y1537152D01*
G03X1166240Y1537010I141J-142D01*
G01Y1491003D01*
G02X1166181Y1490861I-200J0D01*
G01X1164223Y1488903D01*
G02X1164081Y1488844I-142J141D01*
G01X1139143D01*
G02X1139001Y1488903I0J200D01*
G01X1132971Y1494933D01*
G03X1131409Y1495580I-1563J-1564D01*
G01X1119300D01*
G02X1119158Y1495639I0J200D01*
G01X1112391Y1502407D01*
G02X1112332Y1502549I141J142D01*
G01Y1523122D01*
G02X1112391Y1523264I200J0D01*
G01X1113576Y1524450D01*
G02X1113799Y1524491I141J-142D01*
G03X1114617Y1524316I819J1827D01*
G03X1116619Y1526318I0J2002D01*
G03X1116391Y1527246I-2002J0D01*
G02X1116368Y1527338I177J93D01*
G01Y1528807D01*
G03X1115967Y1529921I-1751J-1D01*
G01X1115917Y1529981D01*
X1115925Y1530135D01*
X1116181Y1530391D01*
G03X1116828Y1531953I-1564J1563D01*
G01Y1532075D01*
G02X1116887Y1532217I200J0D01*
G01X1117402Y1532732D01*
X1117510Y1532759D01*
X1117563Y1532742D01*
G03X1117891Y1532667I655J2112D01*
G02X1117955Y1532646I-30J-198D01*
G03X1119131Y1532352I1176J2207D01*
G03X1120324Y1532655I0J2502D01*
G02X1120385Y1532676I95J-176D01*
G03X1121565Y1533290I-384J2178D01*
G01X1128309Y1540034D01*
G03X1128956Y1541596I-1564J1563D01*
G01Y1544203D01*
G02X1129015Y1544345I200J0D01*
G01X1130761Y1546091D01*
G02X1130903Y1546150I142J-141D01*
G01X1139006D01*
G03X1139148Y1546209I0J200D01*
G01X1141788D01*
G02X1141930Y1546150I0J-200D01*
G01X1142087Y1545993D01*
G03X1143649Y1545346I1563J1564D01*
G01X1153829D01*
G02X1153971Y1545287I0J-200D01*
G01X1156246Y1543011D01*
G03X1157808Y1542364I1563J1564D01*
G01X1159422D01*
G03X1161188Y1543244I0J2212D01*
G02X1161347Y1543324I160J-120D01*
G01X1162122D01*
G03X1162624Y1543825I0J502D01*
G01Y1543867D01*
X1162741Y1543984D01*
X1163485D01*
G03Y1548406I0J2211D01*
G01X1162974D01*
G02X1162780Y1548559I0J200D01*
G03X1162626Y1548949I-1469J-355D01*
G02X1162605Y1549093I174J99D01*
G01X1162633Y1549212D01*
G02X1162717Y1549334I195J-44D01*
G03X1163704Y1551175I-1225J1842D01*
G03X1162068Y1553311I-2212J0D01*
G02X1161920Y1553504I52J193D01*
G01Y1554773D01*
G03X1161420Y1555274I-501J0D01*
G01X1160677D01*
G02X1160535Y1555333I0J200D01*
G01X1160282Y1555587D01*
G03X1159576Y1556061I-1563J-1565D01*
G02X1159455Y1556225I78J184D01*
G03X1157498Y1558198I-2200J-225D01*
G02X1157320Y1558397I22J199D01*
G01Y1591556D01*
G03X1157261Y1591698I-200J0D01*
G01X1156363Y1592596D01*
G03X1156221Y1592655I-142J-141D01*
G01X1150747D01*
G02X1150605Y1592714I0J200D01*
G01X1150304Y1593015D01*
G02X1150245Y1593157I141J142D01*
G01Y1596340D01*
G02X1150304Y1596482I200J0D01*
G01X1150312Y1596490D01*
X1150385Y1596520D01*
X1163291D01*
G02X1163433Y1596461I0J-200D01*
G01X1165733Y1594161D01*
G02X1165792Y1594019I-141J-142D01*
G01Y1582629D01*
G03X1165851Y1582487I200J0D01*
G01X1168088Y1580250D01*
G02X1168147Y1580108I-141J-142D01*
G01Y1575762D01*
G02X1167947Y1575562I-200J0D01*
G01X1166873D01*
G03X1166404Y1575467I1J-1212D01*
G01X1166367Y1575452D01*
G37*
G36*
G01X1118836Y1594118D02*
G03I-510J0D01*
G37*
G36*
G01X1118514Y1584908D02*
G03I-510J0D01*
G37*
G36*
G01X1114295Y1601462D02*
G03I-510J0D01*
G37*
G36*
G01X1117773Y1601526D02*
G03I-510J0D01*
G37*
G36*
G01X1114458Y1714244D02*
G03I-510J0D01*
G37*
G36*
G01X1132897Y615658D02*
G03I-510J0D01*
G37*
G36*
G01X1130823Y795315D02*
G03I-656J0D01*
G37*
G36*
G01Y832126D02*
G03I-656J0D01*
G37*
G36*
G01Y868937D02*
G03I-656J0D01*
G37*
G36*
G01Y905749D02*
G03I-656J0D01*
G37*
G36*
G01Y942560D02*
G03I-656J0D01*
G37*
G36*
G01Y1089804D02*
G03I-656J0D01*
G37*
G36*
G01Y1126615D02*
G03I-656J0D01*
G37*
G36*
G01Y1163426D02*
G03I-656J0D01*
G37*
G36*
G01Y1200237D02*
G03I-656J0D01*
G37*
G36*
G01Y1237048D02*
G03I-656J0D01*
G37*
G36*
G01X1132300Y1597984D02*
G03I-510J0D01*
G37*
G36*
G01X1132342Y1607245D02*
G03I-510J0D01*
G37*
G36*
G01X1129740Y1666174D02*
G03I-510J0D01*
G37*
G36*
G01X1126242Y1666072D02*
G03I-510J0D01*
G37*
G36*
G01X1146965Y791969D02*
G03I-656J0D01*
G37*
G36*
G01Y828780D02*
G03I-656J0D01*
G37*
G36*
G01Y865591D02*
G03I-656J0D01*
G37*
G36*
G01Y902402D02*
G03I-656J0D01*
G37*
G36*
G01Y939213D02*
G03I-656J0D01*
G37*
G36*
G01Y1086457D02*
G03I-656J0D01*
G37*
G36*
G01Y1233701D02*
G03I-656J0D01*
G37*
G36*
G01X1192099Y1335882D02*
X1171299D01*
X1163299D01*
X1161399Y1333982D01*
Y1328982D01*
X1160199Y1327782D01*
X1141199D01*
X1140399Y1326982D01*
Y1325682D01*
Y1321582D01*
X1140963Y1321018D01*
X1170635D01*
X1171449Y1321832D01*
Y1327332D01*
X1171999Y1327882D01*
X1172899Y1328782D01*
X1191999D01*
X1192699Y1329482D01*
Y1330382D01*
Y1335282D01*
X1192099Y1335882D01*
G37*
G36*
G01X1143573Y1580334D02*
G03I-510J0D01*
G37*
G36*
G01X1145570Y1588837D02*
G03I-510J0D01*
G37*
G36*
G01X1142155Y1640017D02*
G03I-510J0D01*
G37*
G36*
G01X1146826Y1649422D02*
G03I-510J0D01*
G37*
G36*
G01X1143637Y1649068D02*
G03I-510J0D01*
G37*
G36*
G01X1146987Y1658441D02*
G03I-510J0D01*
G37*
G36*
G01X1166099Y569118D02*
G03I-510J0D01*
G37*
G36*
G01X1160524Y795315D02*
G03I-656J0D01*
G37*
G36*
G01Y832126D02*
G03I-656J0D01*
G37*
G36*
G01Y868937D02*
G03I-656J0D01*
G37*
G36*
G01Y905749D02*
G03I-656J0D01*
G37*
G36*
G01Y942560D02*
G03I-656J0D01*
G37*
G36*
G01Y1089804D02*
G03I-656J0D01*
G37*
G36*
G01Y1126615D02*
G03I-656J0D01*
G37*
G36*
G01Y1163426D02*
G03I-656J0D01*
G37*
G36*
G01Y1200237D02*
G03I-656J0D01*
G37*
G36*
G01Y1237048D02*
G03I-656J0D01*
G37*
G36*
G01X1168905Y1512500D02*
G03I-519J0D01*
G37*
G36*
G01Y1517280D02*
G03I-519J0D01*
G37*
G36*
G01Y1534300D02*
G03I-519J0D01*
G37*
G36*
G01X1161821Y1548204D02*
G03I-510J0D01*
G37*
G36*
G01X1168905Y1539080D02*
G03I-519J0D01*
G37*
G36*
G01X1182199Y1600192D02*
Y1607248D01*
X1185840Y1610889D01*
X1185856D01*
X1186200Y1611233D01*
X1190660D01*
X1191004Y1610889D01*
X1192093Y1609800D01*
X1192450D01*
X1192490Y1609840D01*
X1203260D01*
X1208810Y1604290D01*
X1227330D01*
X1228320Y1605280D01*
Y1615760D01*
X1227762Y1616318D01*
X1201568D01*
X1185231D01*
X1173871Y1604958D01*
X1170561D01*
X1169291Y1603688D01*
Y1600378D01*
Y1597557D01*
Y1595239D01*
X1169899Y1594631D01*
X1179908D01*
X1182199Y1596922D01*
Y1600192D01*
G37*
G36*
G01X1167033Y1589829D02*
X1167598Y1590394D01*
G02X1167740Y1590453I142J-141D01*
G01X1185571D01*
G03X1185713Y1590512I0J200D01*
G01X1190415Y1595214D01*
G03X1190474Y1595356I-141J142D01*
G01Y1606469D01*
G02X1190533Y1606611I200J0D01*
G01X1190818Y1606896D01*
G02X1190960Y1606955I142J-141D01*
G01X1193802D01*
G02X1193944Y1606896I0J-200D01*
G01X1194573Y1606267D01*
G02X1194632Y1606125I-141J-142D01*
G01Y1590397D01*
G02X1194573Y1590255I-200J0D01*
G01X1187205Y1582887D01*
G02X1187063Y1582828I-142J141D01*
G01X1167634D01*
G02X1167492Y1582887I0J200D01*
G01X1167033Y1583346D01*
G02X1166974Y1583488I141J142D01*
G01Y1589687D01*
G02X1167033Y1589829I200J0D01*
G37*
G36*
G01X1162654Y1658042D02*
G03I-510J0D01*
G37*
G36*
G01X1175588Y-24648D02*
G03I-630J0D01*
G37*
G36*
G01Y-15374D02*
G03I-630J0D01*
G37*
G36*
G01Y-5374D02*
G03I-630J0D01*
G37*
G36*
G01Y5352D02*
G03I-630J0D01*
G37*
G36*
G01Y15352D02*
G03I-630J0D01*
G37*
G36*
G01Y24626D02*
G03I-630J0D01*
G37*
G36*
G01X1176666Y791969D02*
G03I-656J0D01*
G37*
G36*
G01Y828780D02*
G03I-656J0D01*
G37*
G36*
G01Y865591D02*
G03I-656J0D01*
G37*
G36*
G01Y902402D02*
G03I-656J0D01*
G37*
G36*
G01Y939213D02*
G03I-656J0D01*
G37*
G36*
G01Y1086457D02*
G03I-656J0D01*
G37*
G36*
G01Y1123268D02*
G03I-656J0D01*
G37*
G36*
G01Y1160079D02*
G03I-656J0D01*
G37*
G36*
G01Y1196890D02*
G03I-656J0D01*
G37*
G36*
G01Y1233701D02*
G03I-656J0D01*
G37*
G36*
G01X1183753Y1488495D02*
G03I-519J0D01*
G37*
G36*
G01X1181843Y1485895D02*
G03I-519J0D01*
G37*
G36*
G01X1183753Y1483295D02*
G03I-519J0D01*
G37*
G36*
G01X1177053Y1498195D02*
G03I-519J0D01*
G37*
G36*
G01X1175143Y1495595D02*
G03I-519J0D01*
G37*
G36*
G01X1177053Y1492995D02*
G03I-519J0D01*
G37*
G36*
G01X1181833D02*
G03I-519J0D01*
G37*
G36*
G01X1183743Y1495595D02*
G03I-519J0D01*
G37*
G36*
G01X1181833Y1498195D02*
G03I-519J0D01*
G37*
G36*
G01X1171505Y1519190D02*
G03I-519J0D01*
G37*
G36*
G01X1174105Y1517280D02*
G03I-519J0D01*
G37*
G36*
G01Y1512500D02*
G03I-519J0D01*
G37*
G36*
G01X1171505Y1510590D02*
G03I-519J0D01*
G37*
G36*
G01X1174105Y1534300D02*
G03I-519J0D01*
G37*
G36*
G01X1171505Y1532490D02*
G03I-519J0D01*
G37*
G36*
G01Y1540990D02*
G03I-519J0D01*
G37*
G36*
G01X1174105Y1539080D02*
G03I-519J0D01*
G37*
G36*
G01X1188462Y1604350D02*
Y1607077D01*
X1189812Y1608427D01*
Y1609645D01*
X1189282Y1610175D01*
X1186873D01*
X1184596Y1607898D01*
Y1607235D01*
Y1604158D01*
Y1602471D01*
Y1602019D01*
X1185006Y1601609D01*
X1187972D01*
X1188462Y1602099D01*
Y1602535D01*
Y1604350D01*
G37*
G36*
G01X1191324Y1664478D02*
Y1660038D01*
G02X1191265Y1659896I-200J0D01*
G01X1190771Y1659402D01*
G02X1190629Y1659343I-142J141D01*
G01X1182678D01*
G02X1182536Y1659402I0J200D01*
G01X1182461Y1659477D01*
G02X1182402Y1659619I141J142D01*
G01Y1664574D01*
G02X1182461Y1664716I200J0D01*
G01X1182537Y1664792D01*
G02X1182679Y1664851I142J-141D01*
G01X1190951D01*
G02X1191093Y1664792I0J-200D01*
G01X1191265Y1664620D01*
G02X1191324Y1664478I-141J-142D01*
G37*
G36*
G01X1178062Y1738118D02*
X1439453D01*
G02X1439638Y1737994I0J-200D01*
G01X1439801Y1737594D01*
X1439777Y1737476D01*
X1439733Y1737433D01*
G03X1438531Y1736185I22078J-22467D01*
G02X1438383Y1736120I-148J135D01*
G01X1353630D01*
G02X1353601Y1736122I-1J200D01*
G01X1353558Y1736129D01*
X1353556D01*
G03X1352958Y1736222I-604J-1917D01*
G01X1352946D01*
G03X1352348Y1736129I6J-2010D01*
G01X1352318Y1736120D01*
X1337882D01*
G02X1337853Y1736122I-1J200D01*
G01X1337810Y1736129D01*
X1337808D01*
G03X1337210Y1736222I-604J-1917D01*
G01X1337198D01*
G03X1336600Y1736129I6J-2010D01*
G01X1336570Y1736120D01*
X1322134D01*
G02X1322105Y1736122I-1J200D01*
G01X1322062Y1736129D01*
X1322060D01*
G03X1321462Y1736222I-604J-1917D01*
G01X1321450D01*
G03X1320852Y1736129I6J-2010D01*
G01X1320822Y1736120D01*
X1307553D01*
X1307501Y1736135D01*
X1307477Y1736149D01*
G03X1307216Y1736222I-261J-428D01*
G01X1304200D01*
G03X1303939Y1736149I0J-501D01*
G01X1303915Y1736135D01*
X1303863Y1736120D01*
X1286701D01*
G02X1286672Y1736122I-1J200D01*
G01X1286629Y1736129D01*
X1286627D01*
G03X1286029Y1736222I-604J-1917D01*
G01X1286017D01*
G03X1285419Y1736129I6J-2010D01*
G01X1285389Y1736120D01*
X1270953D01*
G02X1270924Y1736122I-1J200D01*
G01X1270881Y1736129D01*
X1270879D01*
G03X1270281Y1736222I-604J-1917D01*
G01X1270269D01*
G03X1269671Y1736129I6J-2010D01*
G01X1269641Y1736120D01*
X1255205D01*
G02X1255176Y1736122I-1J200D01*
G01X1255133Y1736129D01*
X1255131D01*
G03X1254533Y1736222I-604J-1917D01*
G01X1254521D01*
G03X1253923Y1736129I6J-2010D01*
G01X1253893Y1736120D01*
X1240624D01*
X1240572Y1736135D01*
X1240548Y1736149D01*
G03X1240288Y1736222I-261J-428D01*
G01X1237270D01*
G03X1237010Y1736149I1J-501D01*
G01X1236986Y1736135D01*
X1236934Y1736120D01*
X1179132D01*
G02X1178984Y1736185I0J200D01*
G03X1177782Y1737433I-23280J-21219D01*
G01X1177738Y1737476D01*
X1177714Y1737594D01*
X1177877Y1737994D01*
G02X1178062Y1738118I185J-76D01*
G37*
G36*
G01X1186521Y187430D02*
X1190821D01*
X1192121Y186130D01*
Y180730D01*
X1191421Y180030D01*
X1186221D01*
X1185821Y180430D01*
Y186730D01*
X1186521Y187430D01*
G37*
G36*
G01X1210207Y168651D02*
X1216407D01*
X1217007Y169251D01*
X1223107D01*
X1223207Y169351D01*
Y170351D01*
X1223107Y170451D01*
X1214907D01*
X1211808Y173550D01*
X1198786D01*
X1197843Y174493D01*
Y174543D01*
X1197571Y174815D01*
Y182710D01*
X1197843Y182982D01*
Y187034D01*
X1198675Y187866D01*
X1203295D01*
X1203700Y188271D01*
Y190096D01*
Y190397D01*
X1203260Y190837D01*
X1194633D01*
X1194107Y190311D01*
Y188517D01*
Y184151D01*
Y172051D01*
Y168482D01*
X1194838Y167751D01*
X1204707D01*
X1209307D01*
X1210207Y168651D01*
G37*
G36*
G01X1190050Y481691D02*
G03I-510J0D01*
G37*
G36*
G01X1192366Y589567D02*
G03I-720J0D01*
G37*
G36*
G01X1190225Y795315D02*
G03I-656J0D01*
G37*
G36*
G01Y832126D02*
G03I-656J0D01*
G37*
G36*
G01Y868937D02*
G03I-656J0D01*
G37*
G36*
G01Y905749D02*
G03I-656J0D01*
G37*
G36*
G01Y942560D02*
G03I-656J0D01*
G37*
G36*
G01Y1089804D02*
G03I-656J0D01*
G37*
G36*
G01Y1126615D02*
G03I-656J0D01*
G37*
G36*
G01Y1163426D02*
G03I-656J0D01*
G37*
G36*
G01Y1200237D02*
G03I-656J0D01*
G37*
G36*
G01Y1237048D02*
G03I-656J0D01*
G37*
G36*
G01X1199722Y1319265D02*
X1224103D01*
G02X1224245Y1319206I0J-200D01*
G01X1224627Y1318824D01*
G02X1224686Y1318682I-141J-142D01*
G01Y1287175D01*
G03X1224745Y1287033I200J0D01*
G01X1232779Y1278999D01*
G02X1232838Y1278857I-141J-142D01*
G01Y1278340D01*
G03X1232897Y1278198I200J0D01*
G01X1238256Y1272839D01*
G03X1238398Y1272780I142J141D01*
G01X1361676D01*
G03X1361818Y1272839I0J200D01*
G01X1362990Y1274011D01*
G03X1363049Y1274153I-141J142D01*
G01Y1279857D01*
G02X1363108Y1279999I200J0D01*
G01X1363980Y1280871D01*
G02X1364122Y1280930I142J-141D01*
G01X1369616D01*
G03X1369758Y1280989I0J200D01*
G01X1373569Y1284800D01*
G03X1373628Y1284942I-141J142D01*
G01Y1291682D01*
G02X1373687Y1291824I200J0D01*
G01X1374068Y1292205D01*
G02X1374209Y1292264I142J-141D01*
G01X1394019D01*
X1394021Y1292265D01*
X1407456D01*
G02X1407598Y1292206I0J-200D01*
G01X1408560Y1291244D01*
G02X1408592Y1291004I-142J-141D01*
G03X1408264Y1289765I2173J-1238D01*
G03X1408583Y1288541I2501J-2D01*
G01X1408616Y1288483D01*
X1408598Y1288350D01*
X1408545Y1288297D01*
G02X1408403Y1288238I-142J141D01*
G01X1401599D01*
G03X1401457Y1288179I0J-200D01*
G01X1400665Y1287387D01*
G03X1400606Y1287245I141J-142D01*
G01Y1258240D01*
G02X1400547Y1258098I-200J0D01*
G01X1379628Y1237179D01*
G02X1379486Y1237120I-142J141D01*
G01X1349602D01*
G03X1349460Y1237061I0J-200D01*
G01X1344390Y1231991D01*
G02X1344248Y1231932I-142J141D01*
G01X1239789D01*
G02X1239647Y1231991I0J200D01*
G01X1213365Y1258273D01*
G03X1213223Y1258332I-142J-141D01*
G01X1201567D01*
G02X1201425Y1258391I0J200D01*
G01X1198234Y1261582D01*
G02X1198175Y1261724I141J142D01*
G01Y1273396D01*
G02X1198234Y1273537I200J-1D01*
G01X1198463Y1273765D01*
X1198536Y1273796D01*
X1198576D01*
X1205490D01*
G03Y1281598I0J3901D01*
G01X1198590D01*
X1198536D01*
X1198463Y1281629D01*
X1198234Y1281857D01*
G02X1198175Y1281998I141J142D01*
G01Y1317718D01*
G02X1198234Y1317860I200J0D01*
G01X1199580Y1319206D01*
G02X1199722Y1319265I142J-141D01*
G37*
G36*
G01X1188533Y1483295D02*
G03I-519J0D01*
G37*
G36*
G01X1190443Y1485895D02*
G03I-519J0D01*
G37*
G36*
G01X1188533Y1488495D02*
G03I-519J0D01*
G37*
G36*
G01X1195243Y1505295D02*
G03I-519J0D01*
G37*
G36*
G01X1197153Y1502695D02*
G03I-519J0D01*
G37*
G36*
G01Y1507895D02*
G03I-519J0D01*
G37*
G36*
G01X1208208Y1560011D02*
X1209834D01*
G02X1209899Y1560000I0J-200D01*
G01X1210813Y1559686D01*
G03X1211219Y1559607I487J1420D01*
G01X1211258Y1559605D01*
X1211327Y1559573D01*
X1211543Y1559345D01*
G02X1211598Y1559207I-145J-138D01*
G01Y1557099D01*
G02X1211543Y1556961I-200J0D01*
G01X1211327Y1556733D01*
X1211258Y1556701D01*
X1211219Y1556699D01*
G03X1210904Y1556648I81J-1499D01*
G01X1209682Y1556313D01*
G02X1209629Y1556306I-52J193D01*
G01X1207942D01*
G02X1207872Y1556319I1J200D01*
G01X1207101Y1556607D01*
G03X1206576Y1556702I-526J-1407D01*
G03X1206179Y1556648I2J-1502D01*
G01X1204958Y1556313D01*
G02X1204905Y1556306I-52J193D01*
G01X1203218D01*
G02X1203148Y1556319I1J200D01*
G01X1202377Y1556607D01*
G03X1201852Y1556702I-526J-1407D01*
G03X1201455Y1556648I2J-1502D01*
G01X1200233Y1556313D01*
G02X1200180Y1556306I-52J193D01*
G01X1198493D01*
G02X1198423Y1556319I1J200D01*
G01X1197652Y1556607D01*
G03X1197127Y1556702I-526J-1407D01*
G03X1196730Y1556648I2J-1502D01*
G01X1195509Y1556313D01*
G02X1195456Y1556306I-52J193D01*
G01X1194053D01*
G02X1193911Y1556365I0J200D01*
G01X1193749Y1556527D01*
G02X1193690Y1556669I141J142D01*
G01Y1559626D01*
G02X1193819Y1559813I200J0D01*
G01X1194303Y1559998D01*
G02X1194375Y1560011I71J-187D01*
G01X1195660D01*
G02X1195725Y1560000I0J-200D01*
G01X1196639Y1559686D01*
G03X1197127Y1559604I489J1420D01*
G03X1197549Y1559665I-2J1502D01*
G01X1198703Y1560003D01*
G02X1198759Y1560011I56J-192D01*
G01X1200385D01*
G02X1200450Y1560000I0J-200D01*
G01X1201364Y1559686D01*
G03X1201852Y1559604I489J1420D01*
G03X1202274Y1559665I-2J1502D01*
G01X1203428Y1560003D01*
G02X1203484Y1560011I56J-192D01*
G01X1205109D01*
G02X1205174Y1560000I0J-200D01*
G01X1206088Y1559686D01*
G03X1206576Y1559604I489J1420D01*
G03X1206998Y1559665I-2J1502D01*
G01X1208152Y1560003D01*
G02X1208208Y1560011I56J-192D01*
G37*
G36*
G01X1220930Y1588957D02*
Y1586703D01*
G02X1220871Y1586561I-200J0D01*
G01X1220309Y1585999D01*
G02X1220167Y1585940I-142J141D01*
G01X1197323D01*
G02X1197181Y1585999I0J200D01*
G01X1196129Y1587051D01*
G02X1196070Y1587193I141J142D01*
G01Y1608111D01*
G02X1196129Y1608253I200J0D01*
G01X1196276Y1608400D01*
G02X1196418Y1608459I142J-141D01*
G01X1201428D01*
G02X1201570Y1608400I0J-200D01*
G01X1220871Y1589099D01*
G02X1220930Y1588957I-141J-142D01*
G37*
G36*
G01X1203221Y87651D02*
G03I-510J0D01*
G37*
G36*
G01X1215366Y421018D02*
G03I-510J0D01*
G37*
G36*
G01X1209120Y591631D02*
G03I-720J0D01*
G37*
G36*
G01X1202160Y668138D02*
G03I-720J0D01*
G37*
G36*
G01X1207897Y668115D02*
G03I-720J0D01*
G37*
G36*
G01X1206367Y791969D02*
G03I-656J0D01*
G37*
G36*
G01Y828780D02*
G03I-656J0D01*
G37*
G36*
G01Y865591D02*
G03I-656J0D01*
G37*
G36*
G01Y902402D02*
G03I-656J0D01*
G37*
G36*
G01Y939213D02*
G03I-656J0D01*
G37*
G36*
G01Y1086457D02*
G03I-656J0D01*
G37*
G36*
G01Y1123268D02*
G03I-656J0D01*
G37*
G36*
G01Y1160079D02*
G03I-656J0D01*
G37*
G36*
G01Y1196890D02*
G03I-656J0D01*
G37*
G36*
G01Y1233701D02*
G03I-656J0D01*
G37*
G36*
G01X1207009Y1335765D02*
X1230529D01*
X1233056D01*
X1233060Y1335762D01*
X1233732D01*
X1235420Y1334074D01*
Y1312163D01*
X1233866Y1310609D01*
Y1305136D01*
X1235495Y1303507D01*
Y1294566D01*
X1235720D01*
X1242018Y1288268D01*
Y1287970D01*
Y1283921D01*
X1243030Y1282909D01*
X1244250Y1281689D01*
X1262840D01*
X1263540Y1280989D01*
Y1275129D01*
X1263281Y1274870D01*
X1244333D01*
X1239898D01*
X1233713Y1281055D01*
X1231255Y1283513D01*
Y1283557D01*
X1226703Y1288109D01*
Y1327861D01*
X1225799Y1328765D01*
X1206799D01*
X1206009Y1329555D01*
Y1334765D01*
X1207009Y1335765D01*
G37*
G36*
G01X1229700Y1428795D02*
X1212300D01*
X1212202Y1428698D01*
Y1412036D01*
Y1411398D01*
X1212400Y1411200D01*
X1229700D01*
X1229800Y1411300D01*
Y1412100D01*
Y1428695D01*
X1229700Y1428795D01*
G37*
G36*
G01X1210553Y1488495D02*
G03I-519J0D01*
G37*
G36*
G01X1208643Y1485895D02*
G03I-519J0D01*
G37*
G36*
G01X1210553Y1483295D02*
G03I-519J0D01*
G37*
G36*
G01X1215333D02*
G03I-519J0D01*
G37*
G36*
G01Y1488495D02*
G03I-519J0D01*
G37*
G36*
G01X1201933Y1502695D02*
G03I-519J0D01*
G37*
G36*
G01X1203843Y1505295D02*
G03I-519J0D01*
G37*
G36*
G01X1208633Y1498195D02*
G03I-519J0D01*
G37*
G36*
G01X1203853D02*
G03I-519J0D01*
G37*
G36*
G01X1201943Y1495595D02*
G03I-519J0D01*
G37*
G36*
G01X1203853Y1492995D02*
G03I-519J0D01*
G37*
G36*
G01X1208633D02*
G03I-519J0D01*
G37*
G36*
G01X1210543Y1495595D02*
G03I-519J0D01*
G37*
G36*
G01X1201933Y1507895D02*
G03I-519J0D01*
G37*
G36*
G01X1213008Y1560011D02*
X1214558D01*
G02X1214623Y1560000I0J-200D01*
G01X1215537Y1559686D01*
G03X1215988Y1559605I488J1420D01*
G01X1216027Y1559604D01*
X1216098Y1559573D01*
X1216321Y1559345D01*
G02X1216378Y1559205I-143J-140D01*
G01Y1557101D01*
G02X1216321Y1556961I-200J0D01*
G01X1216098Y1556733D01*
X1216027Y1556702D01*
X1215988Y1556701D01*
G03X1215628Y1556648I37J-1501D01*
G01X1214406Y1556313D01*
G02X1214353Y1556306I-52J193D01*
G01X1212964D01*
G02X1212822Y1556365I0J200D01*
G01X1212658Y1556529D01*
G02X1212599Y1556671I141J142D01*
G01Y1559602D01*
G02X1212658Y1559744I200J0D01*
G01X1212866Y1559952D01*
G02X1213008Y1560011I142J-141D01*
G37*
G36*
G01X1210389Y1700359D02*
G03I-510J0D01*
G37*
G36*
G01X1214831Y148530D02*
X1219731D01*
X1220531Y147730D01*
Y140530D01*
X1220031Y140030D01*
X1215631D01*
X1214431Y141230D01*
Y148130D01*
X1214831Y148530D01*
G37*
G36*
G01X1226604Y297066D02*
G03I-510J0D01*
G37*
G36*
G01Y305216D02*
G03I-510J0D01*
G37*
G36*
G01X1266445Y1402177D02*
X1272720D01*
X1272838Y1402059D01*
X1381499D01*
X1381663Y1401895D01*
X1388858D01*
X1405690Y1385063D01*
Y1345337D01*
G03X1404431Y1339823I11445J-5514D01*
G03Y1339736I12703J-43D01*
G01X1404312Y1339617D01*
G02X1404170Y1339558I-142J141D01*
G01X1386310D01*
G02X1386168Y1339617I0J200D01*
G01X1386075Y1339710D01*
G02X1386016Y1339852I141J142D01*
G01Y1347315D01*
G02X1386075Y1347457I200J0D01*
G01X1386097Y1347479D01*
X1391462D01*
G03X1391604Y1347538I0J200D01*
G01X1392129Y1348063D01*
G03X1392188Y1348205I-141J142D01*
G01Y1352701D01*
G02X1392247Y1352843I200J0D01*
G01X1393475Y1354071D01*
G03X1393534Y1354213I-141J142D01*
G01Y1359995D01*
G03X1393475Y1360137I-200J0D01*
G01X1391693Y1361919D01*
G03X1391551Y1361978I-142J-141D01*
G01X1370379D01*
G03X1370237Y1361919I0J-200D01*
G01X1368843Y1360525D01*
G03X1367419Y1359024I79J-1501D01*
G03X1367671Y1358191I1503J0D01*
G01Y1357252D01*
X1367788Y1357135D01*
Y1334715D01*
G02X1367729Y1334573I-200J0D01*
G01X1365530Y1332374D01*
G03X1365471Y1332232I141J-142D01*
G01Y1324904D01*
X1367390Y1322985D01*
Y1320476D01*
G02X1367332Y1320336I-200J1D01*
G01X1367176Y1320177D01*
G02X1367034Y1320118I-142J141D01*
G01X1353729D01*
G02X1353587Y1320177I0J200D01*
G01X1353493Y1320271D01*
G02X1353434Y1320413I141J142D01*
G01Y1327718D01*
G02X1353615Y1327891I196J-23D01*
G01X1358472D01*
G03X1358614Y1327950I0J200D01*
G01X1359531Y1328867D01*
G03X1359590Y1329009I-141J142D01*
G01Y1331892D01*
G02X1359649Y1332034I200J0D01*
G01X1361131Y1333516D01*
G03X1361190Y1333658I-141J142D01*
G01Y1340339D01*
X1359249Y1342280D01*
X1338299D01*
X1334738Y1338719D01*
Y1320238D01*
G02X1334679Y1320096I-200J0D01*
G01X1334413Y1319830D01*
G02X1334271Y1319771I-142J141D01*
G01X1320945D01*
G02X1320803Y1319830I0J200D01*
G01X1320693Y1319940D01*
G02X1320634Y1320082I141J142D01*
G01Y1327518D01*
G02X1320815Y1327691I196J-23D01*
G01X1325833D01*
G03X1325975Y1327750I0J200D01*
G01X1326731Y1328506D01*
G03X1326790Y1328648I-141J142D01*
G01Y1331692D01*
G02X1326849Y1331834I200J0D01*
G01X1328094Y1333079D01*
G03X1328152Y1333218I-139J140D01*
G01Y1339577D01*
G03X1328093Y1339719I-200J0D01*
G01X1325732Y1342080D01*
X1305279D01*
X1301838Y1338639D01*
Y1320383D01*
G02X1301779Y1320241I-200J0D01*
G01X1301565Y1320027D01*
G02X1301423Y1319968I-142J141D01*
G01X1287973D01*
G02X1287831Y1320027I0J200D01*
G01X1287789Y1320069D01*
G02X1287730Y1320211I141J142D01*
G01Y1327576D01*
G02X1287901Y1327747I195J-24D01*
G01X1292899D01*
G03X1293041Y1327806I0J200D01*
G01X1293827Y1328592D01*
G03X1293886Y1328734I-141J142D01*
G01Y1331749D01*
G02X1293945Y1331891I200J0D01*
G01X1295190Y1333136D01*
G03X1295248Y1333275I-139J140D01*
G01Y1339364D01*
X1295238Y1339374D01*
Y1339925D01*
G03X1295179Y1340067I-200J0D01*
G01X1292957Y1342289D01*
G03X1292815Y1342348I-142J-141D01*
G01X1272647D01*
X1269310Y1339011D01*
Y1320735D01*
G02X1269251Y1320593I-200J0D01*
G01X1268805Y1320147D01*
G02X1268663Y1320088I-142J141D01*
G01X1255257D01*
G02X1255115Y1320147I0J200D01*
G01X1254893Y1320369D01*
G02X1254834Y1320511I141J142D01*
G01Y1327604D01*
G02X1255005Y1327775I196J-25D01*
G01X1260488D01*
G03X1260630Y1327834I0J200D01*
G01X1260931Y1328135D01*
G03X1260990Y1328277I-141J142D01*
G01Y1332039D01*
G02X1261049Y1332181I200J0D01*
G01X1262477Y1333609D01*
G03X1262536Y1333751I-141J142D01*
G01Y1348805D01*
G02X1262595Y1348947I200J0D01*
G01X1265657Y1352009D01*
G03X1265716Y1352151I-141J142D01*
G01Y1363195D01*
G03X1265657Y1363337I-200J0D01*
G01X1258235Y1370759D01*
G03X1258093Y1370818I-142J-141D01*
G01X1243818D01*
X1239115Y1366115D01*
X1217182D01*
G02X1217040Y1366174I0J200D01*
G01X1216902Y1366312D01*
G02X1216843Y1366454I141J142D01*
G01Y1373642D01*
G02X1216902Y1373784I200J0D01*
G01X1217054Y1373936D01*
G02X1217196Y1373995I142J-141D01*
G01X1222156D01*
G03X1222298Y1374054I0J200D01*
G01X1222940Y1374696D01*
G03X1222999Y1374838I-141J142D01*
G01Y1379892D01*
G02X1223058Y1380034I200J0D01*
G01X1226112Y1383088D01*
X1244500D01*
X1247356D01*
X1266445Y1402177D01*
G37*
G36*
G01X1217243Y1485895D02*
G03I-519J0D01*
G37*
G36*
G01X1222043Y1505295D02*
G03I-519J0D01*
G37*
G36*
G01X1223953Y1502695D02*
G03I-519J0D01*
G37*
G36*
G01X1228733D02*
G03I-519J0D01*
G37*
G36*
G01X1228743Y1495595D02*
G03I-519J0D01*
G37*
G36*
G01X1223953Y1507895D02*
G03I-519J0D01*
G37*
G36*
G01X1228733D02*
G03I-519J0D01*
G37*
G36*
G01X1218060Y1560011D02*
X1219282D01*
G02X1219347Y1560000I0J-200D01*
G01X1220261Y1559686D01*
G03X1220703Y1559605I489J1420D01*
G01X1220742Y1559604D01*
X1220813Y1559573D01*
X1221034Y1559345D01*
G02X1221090Y1559205I-144J-139D01*
G01Y1557101D01*
G02X1221034Y1556961I-200J-1D01*
G01X1220813Y1556733D01*
X1220742Y1556702D01*
X1220703Y1556701D01*
G03X1220352Y1556648I47J-1501D01*
G01X1219131Y1556313D01*
G02X1219078Y1556306I-52J193D01*
G01X1217766D01*
G02X1217624Y1556365I0J200D01*
G01X1217438Y1556551D01*
G02X1217379Y1556693I141J142D01*
G01Y1559330D01*
G02X1217438Y1559472I200J0D01*
G01X1217918Y1559952D01*
G02X1218060Y1560011I142J-141D01*
G37*
G36*
G01X1231827Y1560010D02*
X1232779D01*
G02X1232921Y1559951I0J-200D01*
G01X1233179Y1559693D01*
G02X1233238Y1559552I-141J-142D01*
G01Y1558527D01*
G03X1233296Y1558386I200J0D01*
G01X1233302Y1558380D01*
X1233332Y1558307D01*
Y1558276D01*
X1233669Y1557939D01*
X1233742Y1557909D01*
X1233773D01*
X1234065Y1557617D01*
G03X1234206Y1557558I142J141D01*
G01X1235330D01*
G02X1235530Y1557358I0J-200D01*
G01Y1557090D01*
G02X1235463Y1556941I-200J0D01*
G01X1235209Y1556714D01*
X1235129Y1556688D01*
X1235086Y1556693D01*
G03X1234923Y1556702I-164J-1493D01*
G03X1234526Y1556648I2J-1502D01*
G01X1233304Y1556313D01*
G02X1233251Y1556306I-52J193D01*
G01X1231564D01*
G02X1231494Y1556319I1J200D01*
G01X1230723Y1556607D01*
G03X1230198Y1556702I-526J-1407D01*
G03X1229801Y1556648I2J-1502D01*
G01X1228580Y1556313D01*
G02X1228527Y1556306I-52J193D01*
G01X1226840D01*
G02X1226770Y1556319I1J200D01*
G01X1225999Y1556607D01*
G03X1225474Y1556702I-526J-1407D01*
G03X1225077Y1556648I2J-1502D01*
G01X1223855Y1556313D01*
G02X1223802Y1556306I-52J193D01*
G01X1222408D01*
G02X1222266Y1556365I0J200D01*
G01X1222151Y1556480D01*
G02X1222092Y1556622I141J142D01*
G01Y1559271D01*
G02X1222151Y1559413I200J0D01*
G01X1222689Y1559951D01*
G02X1222831Y1560010I142J-141D01*
G01X1224010D01*
G02X1224075Y1559999I0J-200D01*
G01X1224986Y1559686D01*
G03X1225474Y1559604I489J1420D01*
G03X1225896Y1559665I-2J1502D01*
G01X1227047Y1560002D01*
G02X1227103Y1560010I56J-192D01*
G01X1228734D01*
G02X1228799Y1559999I0J-200D01*
G01X1229710Y1559686D01*
G03X1230198Y1559604I489J1420D01*
G03X1230620Y1559665I-2J1502D01*
G01X1231771Y1560002D01*
G02X1231827Y1560010I56J-192D01*
G37*
G36*
G01X1220248Y1717011D02*
G03I-510J0D01*
G37*
G36*
G01Y1731011D02*
G03I-510J0D01*
G37*
G36*
G01X1236056Y75293D02*
G03I-510J0D01*
G37*
G36*
G01X1230604Y314216D02*
G03I-510J0D01*
G37*
G36*
G01X1264835Y1019213D02*
G02I-13780J0D01*
G37*
G36*
G01X1363490Y1290569D02*
X1244647D01*
X1241968D01*
X1237586Y1294951D01*
Y1297630D01*
X1237560Y1297655D01*
Y1302822D01*
X1238284Y1303546D01*
X1242640D01*
X1243658Y1302528D01*
Y1293825D01*
X1244461Y1293022D01*
X1263141D01*
X1263849Y1293730D01*
Y1309391D01*
X1263061Y1310179D01*
X1242722D01*
X1240361Y1312540D01*
X1237560D01*
Y1317381D01*
X1237860Y1317681D01*
X1241710D01*
X1243613Y1315778D01*
X1249736D01*
Y1318557D01*
X1248423Y1319870D01*
X1246428D01*
X1246202Y1320096D01*
Y1320110D01*
X1246012Y1320300D01*
X1243062D01*
X1242862Y1320500D01*
Y1321100D01*
X1242962Y1321200D01*
X1245072D01*
X1245082Y1321190D01*
X1246216D01*
X1246446Y1321420D01*
Y1321890D01*
X1246454Y1321910D01*
Y1325228D01*
X1246446Y1325249D01*
Y1325410D01*
X1246322Y1325534D01*
Y1325540D01*
X1246243Y1325619D01*
X1242953D01*
X1242902Y1325670D01*
Y1326390D01*
X1243021Y1326509D01*
X1246295D01*
X1246446Y1326660D01*
Y1326890D01*
X1246454Y1326910D01*
Y1327644D01*
X1246513Y1327786D01*
X1246595Y1327868D01*
X1246707Y1327914D01*
X1246753Y1327901D01*
G03X1247011Y1327838I722J2395D01*
G03X1247466Y1327794I467J2458D01*
G01X1247491D01*
G03X1248250Y1327917I-16J2502D01*
G01X1248280Y1327927D01*
X1253239D01*
X1253429Y1327737D01*
Y1319870D01*
X1254679Y1318620D01*
X1263439D01*
X1263605Y1318786D01*
X1269033D01*
X1269471Y1318348D01*
X1273881D01*
X1276471Y1315758D01*
X1282636D01*
Y1318513D01*
X1281309Y1319840D01*
X1279326D01*
X1279098Y1320068D01*
Y1320082D01*
X1278908Y1320272D01*
X1275958D01*
X1275758Y1320472D01*
Y1321072D01*
X1275856Y1321170D01*
X1277970D01*
X1277978Y1321162D01*
X1279112D01*
X1279342Y1321392D01*
Y1321862D01*
X1279350Y1321882D01*
Y1325200D01*
X1279342Y1325221D01*
Y1325382D01*
X1279218Y1325506D01*
Y1325512D01*
X1279129Y1325601D01*
X1275839D01*
X1275798Y1325642D01*
Y1326362D01*
X1275916Y1326480D01*
X1279190D01*
X1279342Y1326632D01*
Y1326862D01*
X1279350Y1326882D01*
Y1327616D01*
X1279409Y1327758D01*
X1279491Y1327840D01*
X1279603Y1327886D01*
X1279649Y1327873D01*
G03X1279907Y1327810I722J2395D01*
G03X1280362Y1327766I467J2458D01*
G01X1280387D01*
G03X1281146Y1327889I-16J2502D01*
G01X1281176Y1327899D01*
X1286090D01*
X1286359Y1327630D01*
Y1319640D01*
X1287511Y1318488D01*
X1287808D01*
X1302171D01*
X1302351Y1318308D01*
X1306791D01*
X1309406Y1315693D01*
X1315531D01*
Y1318187D01*
Y1318448D01*
X1314162Y1319817D01*
X1312196D01*
X1312002Y1320011D01*
Y1320025D01*
X1311812Y1320215D01*
X1308862D01*
X1308662Y1320415D01*
Y1321015D01*
X1308762Y1321115D01*
X1310872D01*
X1310882Y1321105D01*
X1312016D01*
X1312246Y1321335D01*
Y1321805D01*
X1312254Y1321825D01*
Y1325143D01*
X1312246Y1325164D01*
Y1325325D01*
X1312122Y1325449D01*
Y1325455D01*
X1312036Y1325541D01*
X1308746D01*
X1308702Y1325585D01*
Y1326305D01*
X1308801Y1326404D01*
X1312075D01*
X1312246Y1326575D01*
Y1326805D01*
X1312254Y1326825D01*
Y1327559D01*
X1312313Y1327701D01*
X1312395Y1327783D01*
X1312507Y1327829D01*
X1312553Y1327816D01*
G03X1312811Y1327753I722J2395D01*
G03X1313266Y1327709I467J2458D01*
G01X1313291D01*
G03X1314050Y1327832I-16J2502D01*
G01X1314080Y1327842D01*
X1319017D01*
X1319229Y1327630D01*
Y1319730D01*
X1320471Y1318488D01*
X1320556D01*
X1334871D01*
X1334891Y1318468D01*
X1339456D01*
X1342036Y1315888D01*
X1348331D01*
Y1318595D01*
Y1318678D01*
X1347007Y1320002D01*
X1346895D01*
X1345011D01*
X1344802Y1320211D01*
Y1320225D01*
X1344612Y1320415D01*
X1341662D01*
X1341462Y1320615D01*
Y1321215D01*
X1341560Y1321313D01*
X1343674D01*
X1343682Y1321305D01*
X1344816D01*
X1345046Y1321535D01*
Y1322005D01*
X1345054Y1322025D01*
Y1325343D01*
X1345046Y1325364D01*
Y1325525D01*
X1344922Y1325649D01*
Y1325655D01*
X1344832Y1325745D01*
X1341542D01*
X1341502Y1325785D01*
Y1326505D01*
X1341608Y1326611D01*
X1344882D01*
X1345046Y1326775D01*
Y1327005D01*
X1345054Y1327025D01*
Y1327759D01*
X1345113Y1327901D01*
X1345195Y1327983D01*
X1345307Y1328029D01*
X1345353Y1328016D01*
G03X1345611Y1327953I722J2395D01*
G03X1346066Y1327909I467J2458D01*
G01X1346091D01*
G03X1346850Y1328032I-16J2502D01*
G01X1346880Y1328042D01*
X1351889D01*
X1352079Y1327852D01*
Y1319930D01*
X1353231Y1318778D01*
X1353426D01*
X1373156D01*
X1373716Y1318218D01*
Y1313168D01*
X1374836Y1312048D01*
X1394616D01*
X1395156Y1312588D01*
Y1328677D01*
X1394265Y1329568D01*
X1373936D01*
X1371516Y1331988D01*
X1369076D01*
X1368856Y1332208D01*
Y1337708D01*
X1369036Y1337888D01*
X1371216D01*
X1373886Y1335218D01*
X1380966D01*
Y1337998D01*
X1379516Y1339448D01*
X1376653D01*
X1376356Y1339745D01*
X1373475D01*
X1373266Y1339954D01*
Y1340446D01*
X1373465Y1340645D01*
X1376573D01*
X1377104D01*
X1377499Y1341040D01*
Y1344930D01*
X1377362Y1345067D01*
X1376627D01*
X1373697D01*
X1373586Y1345178D01*
Y1345838D01*
X1373693Y1345945D01*
X1376733D01*
X1377394D01*
X1377509Y1346060D01*
Y1347258D01*
X1377619Y1347368D01*
X1384406D01*
X1384566Y1347208D01*
Y1339598D01*
Y1339483D01*
X1385991Y1338058D01*
X1386106D01*
X1404716D01*
X1407096Y1340438D01*
Y1351268D01*
X1408386Y1352558D01*
X1427836D01*
X1432896Y1347498D01*
Y1335438D01*
Y1312307D01*
X1430697Y1310108D01*
X1422146D01*
X1374090D01*
X1373098Y1309116D01*
Y1302560D01*
X1372376Y1301838D01*
X1369359D01*
X1366609Y1299088D01*
Y1293688D01*
X1363490Y1290569D01*
G37*
G36*
G01X1262558Y1308629D02*
X1262849Y1308338D01*
Y1294253D01*
X1262618Y1294022D01*
X1245010D01*
X1244780Y1294252D01*
Y1303159D01*
X1242338Y1305601D01*
X1242222Y1305717D01*
X1239878D01*
X1239313Y1306282D01*
Y1307785D01*
X1240157Y1308629D01*
X1262558D01*
G37*
G36*
G01X1238202Y1305633D02*
X1236916D01*
X1236292Y1306257D01*
Y1310070D01*
X1236909Y1310687D01*
X1237762Y1311540D01*
X1239809D01*
X1239980Y1311369D01*
Y1309928D01*
X1238306Y1308254D01*
Y1307861D01*
Y1305737D01*
X1238202Y1305633D01*
G37*
G36*
G01X1237353Y1488495D02*
G03I-519J0D01*
G37*
G36*
G01X1235443Y1485895D02*
G03I-519J0D01*
G37*
G36*
G01X1237353Y1483295D02*
G03I-519J0D01*
G37*
G36*
G01X1242133D02*
G03I-519J0D01*
G37*
G36*
G01X1244043Y1485895D02*
G03I-519J0D01*
G37*
G36*
G01X1242133Y1488495D02*
G03I-519J0D01*
G37*
G36*
G01X1230643Y1505295D02*
G03I-519J0D01*
G37*
G36*
G01X1230653Y1498195D02*
G03I-519J0D01*
G37*
G36*
G01Y1492995D02*
G03I-519J0D01*
G37*
G36*
G01X1235433D02*
G03I-519J0D01*
G37*
G36*
G01X1237343Y1495595D02*
G03I-519J0D01*
G37*
G36*
G01X1235433Y1498195D02*
G03I-519J0D01*
G37*
G36*
G01X1241279Y1560011D02*
X1242228D01*
G02X1242370Y1559952I0J-200D01*
G01X1242683Y1559639D01*
G02X1242742Y1559498I-141J-142D01*
G01Y1556809D01*
G02X1242683Y1556668I-200J1D01*
G01X1242380Y1556365D01*
G02X1242238Y1556306I-142J141D01*
G01X1241013D01*
G02X1240943Y1556319I1J200D01*
G01X1240172Y1556607D01*
G03X1239647Y1556702I-526J-1407D01*
G03X1239386Y1556679I0J-1492D01*
G01X1239338Y1556670D01*
X1239245Y1556699D01*
X1239167Y1556777D01*
G02X1239108Y1556918I141J142D01*
G01Y1559382D01*
G02X1239167Y1559523I200J-1D01*
G01X1239250Y1559606D01*
X1239341Y1559635D01*
X1239391Y1559627D01*
G03X1239647Y1559604I262J1478D01*
G03X1240069Y1559665I-2J1502D01*
G01X1241223Y1560003D01*
G02X1241279Y1560011I56J-192D01*
G37*
G36*
G01X1246003D02*
X1247254D01*
G02X1247454Y1559811I0J-200D01*
G01Y1556382D01*
X1247424Y1556309D01*
X1247421Y1556306D01*
X1245737D01*
G02X1245667Y1556319I1J200D01*
G01X1244896Y1556607D01*
G03X1244371Y1556702I-526J-1407D01*
G03X1244094Y1556676I1J-1502D01*
G01X1244045Y1556666D01*
X1243950Y1556696D01*
X1243802Y1556844D01*
G02X1243743Y1556986I141J142D01*
G01Y1559218D01*
G02X1243810Y1559368I200J1D01*
G01X1244066Y1559595D01*
X1244148Y1559620D01*
X1244191Y1559615D01*
G03X1244371Y1559604I181J1491D01*
G03X1244793Y1559665I-2J1502D01*
G01X1245947Y1560003D01*
G02X1246003Y1560011I56J-192D01*
G37*
G36*
G01X1236084Y1559873D02*
X1237881D01*
G02X1238023Y1559814I0J-200D01*
G01X1238048Y1559789D01*
G02X1238107Y1559647I-141J-142D01*
G01Y1556865D01*
G02X1238048Y1556723I-200J0D01*
G01X1237772Y1556447D01*
G02X1237630Y1556388I-142J141D01*
G01X1236900D01*
G02X1236758Y1556447I0J200D01*
G01X1236590Y1556615D01*
G02X1236531Y1556757I141J142D01*
G01Y1558154D01*
G03X1236472Y1558296I-200J0D01*
G01X1236267Y1558501D01*
G03X1236125Y1558560I-142J-141D01*
G01X1234621D01*
G02X1234479Y1558619I0J200D01*
G01X1234298Y1558800D01*
G02X1234239Y1558942I141J142D01*
G01Y1559384D01*
G02X1234298Y1559526I200J0D01*
G01X1234406Y1559634D01*
X1234507Y1559662D01*
X1234559Y1559649D01*
G03X1234923Y1559604I365J1457D01*
G03X1235345Y1559665I-2J1502D01*
G01X1236027Y1559865D01*
G02X1236084Y1559873I56J-192D01*
G37*
G36*
G01X1275640Y1620647D02*
Y1604493D01*
G02X1275581Y1604351I-200J0D01*
G01X1274839Y1603609D01*
G02X1274697Y1603550I-142J141D01*
G01X1243743D01*
G02X1243601Y1603609I0J200D01*
G01X1241709Y1605501D01*
G02X1241650Y1605643I141J142D01*
G01Y1620177D01*
G02X1241709Y1620319I200J0D01*
G01X1242451Y1621061D01*
G02X1242593Y1621120I142J-141D01*
G01X1275167D01*
G02X1275309Y1621061I0J-200D01*
G01X1275581Y1620789D01*
G02X1275640Y1620647I-141J-142D01*
G37*
G36*
G01X1248916Y-34648D02*
G03I-630J0D01*
G37*
G36*
G01Y-15374D02*
G03I-630J0D01*
G37*
G36*
G01Y-25374D02*
G03I-630J0D01*
G37*
G36*
G01Y-4648D02*
G03I-630J0D01*
G37*
G36*
G01Y5352D02*
G03I-630J0D01*
G37*
G36*
G01Y14626D02*
G03I-630J0D01*
G37*
G36*
G01X1253071Y72675D02*
G03I-510J0D01*
G37*
G36*
G01X1247000Y483302D02*
G03I-510J0D01*
G37*
G36*
G01X1247258Y785752D02*
G03I-510J0D01*
G37*
G36*
G01X1266484Y1274785D02*
X1265550Y1275719D01*
Y1281219D01*
X1264100Y1282669D01*
X1263430Y1283339D01*
X1245075D01*
X1244300Y1284114D01*
Y1289169D01*
X1244650Y1289519D01*
X1273950D01*
X1275600Y1287869D01*
Y1282869D01*
X1276800Y1281669D01*
X1295800D01*
X1296600Y1280869D01*
Y1275469D01*
X1295916Y1274785D01*
X1266484D01*
G37*
G36*
G01X1261833Y1429610D02*
X1269047D01*
G02X1269189Y1429551I0J-200D01*
G01X1270371Y1428369D01*
G02X1270430Y1428227I-141J-142D01*
G01Y1422883D01*
G02X1270371Y1422741I-200J0D01*
G01X1263659Y1416029D01*
G02X1263517Y1415970I-142J141D01*
G01X1256893D01*
G02X1256751Y1416029I0J200D01*
G01X1256352Y1416428D01*
X1256325Y1416534D01*
X1256342Y1416588D01*
G03X1256407Y1417026I-1437J437D01*
G03X1256186Y1417810I-1501J0D01*
G01X1256171Y1417835D01*
X1256156Y1417886D01*
Y1418082D01*
G03X1256099Y1418456I-1251J1D01*
G01X1256090Y1418486D01*
Y1420374D01*
G02X1256290Y1420574I200J0D01*
G01X1256859D01*
G03X1258222Y1420978I0J2501D01*
G01X1258247Y1420994D01*
X1258302Y1421010D01*
X1258907D01*
G03X1259049Y1421069I0J200D01*
G01X1260061Y1422081D01*
G03X1260120Y1422223I-141J142D01*
G01Y1427897D01*
G02X1260179Y1428039I200J0D01*
G01X1261691Y1429551D01*
G02X1261833Y1429610I142J-141D01*
G37*
G36*
G01X1248843Y1505295D02*
G03I-519J0D01*
G37*
G36*
G01X1250753Y1502695D02*
G03I-519J0D01*
G37*
G36*
G01X1255533D02*
G03I-519J0D01*
G37*
G36*
G01X1257443Y1505295D02*
G03I-519J0D01*
G37*
G36*
G01X1257453Y1498195D02*
G03I-519J0D01*
G37*
G36*
G01X1255543Y1495595D02*
G03I-519J0D01*
G37*
G36*
G01X1257453Y1492995D02*
G03I-519J0D01*
G37*
G36*
G01X1250753Y1507895D02*
G03I-519J0D01*
G37*
G36*
G01X1255533D02*
G03I-519J0D01*
G37*
G36*
G01X1264901Y1560011D02*
X1265877D01*
G02X1265983Y1559981I1J-200D01*
G01X1266255Y1559810D01*
G02X1266291Y1559782I-104J-171D01*
G01X1266356Y1559717D01*
G02X1266415Y1559575I-141J-142D01*
G01Y1556591D01*
G02X1266356Y1556449I-200J0D01*
G01X1266272Y1556365D01*
G02X1266130Y1556306I-142J141D01*
G01X1264635D01*
G02X1264565Y1556319I1J200D01*
G01X1263794Y1556607D01*
G03X1263269Y1556702I-526J-1407D01*
G03X1262872Y1556648I2J-1502D01*
G01X1261651Y1556313D01*
G02X1261598Y1556306I-52J193D01*
G01X1259911D01*
G02X1259841Y1556319I1J200D01*
G01X1259070Y1556607D01*
G03X1258545Y1556702I-526J-1407D01*
G03X1258148Y1556648I2J-1502D01*
G01X1256926Y1556313D01*
G02X1256873Y1556306I-52J193D01*
G01X1255186D01*
G02X1255116Y1556319I1J200D01*
G01X1254345Y1556607D01*
G03X1253820Y1556702I-526J-1407D01*
G03X1253423Y1556648I2J-1502D01*
G01X1252202Y1556313D01*
G02X1252149Y1556306I-52J193D01*
G01X1250462D01*
G02X1250392Y1556319I1J200D01*
G01X1249621Y1556607D01*
G03X1249096Y1556702I-526J-1407D01*
G03X1248906Y1556689I7J-1502D01*
G01X1248863Y1556684D01*
X1248782Y1556709D01*
X1248524Y1556936D01*
G02X1248456Y1557086I132J150D01*
G01Y1559220D01*
G02X1248524Y1559370I200J0D01*
G01X1248782Y1559597D01*
X1248863Y1559622D01*
X1248906Y1559617D01*
G03X1249096Y1559604I197J1489D01*
G03X1249518Y1559665I-2J1502D01*
G01X1250672Y1560003D01*
G02X1250728Y1560011I56J-192D01*
G01X1252353D01*
G02X1252418Y1560000I0J-200D01*
G01X1253332Y1559686D01*
G03X1253820Y1559604I489J1420D01*
G03X1254242Y1559665I-2J1502D01*
G01X1255396Y1560003D01*
G02X1255452Y1560011I56J-192D01*
G01X1257078D01*
G02X1257143Y1560000I0J-200D01*
G01X1258057Y1559686D01*
G03X1258545Y1559604I489J1420D01*
G03X1258967Y1559665I-2J1502D01*
G01X1260121Y1560003D01*
G02X1260177Y1560011I56J-192D01*
G01X1261802D01*
G02X1261867Y1560000I0J-200D01*
G01X1262781Y1559686D01*
G03X1263269Y1559604I489J1420D01*
G03X1263691Y1559665I-2J1502D01*
G01X1264845Y1560003D01*
G02X1264901Y1560011I56J-192D01*
G37*
G36*
G01X1266656Y121022D02*
G03I-510J0D01*
G37*
G36*
G01X1264153Y1488495D02*
G03I-519J0D01*
G37*
G36*
G01X1262243Y1485895D02*
G03I-519J0D01*
G37*
G36*
G01X1264153Y1483295D02*
G03I-519J0D01*
G37*
G36*
G01X1268933D02*
G03I-519J0D01*
G37*
G36*
G01X1270843Y1485895D02*
G03I-519J0D01*
G37*
G36*
G01X1268933Y1488495D02*
G03I-519J0D01*
G37*
G36*
G01X1262233Y1492995D02*
G03I-519J0D01*
G37*
G36*
G01X1264143Y1495595D02*
G03I-519J0D01*
G37*
G36*
G01X1262233Y1498195D02*
G03I-519J0D01*
G37*
G36*
G01X1293647Y159199D02*
X1297146D01*
X1297867Y158478D01*
Y148855D01*
X1296117Y147105D01*
Y144764D01*
X1295628Y144275D01*
X1277591D01*
X1277462Y144404D01*
Y145741D01*
X1277539Y145818D01*
X1284589D01*
X1292669Y153898D01*
Y158221D01*
X1293647Y159199D01*
G37*
G36*
G01X1279187Y808988D02*
G03I-510J0D01*
G37*
G36*
G01X1310110Y838504D02*
G02I-13779J0D01*
G37*
G36*
G01Y1199922D02*
G02I-13779J0D01*
G37*
G36*
G01X1299269Y1274790D02*
X1298340Y1275719D01*
Y1281219D01*
X1296890Y1282669D01*
X1277790D01*
X1277090Y1283369D01*
Y1289169D01*
X1277343Y1289422D01*
X1306837D01*
X1308390Y1287869D01*
Y1282869D01*
X1309590Y1281669D01*
X1328590D01*
X1329390Y1280869D01*
Y1275469D01*
X1328711Y1274790D01*
X1299269D01*
G37*
G36*
G01X1277553Y1488495D02*
G03I-519J0D01*
G37*
G36*
G01X1275643Y1485895D02*
G03I-519J0D01*
G37*
G36*
G01X1277553Y1483295D02*
G03I-519J0D01*
G37*
G36*
G01X1282333D02*
G03I-519J0D01*
G37*
G36*
G01X1284243Y1485895D02*
G03I-519J0D01*
G37*
G36*
G01X1282333Y1488495D02*
G03I-519J0D01*
G37*
G36*
G01X1289013Y1519682D02*
G03I-519J0D01*
G37*
G36*
G01X1286413Y1517772D02*
G03I-519J0D01*
G37*
G36*
G01Y1512992D02*
G03I-519J0D01*
G37*
G36*
G01X1289013Y1511082D02*
G03I-519J0D01*
G37*
G36*
G01X1286413Y1531172D02*
G03I-519J0D01*
G37*
G36*
G01Y1526392D02*
G03I-519J0D01*
G37*
G36*
G01X1289013Y1524482D02*
G03I-519J0D01*
G37*
G36*
G01X1286911Y1553883D02*
X1288415D01*
G02X1288557Y1553824I0J-200D01*
G01X1288988Y1553393D01*
G02X1289047Y1553251I-141J-142D01*
G01Y1552245D01*
G03X1289106Y1552103I200J0D01*
G01X1289563Y1551646D01*
G02X1289622Y1551505I-141J-142D01*
G01Y1551250D01*
G03X1290123Y1550748I502J0D01*
G01X1290367D01*
X1290404Y1550733D01*
G03X1290873Y1550638I470J1117D01*
G03X1291342Y1550733I-1J1212D01*
G01X1291379Y1550748D01*
X1291623D01*
G03X1292107Y1551118I0J502D01*
G01X1292125Y1551183D01*
X1292232Y1551265D01*
X1292714D01*
X1292821Y1551183D01*
X1292839Y1551118D01*
G03X1293323Y1550748I484J132D01*
G01X1293567D01*
X1293604Y1550733D01*
G03X1294073Y1550638I470J1117D01*
G03X1294542Y1550733I-1J1212D01*
G01X1294579Y1550748D01*
X1294823D01*
G03X1295307Y1551118I0J502D01*
G01X1295325Y1551183D01*
X1295432Y1551265D01*
X1295710D01*
X1295773Y1551244D01*
X1295800Y1551223D01*
G03X1297333Y1550698I1533J1976D01*
G03X1298610Y1551048I1J2502D01*
G02X1298712Y1551076I102J-172D01*
G01X1300821D01*
G02X1301021Y1550876I0J-200D01*
G01Y1549696D01*
G02X1300915Y1549519I-200J0D01*
G03X1299942Y1548584I1183J-2205D01*
G02X1299769Y1548486I-172J102D01*
G01X1299425D01*
G02X1299252Y1548584I-1J200D01*
G03X1297097Y1549816I-2155J-1269D01*
G03Y1544812I0J-2502D01*
G03X1298371Y1545161I-1J2502D01*
G02X1298615Y1545130I102J-172D01*
G01X1300102Y1543643D01*
X1300129Y1543592D01*
X1300135Y1543562D01*
G03X1300206Y1543331I1188J239D01*
G01X1300222Y1543294D01*
Y1543050D01*
G03X1300225Y1542994I501J-1D01*
G01X1300226Y1542983D01*
Y1542972D01*
G02X1300026Y1542772I-200J0D01*
G01X1297197D01*
X1297095Y1542841D01*
X1297073Y1542899D01*
G03X1294745Y1544483I-2328J-919D01*
G03X1292243Y1541981I0J-2502D01*
G03X1292312Y1541397I2502J0D01*
G01X1292325Y1541345D01*
X1292297Y1541246D01*
X1290566Y1539516D01*
G03X1290398Y1539305I858J-856D01*
G02X1290229Y1539212I-169J107D01*
G01X1288010D01*
G02X1287868Y1539270I-1J200D01*
G01X1287759Y1539380D01*
G02X1287700Y1539521I141J142D01*
G01Y1541186D01*
G03X1287641Y1541328I-200J0D01*
G01X1286563Y1542406D01*
G02X1286504Y1542548I141J142D01*
G01Y1553476D01*
G02X1286563Y1553618I200J0D01*
G01X1286769Y1553824D01*
G02X1286911Y1553883I142J-141D01*
G37*
G36*
G01X1298582Y1573138D02*
X1300113D01*
G02X1300255Y1573079I0J-200D01*
G01X1300715Y1572619D01*
G02X1300774Y1572477I-141J-142D01*
G01Y1568636D01*
G02X1300715Y1568494I-200J0D01*
G01X1300286Y1568065D01*
G02X1300145Y1568006I-142J141D01*
G01X1297034D01*
G03X1296465Y1567864I0J-1211D01*
G01X1296443Y1567853D01*
X1296396Y1567841D01*
X1295356D01*
G03X1295214Y1567782I0J-200D01*
G01X1294796Y1567364D01*
G02X1294655Y1567306I-141J142D01*
G01X1282934D01*
G02X1282734Y1567506I0J200D01*
G01Y1572009D01*
G02X1282793Y1572151I200J0D01*
G01X1282909Y1572267D01*
G02X1283051Y1572326I142J-141D01*
G01X1286355D01*
G02X1286497Y1572267I0J-200D01*
G01X1288521Y1570243D01*
G03X1288663Y1570184I142J141D01*
G01X1291784D01*
G03X1291887Y1570180I110J1498D01*
G03X1291990Y1570184I-7J1502D01*
G01X1294284D01*
G03X1294387Y1570180I110J1498D01*
G03X1294490Y1570184I-7J1502D01*
G01X1295462D01*
G03X1295604Y1570243I0J200D01*
G01X1298440Y1573079D01*
G02X1298582Y1573138I142J-141D01*
G37*
G36*
G01X1281643Y1617970D02*
X1289487D01*
G02X1289629Y1617911I0J-200D01*
G01X1293241Y1614299D01*
G03X1293383Y1614240I142J141D01*
G01X1305457D01*
G02X1305599Y1614181I0J-200D01*
G01X1306051Y1613729D01*
G02X1306110Y1613587I-141J-142D01*
G01Y1599073D01*
G02X1306051Y1598931I-200J0D01*
G01X1303669Y1596549D01*
G02X1303527Y1596490I-142J141D01*
G01X1303303D01*
G03X1303161Y1596431I0J-200D01*
G01X1293606Y1586876D01*
X1293530Y1586845D01*
X1293490Y1586846D01*
X1293459D01*
G03Y1582842I0J-2002D01*
G01X1293480D01*
G02X1293620Y1582787I2J-200D01*
G01X1293770Y1582645D01*
Y1582608D01*
X1294050Y1582328D01*
G02X1294088Y1582097I-141J-142D01*
G03X1293875Y1581199I1789J-899D01*
G03X1294132Y1580217I2002J-1D01*
G01X1294145Y1580194D01*
X1294158Y1580145D01*
Y1579833D01*
G03X1294217Y1579691I200J0D01*
G01X1295792Y1578116D01*
G02X1295851Y1577974I-141J-142D01*
G01Y1571989D01*
G02X1295792Y1571848I-200J1D01*
G01X1295189Y1571244D01*
G02X1295047Y1571186I-141J142D01*
G01X1289078D01*
G02X1288936Y1571244I-1J200D01*
G01X1286911Y1573269D01*
G03X1286770Y1573328I-142J-141D01*
G01X1286760D01*
X1281426Y1578661D01*
G02X1281367Y1578803I141J142D01*
G01Y1581450D01*
X1281337Y1581523D01*
X1281336Y1581524D01*
X1281348Y1581621D01*
G03X1281356Y1581767I-1203J139D01*
G01Y1582345D01*
G02X1281372Y1582422I200J-1D01*
G01X1282101Y1584183D01*
G03X1282194Y1584647I-1111J464D01*
G01Y1586145D01*
G03X1281839Y1587002I-1212J0D01*
G01X1281229Y1587612D01*
G02X1281170Y1587753I141J142D01*
G01Y1593167D01*
G03X1281111Y1593309I-200J0D01*
G01X1279709Y1594711D01*
G02X1279650Y1594853I141J142D01*
G01Y1615977D01*
G02X1279709Y1616119I200J0D01*
G01X1281501Y1617911D01*
G02X1281643Y1617970I142J-141D01*
G37*
G36*
G01X1296747Y106812D02*
X1315017D01*
X1315942Y105887D01*
Y99789D01*
X1314965Y98812D01*
X1296610D01*
X1295960Y99462D01*
Y106025D01*
X1296747Y106812D01*
G37*
G36*
G01X1316132Y107853D02*
X1296582D01*
X1296332Y108103D01*
Y117128D01*
X1296582Y117378D01*
X1316132D01*
X1316382Y117128D01*
Y108103D01*
X1316132Y107853D01*
G37*
G36*
G01X1299831Y153930D02*
X1308531D01*
X1309531Y152930D01*
Y148930D01*
X1308631Y148030D01*
X1300431D01*
X1299631Y148830D01*
Y153730D01*
X1299831Y153930D01*
G37*
G36*
G01X1299242Y155992D02*
Y159632D01*
X1298191Y160683D01*
Y162891D01*
X1298710Y163410D01*
X1302190D01*
X1306810Y168030D01*
X1316081D01*
X1316771Y167340D01*
Y160530D01*
X1316061Y159820D01*
X1306451D01*
X1304901Y158270D01*
Y156030D01*
X1304671Y155800D01*
X1299434D01*
X1299242Y155992D01*
G37*
G36*
G01X1300766Y523813D02*
Y527613D01*
X1301366Y528213D01*
X1302166D01*
X1308666D01*
X1309466Y527413D01*
X1309651Y527228D01*
X1310019Y526860D01*
Y517598D01*
X1309533Y517112D01*
X1301876D01*
X1300766Y518222D01*
Y519877D01*
Y523813D01*
G37*
G36*
G01X1308866Y529213D02*
X1303466D01*
X1302766D01*
X1301966Y530013D01*
Y534213D01*
X1302766Y535013D01*
X1303466D01*
X1308966D01*
X1309266Y534713D01*
Y529613D01*
X1308866Y529213D01*
G37*
G36*
G01X1346040Y583086D02*
Y524096D01*
Y517088D01*
X1345395Y516443D01*
X1325316D01*
X1324891Y516868D01*
Y525144D01*
Y559598D01*
X1324999Y559706D01*
X1333336D01*
X1333338Y559704D01*
X1334710Y561076D01*
Y578556D01*
Y586190D01*
X1334200Y586700D01*
X1294400D01*
X1294000Y587100D01*
Y588600D01*
Y594200D01*
X1294300Y594500D01*
X1299900D01*
X1300600D01*
X1344900D01*
X1346040Y593360D01*
Y583086D01*
G37*
G36*
G01X1299740Y616080D02*
X1302888Y619228D01*
Y626542D01*
Y632188D01*
X1304400Y633700D01*
X1331200D01*
X1335900D01*
X1337200Y632400D01*
Y596800D01*
X1336120Y595720D01*
X1334020D01*
X1300120D01*
X1294380D01*
X1293900Y596200D01*
Y610240D01*
X1299740Y616080D01*
G37*
G36*
G01X1303205Y1495595D02*
G03I-519J0D01*
G37*
G36*
G01X1291613Y1512992D02*
G03I-519J0D01*
G37*
G36*
G01Y1517772D02*
G03I-519J0D01*
G37*
G36*
G01X1302167Y1517280D02*
G03I-519J0D01*
G37*
G36*
G01X1299567Y1519190D02*
G03I-519J0D01*
G37*
G36*
G01X1296967Y1517280D02*
G03I-519J0D01*
G37*
G36*
G01Y1512500D02*
G03I-519J0D01*
G37*
G36*
G01X1299567Y1510590D02*
G03I-519J0D01*
G37*
G36*
G01X1302167Y1512500D02*
G03I-519J0D01*
G37*
G36*
G01X1291613Y1526392D02*
G03I-519J0D01*
G37*
G36*
G01Y1531172D02*
G03I-519J0D01*
G37*
G36*
G01X1302167Y1534300D02*
G03I-519J0D01*
G37*
G36*
G01X1299567Y1532490D02*
G03I-519J0D01*
G37*
G36*
G01X1296967Y1534300D02*
G03I-519J0D01*
G37*
G36*
G01X1299567Y1540990D02*
G03I-519J0D01*
G37*
G36*
G01X1302167Y1539080D02*
G03I-519J0D01*
G37*
G36*
G01X1301070Y1554261D02*
G03I-510J0D01*
G37*
G36*
G01X1299252Y1583581D02*
X1306913D01*
X1307004Y1583529D01*
X1307031Y1583483D01*
G03X1307215Y1583247I1040J621D01*
G01X1307354Y1583109D01*
G02X1307412Y1582967I-142J-141D01*
G01Y1574088D01*
G02X1307354Y1573947I-200J0D01*
G01X1307133Y1573726D01*
G02X1306991Y1573667I-142J141D01*
G01X1301166D01*
G02X1301025Y1573726I1J200D01*
G01X1300669Y1574081D01*
G03X1300528Y1574140I-142J-141D01*
G01X1298234D01*
X1298160Y1574170D01*
X1298135Y1574195D01*
Y1582527D01*
G02X1298194Y1582669I200J0D01*
G01X1298999Y1583474D01*
X1299030Y1583489D01*
G03X1299150Y1583553I-646J1356D01*
G02X1299252Y1583581I102J-172D01*
G37*
G36*
G01X1320423Y558609D02*
Y554526D01*
X1322564Y552385D01*
Y552376D01*
X1323280Y551660D01*
Y524313D01*
Y517396D01*
X1322302Y516418D01*
X1313940D01*
X1312365D01*
X1311766Y517017D01*
Y518592D01*
Y524113D01*
Y535213D01*
X1312766Y536213D01*
Y540025D01*
X1318755Y546013D01*
Y565307D01*
X1318346Y565716D01*
Y568094D01*
X1318588Y568336D01*
X1320188D01*
X1320423Y568101D01*
Y558609D01*
G37*
G36*
G01X1317188Y568336D02*
X1315288D01*
X1315088Y568136D01*
Y563736D01*
X1315388Y563436D01*
X1317088D01*
X1317346Y563694D01*
Y568178D01*
X1317188Y568336D01*
G37*
G36*
G01X1315411Y560735D02*
X1314339D01*
G02X1314240Y560761I-1J197D01*
G01X1312085Y562003D01*
G02X1312045Y562034I100J170D01*
G01X1311200Y562879D01*
Y566900D01*
X1311400Y567100D01*
X1313200D01*
X1313500Y566800D01*
Y563079D01*
X1314508Y562071D01*
G03X1314648Y562013I140J139D01*
G01X1316556D01*
G02X1316754Y561816I1J-197D01*
G01Y560863D01*
X1316626Y560735D01*
X1315411D01*
G37*
G36*
G01X1304200Y566700D02*
X1307000D01*
X1307300Y567000D01*
X1309900D01*
X1310100Y566800D01*
Y564784D01*
X1310008Y564692D01*
X1304008D01*
X1303900Y564800D01*
Y566400D01*
X1304200Y566700D01*
G37*
G36*
G01X1322923Y555816D02*
X1322760Y555653D01*
X1321555D01*
X1321423Y555785D01*
Y559609D01*
Y569201D01*
X1320388Y570236D01*
X1316188D01*
X1313688D01*
X1310388D01*
X1307000D01*
X1306500Y569736D01*
Y568200D01*
X1306200Y567900D01*
X1304200D01*
X1304050Y568050D01*
Y582350D01*
Y584250D01*
X1304700Y584900D01*
X1306000D01*
X1328800D01*
X1329400Y584300D01*
Y565800D01*
X1328957Y565357D01*
X1327410D01*
X1325244D01*
X1322923Y563035D01*
Y555816D01*
G37*
G36*
G01X1314422Y652410D02*
X1323800D01*
X1324500Y651710D01*
Y636460D01*
X1323600Y635560D01*
X1313300D01*
X1309840D01*
X1308900Y636500D01*
Y651400D01*
X1309910Y652410D01*
X1314422D01*
G37*
G36*
G01X1331819Y1274840D02*
X1330940Y1275719D01*
Y1281219D01*
X1329490Y1282669D01*
X1310390D01*
X1309690Y1283369D01*
Y1289169D01*
X1309968Y1289447D01*
X1339412D01*
X1340990Y1287869D01*
Y1282869D01*
X1342190Y1281669D01*
X1360370D01*
X1360989Y1281050D01*
Y1274910D01*
X1360919Y1274840D01*
X1331819D01*
G37*
G36*
G01X1311815Y1488495D02*
G03I-519J0D01*
G37*
G36*
G01X1309905Y1485895D02*
G03I-519J0D01*
G37*
G36*
G01X1311815Y1483295D02*
G03I-519J0D01*
G37*
G36*
G01X1316595D02*
G03I-519J0D01*
G37*
G36*
G01X1318505Y1485895D02*
G03I-519J0D01*
G37*
G36*
G01X1316595Y1488495D02*
G03I-519J0D01*
G37*
G36*
G01X1305115Y1498195D02*
G03I-519J0D01*
G37*
G36*
G01Y1492995D02*
G03I-519J0D01*
G37*
G36*
G01X1309895D02*
G03I-519J0D01*
G37*
G36*
G01X1311805Y1495595D02*
G03I-519J0D01*
G37*
G36*
G01X1309895Y1498195D02*
G03I-519J0D01*
G37*
G36*
G01X1309001Y1605360D02*
X1394224D01*
G02X1394366Y1605301I0J-200D01*
G01X1395632Y1604035D01*
G02X1395691Y1603893I-141J-142D01*
G01Y1597865D01*
G03X1395750Y1597723I200J0D01*
G01X1399020Y1594453D01*
X1399050Y1594382D01*
Y1594342D01*
G03X1399404Y1593079I2502J20D01*
G02X1399432Y1592977I-172J-102D01*
G01Y1591517D01*
G02X1399373Y1591375I-200J0D01*
G01X1398780Y1590782D01*
G02X1398638Y1590723I-142J141D01*
G01X1398259D01*
X1398236Y1590728D01*
G03X1397955Y1590762I-285J-1178D01*
G01X1396999D01*
G02X1396828Y1590857I-1J200D01*
G03X1395700Y1591841I-2133J-1307D01*
G01X1395666Y1591856D01*
X1393594Y1593928D01*
G03X1393452Y1593987I-142J-141D01*
G01X1320328D01*
X1320291Y1594002D01*
G03X1320099Y1594040I-191J-463D01*
G01X1319855D01*
X1319818Y1594056D01*
G03X1319349Y1594150I-468J-1117D01*
G03X1318880Y1594056I-1J-1211D01*
G01X1318843Y1594040D01*
X1318713D01*
X1318597Y1594149D01*
X1318593Y1594229D01*
G03X1316095Y1596581I-2498J-151D01*
G03X1313593Y1594079I0J-2502D01*
G03X1315629Y1591621I2502J0D01*
G01X1315700Y1591607D01*
X1315792Y1591497D01*
Y1590571D01*
G02X1315733Y1590430I-200J1D01*
G01X1315637Y1590334D01*
G02X1315495Y1590275I-142J141D01*
G01X1310554D01*
G02X1310412Y1590334I0J200D01*
G01X1309182Y1591564D01*
G02Y1591847I141J142D01*
G01X1315208Y1597874D01*
X1315307Y1597902D01*
X1315359Y1597889D01*
G03X1315943Y1597820I584J2433D01*
G03X1313441Y1600322I0J2502D01*
G03X1313510Y1599738I2502J0D01*
G01X1313523Y1599686D01*
X1313495Y1599587D01*
X1309142Y1595235D01*
G02X1308924Y1595191I-142J141D01*
G01X1308868Y1595215D01*
X1308801Y1595314D01*
Y1605160D01*
G02X1309001Y1605360I200J0D01*
G37*
G36*
G01X1523951Y763816D02*
X1548761D01*
X1550257Y762320D01*
Y743597D01*
X1552374Y741480D01*
X1575374D01*
X1575791Y741063D01*
Y735700D01*
X1575061Y734970D01*
X1556871D01*
X1555548Y733647D01*
Y733411D01*
X1555541Y733404D01*
Y726978D01*
X1555548Y726971D01*
Y726667D01*
X1556601Y725614D01*
X1556905D01*
X1556910Y725609D01*
X1578478D01*
X1581921Y722166D01*
Y713797D01*
X1581121Y712997D01*
X1577857D01*
X1577260Y713594D01*
Y722512D01*
X1576388Y723384D01*
X1556425D01*
X1555715Y722674D01*
Y707650D01*
X1556295Y707070D01*
Y706224D01*
X1576983D01*
X1578584Y704623D01*
Y704619D01*
X1579343Y703860D01*
X1582220D01*
X1582223Y703863D01*
X1583891D01*
X1588681Y699073D01*
Y693084D01*
X1589901Y691864D01*
X1613490D01*
X1614257Y691097D01*
Y685765D01*
X1618394Y681628D01*
X1621517D01*
X1622097Y681048D01*
Y674133D01*
X1623397Y672833D01*
X1678272D01*
X1679522Y671583D01*
Y621927D01*
X1678147Y620552D01*
X1658250D01*
X1657517Y621285D01*
Y629788D01*
X1653227Y634078D01*
Y644188D01*
X1652218Y645197D01*
X1644967D01*
X1642340Y647824D01*
X1635606D01*
Y645154D01*
X1635687D01*
Y645116D01*
X1635627Y645056D01*
X1635606D01*
Y644974D01*
X1636966Y643614D01*
X1638891D01*
X1639177Y643328D01*
X1642657D01*
X1642707Y643278D01*
Y642488D01*
X1642657Y642438D01*
X1639097D01*
X1638897Y642238D01*
Y638313D01*
X1639192Y638018D01*
X1643057D01*
X1643257Y637818D01*
Y637288D01*
X1643087Y637118D01*
X1639321D01*
X1638897Y636694D01*
Y635894D01*
X1638867Y635864D01*
X1632027D01*
X1631997Y635894D01*
Y643863D01*
X1630804Y645056D01*
X1612783D01*
X1612557Y645282D01*
Y647268D01*
X1616257Y650968D01*
Y662997D01*
X1614857Y664397D01*
X1611767D01*
X1609320Y666844D01*
X1607295Y666845D01*
X1602704D01*
X1602715Y666856D01*
X1602606D01*
Y664154D01*
X1602607D01*
X1602606Y664153D01*
Y664113D01*
X1604105Y662614D01*
X1605957D01*
X1606243Y662328D01*
X1609677D01*
X1609697Y662308D01*
Y661470D01*
X1609647Y661420D01*
X1606079D01*
X1605897Y661238D01*
Y657333D01*
X1606222Y657008D01*
X1609677D01*
X1609707Y656978D01*
Y656168D01*
X1609667Y656128D01*
X1606331D01*
X1605897Y655694D01*
Y654894D01*
X1605867Y654864D01*
X1599027D01*
X1598997Y654894D01*
Y662763D01*
X1597687Y664073D01*
X1579348D01*
X1579343Y664078D01*
X1578687D01*
X1577897Y664868D01*
Y672598D01*
X1578851Y673552D01*
Y679391D01*
X1582761Y683301D01*
Y697193D01*
X1581857Y698097D01*
X1579066D01*
X1576038Y701125D01*
X1575036D01*
X1574536Y700625D01*
X1569836D01*
Y697854D01*
X1571307Y696383D01*
X1573137D01*
X1573422Y696098D01*
X1576887D01*
X1576917Y696068D01*
Y695228D01*
X1576897Y695208D01*
X1573328D01*
X1573127Y695007D01*
Y691063D01*
X1573412Y690778D01*
X1576897D01*
X1576917Y690758D01*
Y689918D01*
X1576897Y689898D01*
X1573562D01*
X1573127Y689463D01*
Y688663D01*
X1573097Y688633D01*
X1566257D01*
X1566227Y688663D01*
Y696463D01*
X1564865Y697825D01*
X1547757D01*
X1547257Y698325D01*
Y699265D01*
X1548257Y700265D01*
Y703265D01*
X1549502Y704510D01*
Y719852D01*
X1549257Y720097D01*
X1546044D01*
X1542908Y723233D01*
X1541906D01*
Y723232D01*
X1541430Y722756D01*
X1536811D01*
X1536788Y722733D01*
X1536706D01*
Y722651D01*
X1536701Y722646D01*
Y721991D01*
X1536706Y721986D01*
Y719814D01*
X1538029Y718491D01*
X1540037D01*
X1540320Y718208D01*
X1543767D01*
X1543777Y718198D01*
Y717338D01*
X1543757Y717318D01*
X1540200D01*
X1539997Y717115D01*
Y713083D01*
X1540192Y712888D01*
X1543777D01*
X1543787Y712878D01*
Y712028D01*
X1543757Y711998D01*
X1540424D01*
X1539997Y711571D01*
Y710771D01*
X1539967Y710741D01*
X1533127D01*
X1533097Y710771D01*
Y718393D01*
X1531557Y719933D01*
X1523306D01*
Y719932D01*
X1516922D01*
X1516610Y720244D01*
X1513097D01*
X1510583Y722758D01*
X1503906D01*
Y719934D01*
X1505349Y718491D01*
X1507247D01*
X1507540Y718198D01*
X1510967D01*
X1510997Y718168D01*
Y717358D01*
X1510957Y717318D01*
X1507400D01*
X1507197Y717115D01*
Y713213D01*
X1507522Y712888D01*
X1510957D01*
X1510977Y712868D01*
Y712018D01*
X1510957Y711998D01*
X1507624D01*
X1507197Y711571D01*
Y710771D01*
X1507167Y710741D01*
X1500327D01*
X1500297Y710771D01*
Y718563D01*
X1498927Y719933D01*
X1484267D01*
X1483956Y720244D01*
X1479847D01*
X1477528Y722563D01*
X1470824D01*
Y719766D01*
X1472267Y718323D01*
X1474167D01*
X1474452Y718038D01*
X1477877D01*
X1477897Y718018D01*
Y717168D01*
X1477877Y717148D01*
X1474316D01*
X1474115Y716947D01*
Y713075D01*
X1474472Y712718D01*
X1477877D01*
X1477907Y712688D01*
Y711868D01*
X1477877Y711838D01*
X1474550D01*
X1474115Y711403D01*
Y710603D01*
X1474085Y710573D01*
X1467245D01*
X1467215Y710603D01*
Y718445D01*
X1465895Y719765D01*
X1451925D01*
X1450257Y718097D01*
Y716097D01*
X1448769Y714609D01*
X1445273D01*
X1443860Y716022D01*
Y724929D01*
X1443042Y725747D01*
X1424495D01*
X1423785Y725037D01*
Y710013D01*
X1423788Y710010D01*
Y709306D01*
X1424507Y708587D01*
X1445053D01*
X1446654Y706986D01*
Y706982D01*
X1447413Y706223D01*
X1448760D01*
X1449757Y705226D01*
Y701234D01*
X1449257Y700734D01*
X1446862D01*
X1444108Y703488D01*
X1443106D01*
X1442606Y702988D01*
X1437906D01*
Y700274D01*
X1439434Y698746D01*
X1441197D01*
X1441485Y698458D01*
X1444977D01*
X1444997Y698438D01*
Y697598D01*
X1444967Y697568D01*
X1441395D01*
X1441197Y697370D01*
Y693413D01*
X1441462Y693148D01*
X1444957D01*
X1444987Y693118D01*
Y692288D01*
X1444957Y692258D01*
X1441629D01*
X1441197Y691826D01*
Y691026D01*
X1441167Y690996D01*
X1434327D01*
X1434297Y691026D01*
Y698853D01*
X1432962Y700188D01*
X1424506D01*
X1424283Y699965D01*
X1418457D01*
X1417631Y699139D01*
Y683297D01*
X1416431Y682097D01*
X1412671D01*
X1411771Y682997D01*
Y692151D01*
X1410971Y692951D01*
X1410658D01*
X1410442Y693167D01*
X1391895D01*
X1391185Y692457D01*
Y677433D01*
X1391671Y676947D01*
Y676243D01*
X1391907Y676007D01*
X1412247D01*
X1414657Y673597D01*
X1417131D01*
X1417631Y673097D01*
Y669238D01*
X1416957Y668564D01*
X1413852D01*
X1411508Y670908D01*
X1410506D01*
X1410006Y670408D01*
X1405306D01*
Y667624D01*
X1406764Y666166D01*
X1408607D01*
X1408885Y665888D01*
X1412357D01*
X1412367Y665878D01*
Y664998D01*
X1412357Y664988D01*
X1408795D01*
X1408597Y664790D01*
Y660843D01*
X1408872Y660568D01*
X1412357D01*
X1412387Y660538D01*
Y659698D01*
X1412367Y659678D01*
X1409029D01*
X1408597Y659246D01*
Y658446D01*
X1408567Y658416D01*
X1401727D01*
X1401697Y658446D01*
Y666373D01*
X1400462Y667608D01*
X1386000D01*
X1384961Y666569D01*
Y649801D01*
X1384129Y648969D01*
X1380133D01*
X1379171Y649931D01*
Y659351D01*
X1378371Y660151D01*
X1377858D01*
X1377742Y660267D01*
X1359195D01*
X1358485Y659557D01*
Y644533D01*
X1358488Y644530D01*
Y643826D01*
X1359207Y643107D01*
X1379615D01*
X1381976Y640746D01*
X1384157D01*
X1384961Y639942D01*
Y636568D01*
X1384157Y635764D01*
X1381881D01*
X1380164Y637481D01*
X1378808D01*
Y638008D01*
X1377806D01*
Y637508D01*
X1372606D01*
Y634806D01*
X1372662D01*
Y634774D01*
X1372606Y634718D01*
Y634694D01*
X1374034Y633266D01*
X1375907D01*
X1376195Y632978D01*
X1379657D01*
X1379687Y632948D01*
Y632128D01*
X1379657Y632098D01*
X1376105D01*
X1375897Y631890D01*
Y628034D01*
X1376263Y627668D01*
X1379657D01*
X1379677Y627648D01*
Y626798D01*
X1379657Y626778D01*
X1376329D01*
X1375897Y626346D01*
Y625546D01*
X1375867Y625516D01*
X1369027D01*
X1368997Y625546D01*
Y633423D01*
X1367712Y634708D01*
X1360206D01*
Y634721D01*
X1330147D01*
X1329261Y635607D01*
Y650922D01*
X1330136Y651797D01*
X1347957D01*
X1352257Y656097D01*
Y659197D01*
X1355545Y662485D01*
X1378285D01*
X1379261Y663461D01*
Y669601D01*
X1379757Y670097D01*
X1383257D01*
X1386757Y673597D01*
Y693097D01*
X1388945Y695285D01*
X1411025D01*
X1411901Y696161D01*
Y702591D01*
X1412741Y703431D01*
X1416757D01*
X1419357Y706031D01*
Y724997D01*
X1421815Y727455D01*
X1444115D01*
X1445607Y728947D01*
Y734347D01*
X1446757Y735497D01*
X1449557D01*
X1452261Y738201D01*
Y746101D01*
X1453329Y747169D01*
X1542661D01*
X1543858Y748366D01*
X1543861D01*
Y755796D01*
X1542911Y756746D01*
X1524831D01*
X1523561Y758016D01*
Y763426D01*
X1523951Y763816D01*
G37*
G36*
G01X1377157Y670165D02*
X1378057Y669265D01*
Y664065D01*
X1377553Y663561D01*
X1354221D01*
X1350357Y659697D01*
Y656597D01*
X1347557Y653797D01*
X1330357D01*
X1329783Y654371D01*
Y665000D01*
Y669023D01*
X1330925Y670165D01*
X1377157D01*
G37*
G36*
G01X1465232Y807098D02*
X1474790Y797540D01*
X1546340D01*
X1549257Y794623D01*
Y768059D01*
G02X1549198Y767917I-200J0D01*
G01X1546868Y765588D01*
X1456333D01*
X1455357Y764612D01*
Y764093D01*
Y759948D01*
G02X1455298Y759806I-200J0D01*
G01X1453316Y757824D01*
X1453288Y757795D01*
X1453214Y757765D01*
X1446340D01*
G03X1446198Y757706I0J-200D01*
G01X1442816Y754324D01*
G03X1442757Y754182I141J-142D01*
G01Y746637D01*
X1442166Y746046D01*
X1423502D01*
X1422257Y744801D01*
Y739348D01*
G02X1422198Y739206I-200J0D01*
G01X1420816Y737824D01*
X1420788Y737795D01*
X1420714Y737765D01*
X1415008D01*
G03X1414866Y737706I0J-200D01*
G01X1410316Y733156D01*
G03X1410257Y733014I141J-142D01*
G01Y714143D01*
X1409572Y713458D01*
X1391339D01*
X1389757Y711876D01*
Y706848D01*
G02X1389698Y706706I-200J0D01*
G01X1388316Y705324D01*
X1388288Y705295D01*
X1388214Y705265D01*
X1382840D01*
G03X1382698Y705206I0J-200D01*
G01X1378316Y700824D01*
G03X1378257Y700682I141J-142D01*
G01Y681659D01*
X1377136Y680538D01*
X1354508D01*
X1352646Y682400D01*
G03X1352504Y682459I-142J-141D01*
G01X1327210D01*
G02X1327068Y682518I0J200D01*
G01X1320186Y689400D01*
X1320157Y689428D01*
X1320127Y689502D01*
Y782855D01*
Y790417D01*
X1349600Y819890D01*
X1452440D01*
X1465232Y807098D01*
G37*
G36*
G01X1330933Y857388D02*
G03I-656J0D01*
G37*
G36*
G01X1327153Y1214334D02*
G03I-720J0D01*
G37*
G36*
G01X1330468Y1422513D02*
X1354037D01*
X1358046D01*
X1358731Y1421828D01*
X1359943Y1420616D01*
Y1407203D01*
G02X1359885Y1407064I-197J1D01*
G01X1358990Y1406169D01*
X1327184D01*
X1322660D01*
X1321060D01*
X1320549Y1406680D01*
Y1421760D01*
X1321302Y1422513D01*
X1322642D01*
X1330468D01*
G37*
G36*
G01X1323305Y1505295D02*
G03I-519J0D01*
G37*
G36*
G01X1325215Y1502695D02*
G03I-519J0D01*
G37*
G36*
G01X1329995D02*
G03I-519J0D01*
G37*
G36*
G01X1331905Y1505295D02*
G03I-519J0D01*
G37*
G36*
G01X1331915Y1498195D02*
G03I-519J0D01*
G37*
G36*
G01X1330005Y1495595D02*
G03I-519J0D01*
G37*
G36*
G01X1331915Y1492995D02*
G03I-519J0D01*
G37*
G36*
G01X1325215Y1507895D02*
G03I-519J0D01*
G37*
G36*
G01X1329995D02*
G03I-519J0D01*
G37*
G36*
G01X1336270Y1560011D02*
X1337896D01*
G02X1337961Y1560000I0J-200D01*
G01X1338875Y1559686D01*
G03X1339281Y1559607I487J1420D01*
G01X1339320Y1559605D01*
X1339389Y1559573D01*
X1339605Y1559345D01*
G02X1339660Y1559207I-145J-138D01*
G01Y1557099D01*
G02X1339605Y1556961I-200J0D01*
G01X1339389Y1556733D01*
X1339320Y1556701D01*
X1339281Y1556699D01*
G03X1338966Y1556648I81J-1499D01*
G01X1337744Y1556313D01*
G02X1337691Y1556306I-52J193D01*
G01X1336004D01*
G02X1335934Y1556319I1J200D01*
G01X1335163Y1556607D01*
G03X1334638Y1556702I-526J-1407D01*
G03X1334241Y1556648I2J-1502D01*
G01X1333020Y1556313D01*
G02X1332967Y1556306I-52J193D01*
G01X1331280D01*
G02X1331210Y1556319I1J200D01*
G01X1330439Y1556607D01*
G03X1329914Y1556702I-526J-1407D01*
G03X1329517Y1556648I2J-1502D01*
G01X1328295Y1556313D01*
G02X1328242Y1556306I-52J193D01*
G01X1326555D01*
G02X1326485Y1556319I1J200D01*
G01X1325714Y1556607D01*
G03X1325189Y1556702I-526J-1407D01*
G03X1324792Y1556648I2J-1502D01*
G01X1323571Y1556313D01*
G02X1323518Y1556306I-52J193D01*
G01X1322115D01*
G02X1321973Y1556365I0J200D01*
G01X1321811Y1556527D01*
G02X1321752Y1556669I141J142D01*
G01Y1559626D01*
G02X1321881Y1559813I200J0D01*
G01X1322365Y1559998D01*
G02X1322437Y1560011I71J-187D01*
G01X1323722D01*
G02X1323787Y1560000I0J-200D01*
G01X1324701Y1559686D01*
G03X1325189Y1559604I489J1420D01*
G03X1325611Y1559665I-2J1502D01*
G01X1326765Y1560003D01*
G02X1326821Y1560011I56J-192D01*
G01X1328447D01*
G02X1328512Y1560000I0J-200D01*
G01X1329426Y1559686D01*
G03X1329914Y1559604I489J1420D01*
G03X1330336Y1559665I-2J1502D01*
G01X1331490Y1560003D01*
G02X1331546Y1560011I56J-192D01*
G01X1333171D01*
G02X1333236Y1560000I0J-200D01*
G01X1334150Y1559686D01*
G03X1334638Y1559604I489J1420D01*
G03X1335060Y1559665I-2J1502D01*
G01X1336214Y1560003D01*
G02X1336270Y1560011I56J-192D01*
G37*
G36*
G01X1517461Y718466D02*
X1531561D01*
X1531606Y718421D01*
Y710733D01*
X1526177D01*
X1525445Y710001D01*
Y706040D01*
X1524257Y704852D01*
Y692038D01*
X1520297Y688078D01*
Y669608D01*
X1512177Y661488D01*
X1511920Y661231D01*
Y629731D01*
X1510677Y628488D01*
X1438667D01*
X1435177Y624998D01*
Y590718D01*
X1431227Y586768D01*
X1389067D01*
X1379238Y596597D01*
X1346145D01*
X1344682Y598060D01*
Y632582D01*
X1345606Y633506D01*
X1360506D01*
X1360706Y633306D01*
X1367506D01*
Y625567D01*
X1367447Y625508D01*
X1361907D01*
X1361451Y625052D01*
Y620931D01*
X1360151Y619631D01*
Y611271D01*
X1361666Y609756D01*
X1384045D01*
X1385961Y611672D01*
Y640299D01*
X1388048Y642386D01*
Y648350D01*
X1386742Y649656D01*
X1386737D01*
X1385961Y650432D01*
Y665940D01*
X1386427Y666406D01*
X1393206D01*
X1393406Y666206D01*
X1400206D01*
Y658408D01*
X1394637D01*
X1394201Y657972D01*
Y654612D01*
X1392161Y652572D01*
Y645193D01*
X1392743Y644611D01*
X1397257D01*
X1397757Y644111D01*
Y641765D01*
X1399034Y640488D01*
X1412800D01*
X1418757Y646445D01*
Y673295D01*
X1420748Y675286D01*
Y681250D01*
X1419442Y682556D01*
X1419437D01*
X1418757Y683236D01*
Y698265D01*
X1419457Y698965D01*
X1426006D01*
Y698786D01*
X1432806D01*
Y690988D01*
X1427270D01*
X1426801Y690519D01*
Y686641D01*
X1425257Y685097D01*
Y678265D01*
X1426257Y677265D01*
X1431757D01*
X1431923Y677099D01*
Y674099D01*
X1432257Y673765D01*
X1446527D01*
X1451061Y678299D01*
Y705579D01*
X1453348Y707866D01*
Y713830D01*
X1452042Y715136D01*
X1452037D01*
X1451757Y715416D01*
Y717981D01*
X1452161Y718385D01*
X1458924D01*
Y718363D01*
X1465724D01*
Y710565D01*
X1460377D01*
X1459567Y709755D01*
Y706223D01*
X1458247Y704903D01*
Y697765D01*
X1458747Y697265D01*
X1462257D01*
X1463307Y696215D01*
Y694315D01*
X1464358Y693265D01*
X1479457D01*
X1484311Y698119D01*
Y718016D01*
X1484761Y718466D01*
X1498806D01*
Y710733D01*
X1493165D01*
X1492647Y710215D01*
Y706342D01*
X1491161Y704856D01*
Y698154D01*
X1494403Y694912D01*
X1513202D01*
X1516961Y698671D01*
Y717966D01*
X1517461Y718466D01*
G37*
G36*
G01X1340003Y857388D02*
G03I-656J0D01*
G37*
G36*
G01X1338485Y1177999D02*
G03I-510J0D01*
G37*
G36*
G01X1338652Y1181642D02*
G03I-510J0D01*
G37*
G36*
G01X1342819Y1289498D02*
X1364066D01*
X1367689Y1293121D01*
Y1298511D01*
X1369443Y1300265D01*
X1393190D01*
X1394190Y1299265D01*
Y1295265D01*
X1393190Y1294265D01*
X1373090D01*
X1371439Y1292614D01*
Y1285737D01*
X1368803Y1283101D01*
X1342358D01*
X1342090Y1283369D01*
Y1288769D01*
X1342819Y1289498D01*
G37*
G36*
G01X1338615Y1488495D02*
G03I-519J0D01*
G37*
G36*
G01X1336705Y1485895D02*
G03I-519J0D01*
G37*
G36*
G01X1338615Y1483295D02*
G03I-519J0D01*
G37*
G36*
G01X1343395D02*
G03I-519J0D01*
G37*
G36*
G01X1345305Y1485895D02*
G03I-519J0D01*
G37*
G36*
G01X1343395Y1488495D02*
G03I-519J0D01*
G37*
G36*
G01X1336695Y1492995D02*
G03I-519J0D01*
G37*
G36*
G01X1338605Y1495595D02*
G03I-519J0D01*
G37*
G36*
G01X1336695Y1498195D02*
G03I-519J0D01*
G37*
G36*
G01X1346122Y1560011D02*
X1347344D01*
G02X1347409Y1560000I0J-200D01*
G01X1348323Y1559686D01*
G03X1348765Y1559605I489J1420D01*
G01X1348804Y1559604D01*
X1348875Y1559573D01*
X1349096Y1559345D01*
G02X1349152Y1559205I-144J-139D01*
G01Y1557101D01*
G02X1349096Y1556961I-200J-1D01*
G01X1348875Y1556733D01*
X1348804Y1556702D01*
X1348765Y1556701D01*
G03X1348414Y1556648I47J-1501D01*
G01X1347193Y1556313D01*
G02X1347140Y1556306I-52J193D01*
G01X1345788D01*
X1345715Y1556336D01*
X1345704Y1556346D01*
Y1559594D01*
G02X1345763Y1559735I200J-1D01*
G01X1345980Y1559952D01*
G02X1346122Y1560011I142J-141D01*
G37*
G36*
G01X1341070D02*
X1342620D01*
G02X1342685Y1560000I0J-200D01*
G01X1343599Y1559686D01*
G03X1344087Y1559604I489J1420D01*
G03X1344258Y1559614I-2J1502D01*
G01X1344301Y1559619D01*
X1344381Y1559594D01*
X1344636Y1559366D01*
G02X1344703Y1559217I-133J-149D01*
G01Y1557089D01*
G02X1344636Y1556940I-200J0D01*
G01X1344381Y1556712D01*
X1344301Y1556687D01*
X1344258Y1556692D01*
G03X1344087Y1556702I-173J-1492D01*
G03X1343690Y1556648I2J-1502D01*
G01X1342468Y1556313D01*
G02X1342415Y1556306I-52J193D01*
G01X1341026D01*
G02X1340884Y1556365I0J200D01*
G01X1340720Y1556529D01*
G02X1340661Y1556671I141J142D01*
G01Y1559602D01*
G02X1340720Y1559744I200J0D01*
G01X1340928Y1559952D01*
G02X1341070Y1560011I142J-141D01*
G37*
G36*
G01X1359779Y644657D02*
X1359488Y644948D01*
Y659142D01*
X1359610Y659264D01*
X1377327D01*
X1377557Y659034D01*
Y650127D01*
X1379999Y647685D01*
X1380115Y647569D01*
X1382753D01*
X1382957Y647365D01*
Y645465D01*
X1382149Y644657D01*
X1359779D01*
G37*
G36*
G01X1383425Y702765D02*
X1410257D01*
X1410737Y702285D01*
Y696953D01*
X1410277Y696493D01*
X1388153D01*
X1385257Y693597D01*
Y674097D01*
X1383425Y672265D01*
X1359757D01*
X1359331Y672691D01*
Y677951D01*
X1359798Y678418D01*
X1377910D01*
X1380257Y680765D01*
Y699597D01*
X1383425Y702765D01*
G37*
G36*
G01X1351319Y1202323D02*
G03I-510J0D01*
G37*
G36*
G01X1363505Y1485895D02*
G03I-519J0D01*
G37*
G36*
G01X1350105Y1505295D02*
G03I-519J0D01*
G37*
G36*
G01X1352015Y1502695D02*
G03I-519J0D01*
G37*
G36*
G01X1356795D02*
G03I-519J0D01*
G37*
G36*
G01X1358705Y1505295D02*
G03I-519J0D01*
G37*
G36*
G01X1358715Y1498195D02*
G03I-519J0D01*
G37*
G36*
G01X1356805Y1495595D02*
G03I-519J0D01*
G37*
G36*
G01X1358715Y1492995D02*
G03I-519J0D01*
G37*
G36*
G01X1363495D02*
G03I-519J0D01*
G37*
G36*
G01Y1498195D02*
G03I-519J0D01*
G37*
G36*
G01X1352015Y1507895D02*
G03I-519J0D01*
G37*
G36*
G01X1356795D02*
G03I-519J0D01*
G37*
G36*
G01X1359889Y1560010D02*
X1360841D01*
G02X1360983Y1559951I0J-200D01*
G01X1361241Y1559693D01*
G02X1361300Y1559552I-141J-142D01*
G01Y1558527D01*
G03X1361358Y1558386I200J0D01*
G01X1361364Y1558380D01*
X1361394Y1558307D01*
Y1558276D01*
X1361731Y1557939D01*
X1361804Y1557909D01*
X1361835D01*
X1362127Y1557617D01*
G03X1362268Y1557558I142J141D01*
G01X1363392D01*
G02X1363592Y1557358I0J-200D01*
G01Y1557090D01*
G02X1363525Y1556941I-200J0D01*
G01X1363271Y1556714D01*
X1363191Y1556688D01*
X1363148Y1556693D01*
G03X1362985Y1556702I-164J-1493D01*
G03X1362588Y1556648I2J-1502D01*
G01X1361366Y1556313D01*
G02X1361313Y1556306I-52J193D01*
G01X1359626D01*
G02X1359556Y1556319I1J200D01*
G01X1358785Y1556607D01*
G03X1358260Y1556702I-526J-1407D01*
G03X1357863Y1556648I2J-1502D01*
G01X1356642Y1556313D01*
G02X1356589Y1556306I-52J193D01*
G01X1354902D01*
G02X1354832Y1556319I1J200D01*
G01X1354061Y1556607D01*
G03X1353536Y1556702I-526J-1407D01*
G03X1353139Y1556648I2J-1502D01*
G01X1351917Y1556313D01*
G02X1351864Y1556306I-52J193D01*
G01X1350470D01*
G02X1350328Y1556365I0J200D01*
G01X1350213Y1556480D01*
G02X1350154Y1556622I141J142D01*
G01Y1559271D01*
G02X1350213Y1559413I200J0D01*
G01X1350751Y1559951D01*
G02X1350893Y1560010I142J-141D01*
G01X1352072D01*
G02X1352137Y1559999I0J-200D01*
G01X1353048Y1559686D01*
G03X1353536Y1559604I489J1420D01*
G03X1353958Y1559665I-2J1502D01*
G01X1355109Y1560002D01*
G02X1355165Y1560010I56J-192D01*
G01X1356796D01*
G02X1356861Y1559999I0J-200D01*
G01X1357772Y1559686D01*
G03X1358260Y1559604I489J1420D01*
G03X1358682Y1559665I-2J1502D01*
G01X1359833Y1560002D01*
G02X1359889Y1560010I56J-192D01*
G37*
G36*
G01X1364146Y1559873D02*
X1365943D01*
G02X1366085Y1559814I0J-200D01*
G01X1366095Y1559804D01*
X1366126Y1559730D01*
Y1556821D01*
G02X1366067Y1556680I-200J1D01*
G01X1365834Y1556447D01*
G02X1365692Y1556388I-142J141D01*
G01X1364962D01*
G02X1364820Y1556447I0J200D01*
G01X1364652Y1556615D01*
G02X1364593Y1556757I141J142D01*
G01Y1558154D01*
G03X1364534Y1558296I-200J0D01*
G01X1364329Y1558501D01*
G03X1364187Y1558560I-142J-141D01*
G01X1362683D01*
G02X1362541Y1558619I0J200D01*
G01X1362360Y1558800D01*
G02X1362301Y1558942I141J142D01*
G01Y1559384D01*
G02X1362360Y1559526I200J0D01*
G01X1362468Y1559634D01*
X1362569Y1559662D01*
X1362621Y1559649D01*
G03X1362985Y1559604I365J1457D01*
G03X1363407Y1559665I-2J1502D01*
G01X1364089Y1559865D01*
G02X1364146Y1559873I56J-192D01*
G37*
G36*
G01X1378372Y485552D02*
G03I-510J0D01*
G37*
G36*
G01Y511052D02*
G03I-510J0D01*
G37*
G36*
G01X1364749Y1207949D02*
G03I-510J0D01*
G37*
G36*
G01X1421414Y1294400D02*
X1396209D01*
X1395803Y1294806D01*
Y1301121D01*
X1395124Y1301800D01*
X1375690D01*
X1374890Y1302600D01*
Y1308054D01*
X1375820Y1308984D01*
X1422080D01*
X1422856Y1308208D01*
Y1295842D01*
X1421414Y1294400D01*
G37*
G36*
G01X1393740Y1328075D02*
X1394031Y1327784D01*
Y1313590D01*
X1393909Y1313468D01*
X1376192D01*
X1375962Y1313698D01*
Y1322605D01*
X1373520Y1325047D01*
X1373404Y1325163D01*
X1371379D01*
X1371148D01*
X1370506Y1325805D01*
Y1327278D01*
X1371303Y1328075D01*
X1393740D01*
G37*
G36*
G01X1369384Y1325079D02*
X1368219D01*
X1367607D01*
X1367474Y1325212D01*
Y1329516D01*
X1368091Y1330133D01*
X1368944Y1330986D01*
X1370991D01*
X1371162Y1330815D01*
Y1329374D01*
X1369488Y1327700D01*
Y1327307D01*
Y1325183D01*
X1369384Y1325079D01*
G37*
G36*
G01X1365415Y1488495D02*
G03I-519J0D01*
G37*
G36*
G01Y1483295D02*
G03I-519J0D01*
G37*
G36*
G01X1370195D02*
G03I-519J0D01*
G37*
G36*
G01X1372105Y1485895D02*
G03I-519J0D01*
G37*
G36*
G01X1370195Y1488495D02*
G03I-519J0D01*
G37*
G36*
G01X1365405Y1495595D02*
G03I-519J0D01*
G37*
G36*
G01X1376905Y1505295D02*
G03I-519J0D01*
G37*
G36*
G01X1378815Y1502695D02*
G03I-519J0D01*
G37*
G36*
G01Y1507895D02*
G03I-519J0D01*
G37*
G36*
G01X1369341Y1560011D02*
X1370290D01*
G02X1370432Y1559952I0J-200D01*
G01X1370745Y1559639D01*
G02X1370804Y1559498I-141J-142D01*
G01Y1556809D01*
G02X1370745Y1556668I-200J1D01*
G01X1370442Y1556365D01*
G02X1370300Y1556306I-142J141D01*
G01X1369075D01*
G02X1369005Y1556319I1J200D01*
G01X1368234Y1556607D01*
G03X1367709Y1556702I-526J-1407D01*
G03X1367448Y1556679I0J-1492D01*
G01X1367400Y1556670D01*
X1367307Y1556699D01*
X1367186Y1556820D01*
G02X1367127Y1556962I141J142D01*
G01Y1559338D01*
G02X1367186Y1559480I200J0D01*
G01X1367312Y1559606D01*
X1367403Y1559635D01*
X1367453Y1559627D01*
G03X1367709Y1559604I262J1478D01*
G03X1368131Y1559665I-2J1502D01*
G01X1369285Y1560003D01*
G02X1369341Y1560011I56J-192D01*
G37*
G36*
G01X1392963D02*
X1393939D01*
G02X1394045Y1559981I1J-200D01*
G01X1394317Y1559810D01*
G02X1394353Y1559782I-104J-171D01*
G01X1394418Y1559717D01*
G02X1394477Y1559575I-141J-142D01*
G01Y1556591D01*
G02X1394418Y1556449I-200J0D01*
G01X1394334Y1556365D01*
G02X1394192Y1556306I-142J141D01*
G01X1392697D01*
G02X1392627Y1556319I1J200D01*
G01X1391856Y1556607D01*
G03X1391331Y1556702I-526J-1407D01*
G03X1390934Y1556648I2J-1502D01*
G01X1389713Y1556313D01*
G02X1389660Y1556306I-52J193D01*
G01X1387973D01*
G02X1387903Y1556319I1J200D01*
G01X1387132Y1556607D01*
G03X1386607Y1556702I-526J-1407D01*
G03X1386210Y1556648I2J-1502D01*
G01X1384988Y1556313D01*
G02X1384935Y1556306I-52J193D01*
G01X1383248D01*
G02X1383178Y1556319I1J200D01*
G01X1382407Y1556607D01*
G03X1381882Y1556702I-526J-1407D01*
G03X1381485Y1556648I2J-1502D01*
G01X1380264Y1556313D01*
G02X1380211Y1556306I-52J193D01*
G01X1378524D01*
G02X1378454Y1556319I1J200D01*
G01X1377683Y1556607D01*
G03X1377248Y1556699I-525J-1407D01*
G01X1377209Y1556701D01*
X1377140Y1556733D01*
X1376926Y1556961D01*
G02X1376872Y1557098I146J137D01*
G01Y1559208D01*
G02X1376926Y1559345I200J0D01*
G01X1377140Y1559573D01*
X1377209Y1559605D01*
X1377248Y1559607D01*
G03X1377580Y1559665I-91J1499D01*
G01X1378734Y1560003D01*
G02X1378790Y1560011I56J-192D01*
G01X1380415D01*
G02X1380480Y1560000I0J-200D01*
G01X1381394Y1559686D01*
G03X1381882Y1559604I489J1420D01*
G03X1382304Y1559665I-2J1502D01*
G01X1383458Y1560003D01*
G02X1383514Y1560011I56J-192D01*
G01X1385140D01*
G02X1385205Y1560000I0J-200D01*
G01X1386119Y1559686D01*
G03X1386607Y1559604I489J1420D01*
G03X1387029Y1559665I-2J1502D01*
G01X1388183Y1560003D01*
G02X1388239Y1560011I56J-192D01*
G01X1389864D01*
G02X1389929Y1560000I0J-200D01*
G01X1390843Y1559686D01*
G03X1391331Y1559604I489J1420D01*
G03X1391753Y1559665I-2J1502D01*
G01X1392907Y1560003D01*
G02X1392963Y1560011I56J-192D01*
G37*
G36*
G01X1374065D02*
X1375550D01*
G02X1375692Y1559952I0J-200D01*
G01X1375811Y1559833D01*
G02X1375870Y1559691I-141J-142D01*
G01Y1556776D01*
G02X1375811Y1556634I-200J0D01*
G01X1375542Y1556365D01*
G02X1375400Y1556306I-142J141D01*
G01X1373799D01*
G02X1373729Y1556319I1J200D01*
G01X1372958Y1556607D01*
G03X1372433Y1556702I-526J-1407D01*
G03X1372156Y1556676I1J-1502D01*
G01X1372107Y1556666D01*
X1372012Y1556696D01*
X1371864Y1556844D01*
G02X1371805Y1556986I141J142D01*
G01Y1559218D01*
G02X1371872Y1559368I200J1D01*
G01X1372128Y1559595D01*
X1372210Y1559620D01*
X1372253Y1559615D01*
G03X1372433Y1559604I181J1491D01*
G03X1372855Y1559665I-2J1502D01*
G01X1374009Y1560003D01*
G02X1374065Y1560011I56J-192D01*
G37*
G36*
G01X1384135Y647653D02*
X1385300D01*
X1385912D01*
X1386045Y647520D01*
Y643216D01*
X1385428Y642599D01*
X1384575Y641746D01*
X1382528D01*
X1382357Y641917D01*
Y643358D01*
X1384031Y645032D01*
Y645425D01*
Y647549D01*
X1384135Y647653D01*
G37*
G36*
G01X1392479Y677557D02*
X1392188Y677848D01*
Y692042D01*
X1392310Y692164D01*
X1410027D01*
X1410257Y691934D01*
Y683027D01*
X1412699Y680585D01*
X1412815Y680469D01*
X1415453D01*
X1415657Y680265D01*
Y678365D01*
X1414849Y677557D01*
X1392479D01*
G37*
G36*
G01X1415257Y735265D02*
X1443257D01*
X1444197Y734325D01*
Y729933D01*
X1443297Y729033D01*
X1420693D01*
X1417757Y726097D01*
Y706097D01*
X1416425Y704765D01*
X1392757D01*
X1391757Y705765D01*
Y710765D01*
X1392257Y711265D01*
X1410757D01*
X1412257Y712765D01*
Y732265D01*
X1415257Y735265D01*
G37*
G36*
G01X1392215Y1488495D02*
G03I-519J0D01*
G37*
G36*
G01X1390305Y1485895D02*
G03I-519J0D01*
G37*
G36*
G01X1392215Y1483295D02*
G03I-519J0D01*
G37*
G36*
G01X1383595Y1502695D02*
G03I-519J0D01*
G37*
G36*
G01X1385505Y1505295D02*
G03I-519J0D01*
G37*
G36*
G01X1385515Y1498195D02*
G03I-519J0D01*
G37*
G36*
G01X1383605Y1495595D02*
G03I-519J0D01*
G37*
G36*
G01X1385515Y1492995D02*
G03I-519J0D01*
G37*
G36*
G01X1390295D02*
G03I-519J0D01*
G37*
G36*
G01X1392205Y1495595D02*
G03I-519J0D01*
G37*
G36*
G01X1390295Y1498195D02*
G03I-519J0D01*
G37*
G36*
G01X1383595Y1507895D02*
G03I-519J0D01*
G37*
G36*
G01X1393689Y1733118D02*
G03I-510J0D01*
G37*
G36*
G01X1403717Y118938D02*
G03I-510J0D01*
G37*
G36*
G01X1404010Y458377D02*
G03I-510J0D01*
G37*
G36*
G01X1396995Y1483295D02*
G03I-519J0D01*
G37*
G36*
G01X1398905Y1485895D02*
G03I-519J0D01*
G37*
G36*
G01X1396995Y1488495D02*
G03I-519J0D01*
G37*
G36*
G01X1405615D02*
G03I-519J0D01*
G37*
G36*
G01X1403705Y1485895D02*
G03I-519J0D01*
G37*
G36*
G01X1405615Y1483295D02*
G03I-519J0D01*
G37*
G36*
G01X1418606Y1581197D02*
X1421725D01*
G02X1421867Y1581138I0J-200D01*
G01X1421978Y1581027D01*
G02X1422037Y1580885I-141J-142D01*
G01Y1579950D01*
X1422036Y1579940D01*
G03X1422029Y1579795I1495J-145D01*
G03X1422036Y1579650I1502J0D01*
G01X1422037Y1579640D01*
Y1577450D01*
X1422036Y1577440D01*
G03X1422029Y1577295I1495J-145D01*
G03X1422036Y1577150I1502J0D01*
G01X1422037Y1577140D01*
Y1574950D01*
X1422036Y1574940D01*
G03X1422029Y1574795I1495J-145D01*
G03X1422036Y1574650I1502J0D01*
G01X1422037Y1574640D01*
Y1573918D01*
G03X1422096Y1573776I200J0D01*
G01X1422135Y1573737D01*
G02X1422194Y1573596I-141J-142D01*
G01Y1573411D01*
G03X1422695Y1572910I501J0D01*
G01X1422880D01*
G02X1423021Y1572851I-1J-200D01*
G01X1423055Y1572817D01*
G02X1423114Y1572675I-141J-142D01*
G01Y1568754D01*
G03X1423173Y1568612I200J0D01*
G01X1423309Y1568476D01*
Y1568452D01*
X1423711Y1568050D01*
G03X1423853Y1567991I142J141D01*
G01X1424130D01*
X1424160Y1567981D01*
G03X1424621Y1567909I459J1430D01*
G03X1425082Y1567981I2J1502D01*
G01X1425112Y1567991D01*
X1429290D01*
G02X1429432Y1567932I0J-200D01*
G01X1431419Y1565945D01*
G02X1431478Y1565803I-141J-142D01*
G01Y1562971D01*
G02X1431419Y1562829I-200J0D01*
G01X1430938Y1562348D01*
G02X1430796Y1562289I-142J141D01*
G01X1424529D01*
G02X1424387Y1562348I0J200D01*
G01X1423863Y1562872D01*
G03X1423721Y1562931I-142J-141D01*
G01X1421657D01*
X1421637Y1562935D01*
G03X1421382Y1562962I-254J-1184D01*
G01X1419437D01*
G03X1419182Y1562935I-1J-1211D01*
G01X1419162Y1562931D01*
X1416457D01*
G02X1416316Y1562990I1J200D01*
G01X1416186Y1563120D01*
G03X1415329Y1563474I-856J-857D01*
G01X1412100D01*
G03X1411636Y1563382I-1J-1211D01*
G01X1410902Y1563078D01*
G03X1410691Y1562965I464J-1119D01*
G02X1410579Y1562931I-112J166D01*
G01X1406323D01*
G02X1406158Y1563017I-1J200D01*
G01X1405943Y1563328D01*
X1405930Y1563424D01*
X1405948Y1563471D01*
G03X1406024Y1563895I-1135J422D01*
G01Y1564555D01*
G02X1406083Y1564697I200J0D01*
G01X1407621Y1566234D01*
G02X1407762Y1566293I142J-141D01*
G01X1411461D01*
G02X1411603Y1566234I0J-200D01*
G01X1412368Y1565469D01*
G03X1412510Y1565410I142J141D01*
G01X1414518D01*
X1414567Y1565397D01*
X1414590Y1565384D01*
G03X1415184Y1565228I595J1056D01*
G01X1418474D01*
X1418506Y1565217D01*
G03X1418673Y1565188I168J473D01*
G01X1419873D01*
G03X1420374Y1565690I0J501D01*
G01Y1565770D01*
G02X1420433Y1565911I200J-1D01*
G01X1420484Y1565962D01*
G03X1420543Y1566104I-141J142D01*
G01Y1566246D01*
G02X1420602Y1566387I200J-1D01*
G01X1421056Y1566841D01*
G03X1421410Y1567698I-857J856D01*
G01Y1569924D01*
G03X1421056Y1570781I-1211J1D01*
G01X1420283Y1571553D01*
G02X1420224Y1571695I141J142D01*
G01Y1571750D01*
G03X1419723Y1572252I-502J0D01*
G01X1419523D01*
G02X1419382Y1572310I0J200D01*
G01X1418463Y1573229D01*
G02X1418404Y1573371I141J142D01*
G01Y1580995D01*
G02X1418463Y1581137I200J0D01*
G01X1418464Y1581138D01*
G02X1418606Y1581197I142J-141D01*
G37*
G36*
G01X1414510Y460362D02*
G03I-510J0D01*
G37*
G36*
G01X1416835Y680553D02*
X1418000D01*
X1418612D01*
X1418745Y680420D01*
Y676116D01*
X1418128Y675499D01*
X1417275Y674646D01*
X1415228D01*
X1415057Y674817D01*
Y676258D01*
X1416731Y677932D01*
Y678325D01*
Y680449D01*
X1416835Y680553D01*
G37*
G36*
G01X1410395Y1483295D02*
G03I-519J0D01*
G37*
G36*
G01X1412305Y1485895D02*
G03I-519J0D01*
G37*
G36*
G01X1410395Y1488495D02*
G03I-519J0D01*
G37*
G36*
G01X1417075Y1519682D02*
G03I-519J0D01*
G37*
G36*
G01X1414475Y1517772D02*
G03I-519J0D01*
G37*
G36*
G01Y1512992D02*
G03I-519J0D01*
G37*
G36*
G01X1417075Y1511082D02*
G03I-519J0D01*
G37*
G36*
G01X1419675Y1512992D02*
G03I-519J0D01*
G37*
G36*
G01Y1517772D02*
G03I-519J0D01*
G37*
G36*
G01X1417075Y1533082D02*
G03I-519J0D01*
G37*
G36*
G01X1414475Y1531172D02*
G03I-519J0D01*
G37*
G36*
G01Y1526392D02*
G03I-519J0D01*
G37*
G36*
G01X1417075Y1524482D02*
G03I-519J0D01*
G37*
G36*
G01X1419675Y1526392D02*
G03I-519J0D01*
G37*
G36*
G01Y1531172D02*
G03I-519J0D01*
G37*
G36*
G01X1414973Y1553883D02*
X1416477D01*
G02X1416619Y1553824I0J-200D01*
G01X1417050Y1553393D01*
G02X1417109Y1553251I-141J-142D01*
G01Y1552245D01*
G03X1417168Y1552103I200J0D01*
G01X1417625Y1551646D01*
G02X1417684Y1551505I-141J-142D01*
G01Y1551250D01*
G03X1418185Y1550748I502J0D01*
G01X1418429D01*
X1418466Y1550733D01*
G03X1418935Y1550638I470J1117D01*
G03X1419404Y1550733I-1J1212D01*
G01X1419441Y1550748D01*
X1419685D01*
G03X1420169Y1551118I0J502D01*
G01X1420187Y1551183D01*
X1420294Y1551265D01*
X1420776D01*
X1420883Y1551183D01*
X1420901Y1551118D01*
G03X1421385Y1550748I484J132D01*
G01X1421629D01*
X1421666Y1550733D01*
G03X1422135Y1550638I470J1117D01*
G03X1422604Y1550733I-1J1212D01*
G01X1422641Y1550748D01*
X1422885D01*
G03X1422918Y1550750I-14J501D01*
G01X1423020D01*
X1423042Y1550772D01*
X1423078Y1550787D01*
G03X1423348Y1551057I-193J463D01*
G01X1423363Y1551093D01*
X1424331Y1552061D01*
G02X1424473Y1552120I142J-141D01*
G01X1426353D01*
G02X1426477Y1552077I0J-200D01*
G03X1427713Y1551650I1236J1575D01*
G03X1428849Y1552004I-1J2002D01*
G02X1429077I114J-165D01*
G03X1430213Y1551650I1137J1648D01*
G03X1431449Y1552077I0J2002D01*
G02X1431573Y1552120I124J-157D01*
G01X1432729D01*
G02X1432870Y1552061I-1J-200D01*
G01X1433328Y1551603D01*
G03X1434185Y1551248I857J857D01*
G01X1436770D01*
G02X1436970Y1551048I0J-200D01*
G01Y1549601D01*
G02X1436877Y1549432I-200J0D01*
G03X1436054Y1548584I1333J-2117D01*
G02X1435881Y1548486I-172J102D01*
G01X1435537D01*
G02X1435364Y1548584I-1J200D01*
G03X1433209Y1549816I-2155J-1269D01*
G03Y1544812I0J-2502D01*
G03X1434483Y1545161I-1J2502D01*
G02X1434727Y1545130I102J-172D01*
G01X1436214Y1543643D01*
X1436241Y1543592D01*
X1436247Y1543562D01*
G03X1436318Y1543331I1188J239D01*
G01X1436334Y1543294D01*
Y1543065D01*
G02X1436134Y1542865I-200J0D01*
G01X1430282D01*
G02X1430099Y1542985I0J200D01*
G03X1425515I-2292J-1004D01*
G02X1425332Y1542865I-183J80D01*
G01X1425282D01*
G02X1425099Y1542985I0J200D01*
G03X1422807Y1544483I-2292J-1004D01*
G03X1420305Y1541981I0J-2502D01*
G03X1420374Y1541397I2502J0D01*
G01X1420387Y1541345D01*
X1420359Y1541246D01*
X1418628Y1539516D01*
G03X1418460Y1539305I858J-856D01*
G02X1418291Y1539212I-169J107D01*
G01X1416072D01*
G02X1415930Y1539270I-1J200D01*
G01X1415821Y1539380D01*
G02X1415762Y1539521I141J142D01*
G01Y1541186D01*
G03X1415703Y1541328I-200J0D01*
G01X1414625Y1542406D01*
G02X1414566Y1542548I141J142D01*
G01Y1553476D01*
G02X1414625Y1553618I200J0D01*
G01X1414831Y1553824D01*
G02X1414973Y1553883I142J-141D01*
G37*
G36*
G01X1422920Y1583553D02*
X1427951D01*
G02X1428098Y1583488I-1J-200D01*
G03X1429566Y1582842I1473J1356D01*
G01X1429606D01*
X1429678Y1582812D01*
X1430162Y1582328D01*
G02X1430200Y1582097I-141J-142D01*
G03X1429987Y1581199I1789J-899D01*
G03X1430244Y1580217I2002J-1D01*
G01X1430257Y1580194D01*
X1430270Y1580145D01*
Y1579833D01*
G03X1430329Y1579691I200J0D01*
G01X1431904Y1578116D01*
G02X1431963Y1577974I-141J-142D01*
G01Y1570273D01*
G02X1431904Y1570131I-200J0D01*
G01X1430419Y1568646D01*
G02X1430277Y1568587I-142J141D01*
G01X1430276D01*
G02X1430135Y1568646I1J200D01*
G01X1429846Y1568934D01*
G03X1429705Y1568992I-141J-142D01*
G01X1424292D01*
G02X1424150Y1569051I0J200D01*
G01X1424146Y1569055D01*
X1424116Y1569129D01*
Y1573090D01*
G03X1424057Y1573231I-200J-1D01*
G01X1423097Y1574191D01*
G02X1423038Y1574333I141J142D01*
G01Y1581300D01*
G03X1422980Y1581441I-200J0D01*
G01X1422549Y1581873D01*
G02X1422490Y1582014I141J142D01*
G01Y1583123D01*
G02X1422549Y1583265I200J0D01*
G01X1422778Y1583494D01*
G02X1422920Y1583553I142J-141D01*
G37*
G36*
G01X1434447Y-34648D02*
G03I-630J0D01*
G37*
G36*
G01Y-25374D02*
G03I-630J0D01*
G37*
G36*
G01Y-15374D02*
G03I-630J0D01*
G37*
G36*
G01Y-4648D02*
G03I-630J0D01*
G37*
G36*
G01Y5352D02*
G03I-630J0D01*
G37*
G36*
G01Y14626D02*
G03I-630J0D01*
G37*
G36*
G01X1428483Y60409D02*
G03I-510J0D01*
G37*
G36*
G01X1425079Y710137D02*
X1424788Y710428D01*
Y724622D01*
X1424910Y724744D01*
X1442627D01*
X1442857Y724514D01*
Y715607D01*
X1445299Y713165D01*
X1445415Y713049D01*
X1447973D01*
X1448257Y712765D01*
Y710965D01*
X1447429Y710137D01*
X1425079D01*
G37*
G36*
G01X1475256Y755265D02*
X1476257Y754264D01*
Y749042D01*
X1475821Y748606D01*
X1452766D01*
X1450757Y746597D01*
Y739097D01*
X1448925Y737265D01*
X1425257D01*
X1424257Y738265D01*
Y743265D01*
X1424757Y743765D01*
X1442757D01*
X1444757Y745765D01*
Y753265D01*
X1446757Y755265D01*
X1475256D01*
G37*
G36*
G01X1438279Y1517280D02*
G03I-519J0D01*
G37*
G36*
G01X1435679Y1519190D02*
G03I-519J0D01*
G37*
G36*
G01X1433079Y1517280D02*
G03I-519J0D01*
G37*
G36*
G01Y1512500D02*
G03I-519J0D01*
G37*
G36*
G01X1435679Y1510590D02*
G03I-519J0D01*
G37*
G36*
G01X1438279Y1512500D02*
G03I-519J0D01*
G37*
G36*
G01X1433079Y1534300D02*
G03I-519J0D01*
G37*
G36*
G01X1435679Y1532490D02*
G03I-519J0D01*
G37*
G36*
G01X1438279Y1534300D02*
G03I-519J0D01*
G37*
G36*
G01X1435679Y1540990D02*
G03I-519J0D01*
G37*
G36*
G01X1433079Y1539080D02*
G03I-519J0D01*
G37*
G36*
G01X1438279D02*
G03I-519J0D01*
G37*
G36*
G01X1437450Y1554277D02*
G03I-510J0D01*
G37*
G36*
G01X1435364Y1583581D02*
X1443025D01*
X1443116Y1583529D01*
X1443143Y1583483D01*
G03X1443327Y1583247I1040J621D01*
G01X1443466Y1583109D01*
G02X1443524Y1582967I-142J-141D01*
G01Y1574088D01*
G02X1443466Y1573947I-200J0D01*
G01X1443245Y1573726D01*
G02X1443103Y1573667I-142J141D01*
G01X1434858D01*
G02X1434716Y1573726I0J200D01*
G01X1434306Y1574136D01*
G02X1434247Y1574278I141J142D01*
G01Y1582527D01*
G02X1434306Y1582669I200J0D01*
G01X1435111Y1583474D01*
X1435142Y1583489D01*
G03X1435262Y1583553I-646J1356D01*
G02X1435364Y1583581I102J-172D01*
G37*
G36*
G01X1434489Y1655655D02*
G03I-510J0D01*
G37*
G36*
G01X1446495Y116953D02*
G03I-510J0D01*
G37*
G36*
G01X1451863Y116158D02*
G03I-510J0D01*
G37*
G36*
G01X1441900Y163944D02*
G03I-510J0D01*
G37*
G36*
G01X1443503Y176204D02*
G03I-510J0D01*
G37*
G36*
G01X1503357Y596668D02*
X1446182D01*
X1444492Y598358D01*
X1440972D01*
X1439748Y599582D01*
Y623594D01*
X1440365Y624211D01*
X1507623D01*
X1508597Y623237D01*
Y597668D01*
X1507597Y596668D01*
X1503357D01*
G37*
G36*
G01X1449435Y713133D02*
X1450600D01*
X1451212D01*
X1451345Y713000D01*
Y708696D01*
X1450728Y708079D01*
X1449875Y707226D01*
X1447828D01*
X1447657Y707397D01*
Y708838D01*
X1449331Y710512D01*
Y710905D01*
Y713029D01*
X1449435Y713133D01*
G37*
G36*
G01X1447927Y1488495D02*
G03I-519J0D01*
G37*
G36*
G01X1446017Y1485895D02*
G03I-519J0D01*
G37*
G36*
G01X1447927Y1483295D02*
G03I-519J0D01*
G37*
G36*
G01X1452707D02*
G03I-519J0D01*
G37*
G36*
G01Y1488495D02*
G03I-519J0D01*
G37*
G36*
G01X1441227Y1498195D02*
G03I-519J0D01*
G37*
G36*
G01X1439317Y1495595D02*
G03I-519J0D01*
G37*
G36*
G01X1441227Y1492995D02*
G03I-519J0D01*
G37*
G36*
G01X1446007D02*
G03I-519J0D01*
G37*
G36*
G01X1447917Y1495595D02*
G03I-519J0D01*
G37*
G36*
G01X1446007Y1498195D02*
G03I-519J0D01*
G37*
G36*
G01X1459272Y1601530D02*
X1525887D01*
G02X1526029Y1601471I0J-200D01*
G01X1529218Y1598282D01*
X1529248Y1598211D01*
Y1598171D01*
G03X1531731Y1595688I2502J19D01*
G01X1531771D01*
X1531842Y1595658D01*
X1535371Y1592129D01*
G02X1535430Y1591987I-141J-142D01*
G01Y1591583D01*
G02X1535372Y1591441I-200J-1D01*
G01X1534844Y1590913D01*
G02X1534702Y1590854I-142J141D01*
G01X1533210D01*
G02X1533068Y1590913I0J200D01*
G01X1529646Y1594335D01*
G03X1529504Y1594394I-142J-141D01*
G01X1454788D01*
X1454677Y1594485D01*
X1454663Y1594556D01*
G03X1452207Y1596581I-2456J-477D01*
G03X1449705Y1594079I0J-2502D01*
G03X1451741Y1591621I2502J0D01*
G01X1451812Y1591607D01*
X1451904Y1591497D01*
Y1590420D01*
G02X1451845Y1590279I-200J1D01*
G01X1451818Y1590252D01*
X1451745Y1590222D01*
X1446909D01*
G02X1446767Y1590281I0J200D01*
G01X1446357Y1590691D01*
G02X1446298Y1590833I141J142D01*
G01Y1595371D01*
G02X1446421Y1595556I200J0D01*
G01X1452658Y1598140D01*
X1452760Y1598128D01*
X1452803Y1598097D01*
G03X1454274Y1597619I1471J2024D01*
G03X1456703Y1599522I0J2502D01*
G01X1456720Y1599590D01*
X1456828Y1599674D01*
X1457250D01*
G03X1457392Y1599733I0J200D01*
G01X1459130Y1601471D01*
G02X1459272Y1601530I142J-141D01*
G37*
G36*
G01X1459687Y163796D02*
G03I-510J0D01*
G37*
G36*
G01X1460192Y450372D02*
G03I-510J0D01*
G37*
G36*
G01X1457716Y763524D02*
X1487023D01*
X1488691Y761856D01*
Y756856D01*
X1490082Y755465D01*
X1508557D01*
X1509691Y754331D01*
Y749456D01*
X1508891Y748656D01*
X1485191D01*
X1479691D01*
X1478641Y749706D01*
Y755206D01*
X1476582Y757265D01*
X1457757D01*
X1457391Y757631D01*
Y763199D01*
X1457716Y763524D01*
G37*
G36*
G01X1454617Y1485895D02*
G03I-519J0D01*
G37*
G36*
G01X1459417Y1505295D02*
G03I-519J0D01*
G37*
G36*
G01X1461327Y1502695D02*
G03I-519J0D01*
G37*
G36*
G01X1466107D02*
G03I-519J0D01*
G37*
G36*
G01X1468017Y1505295D02*
G03I-519J0D01*
G37*
G36*
G01X1468027Y1498195D02*
G03I-519J0D01*
G37*
G36*
G01X1466117Y1495595D02*
G03I-519J0D01*
G37*
G36*
G01X1468027Y1492995D02*
G03I-519J0D01*
G37*
G36*
G01X1461327Y1507895D02*
G03I-519J0D01*
G37*
G36*
G01X1466107D02*
G03I-519J0D01*
G37*
G36*
G01X1472382Y1560011D02*
X1474008D01*
G02X1474073Y1560000I0J-200D01*
G01X1474987Y1559686D01*
G03X1475393Y1559607I487J1420D01*
G01X1475432Y1559605D01*
X1475501Y1559573D01*
X1475717Y1559345D01*
G02X1475772Y1559207I-145J-138D01*
G01Y1557099D01*
G02X1475717Y1556961I-200J0D01*
G01X1475501Y1556733D01*
X1475432Y1556701D01*
X1475393Y1556699D01*
G03X1475078Y1556648I81J-1499D01*
G01X1473856Y1556313D01*
G02X1473803Y1556306I-52J193D01*
G01X1472116D01*
G02X1472046Y1556319I1J200D01*
G01X1471275Y1556607D01*
G03X1470750Y1556702I-526J-1407D01*
G03X1470353Y1556648I2J-1502D01*
G01X1469132Y1556313D01*
G02X1469079Y1556306I-52J193D01*
G01X1467392D01*
G02X1467322Y1556319I1J200D01*
G01X1466551Y1556607D01*
G03X1466026Y1556702I-526J-1407D01*
G03X1465629Y1556648I2J-1502D01*
G01X1464407Y1556313D01*
G02X1464354Y1556306I-52J193D01*
G01X1462667D01*
G02X1462597Y1556319I1J200D01*
G01X1461826Y1556607D01*
G03X1461301Y1556702I-526J-1407D01*
G03X1460904Y1556648I2J-1502D01*
G01X1459683Y1556313D01*
G02X1459630Y1556306I-52J193D01*
G01X1458227D01*
G02X1458085Y1556365I0J200D01*
G01X1457923Y1556527D01*
G02X1457864Y1556669I141J142D01*
G01Y1559626D01*
G02X1457993Y1559813I200J0D01*
G01X1458477Y1559998D01*
G02X1458549Y1560011I71J-187D01*
G01X1459834D01*
G02X1459899Y1560000I0J-200D01*
G01X1460813Y1559686D01*
G03X1461301Y1559604I489J1420D01*
G03X1461723Y1559665I-2J1502D01*
G01X1462877Y1560003D01*
G02X1462933Y1560011I56J-192D01*
G01X1464559D01*
G02X1464624Y1560000I0J-200D01*
G01X1465538Y1559686D01*
G03X1466026Y1559604I489J1420D01*
G03X1466448Y1559665I-2J1502D01*
G01X1467602Y1560003D01*
G02X1467658Y1560011I56J-192D01*
G01X1469283D01*
G02X1469348Y1560000I0J-200D01*
G01X1470262Y1559686D01*
G03X1470750Y1559604I489J1420D01*
G03X1471172Y1559665I-2J1502D01*
G01X1472326Y1560003D01*
G02X1472382Y1560011I56J-192D01*
G37*
G36*
G01X1460967Y1685160D02*
G03I-510J0D01*
G37*
G36*
G01X1468905Y487582D02*
G03I-510J0D01*
G37*
G36*
G01X1480125Y548950D02*
X1500303D01*
X1501667Y550314D01*
Y566567D01*
X1496554Y571680D01*
X1479755D01*
X1478664Y570589D01*
Y550411D01*
X1480125Y548950D01*
G37*
G36*
G01X1477635Y561477D02*
Y580159D01*
X1474904Y582890D01*
X1469179D01*
X1468679Y582390D01*
Y569252D01*
X1469088Y568843D01*
X1472544D01*
X1474746Y566641D01*
Y564721D01*
X1471725Y561700D01*
Y560977D01*
X1472225Y560477D01*
X1476635D01*
X1477635Y561477D01*
G37*
G36*
G01X1474727Y1488495D02*
G03I-519J0D01*
G37*
G36*
G01X1472817Y1485895D02*
G03I-519J0D01*
G37*
G36*
G01X1474727Y1483295D02*
G03I-519J0D01*
G37*
G36*
G01X1479507D02*
G03I-519J0D01*
G37*
G36*
G01X1481417Y1485895D02*
G03I-519J0D01*
G37*
G36*
G01X1479507Y1488495D02*
G03I-519J0D01*
G37*
G36*
G01X1472807Y1492995D02*
G03I-519J0D01*
G37*
G36*
G01X1474717Y1495595D02*
G03I-519J0D01*
G37*
G36*
G01X1472807Y1498195D02*
G03I-519J0D01*
G37*
G36*
G01X1482234Y1560011D02*
X1483456D01*
G02X1483521Y1560000I0J-200D01*
G01X1484435Y1559686D01*
G03X1484877Y1559605I489J1420D01*
G01X1484916Y1559604D01*
X1484987Y1559573D01*
X1485208Y1559345D01*
G02X1485264Y1559205I-144J-139D01*
G01Y1557101D01*
G02X1485208Y1556961I-200J-1D01*
G01X1484987Y1556733D01*
X1484916Y1556702D01*
X1484877Y1556701D01*
G03X1484526Y1556648I47J-1501D01*
G01X1483305Y1556313D01*
G02X1483252Y1556306I-52J193D01*
G01X1481900D01*
X1481827Y1556336D01*
X1481816Y1556346D01*
Y1559594D01*
G02X1481875Y1559735I200J-1D01*
G01X1482092Y1559952D01*
G02X1482234Y1560011I142J-141D01*
G37*
G36*
G01X1477182D02*
X1478732D01*
G02X1478797Y1560000I0J-200D01*
G01X1479711Y1559686D01*
G03X1480199Y1559604I489J1420D01*
G03X1480370Y1559614I-2J1502D01*
G01X1480413Y1559619D01*
X1480493Y1559594D01*
X1480748Y1559366D01*
G02X1480815Y1559217I-133J-149D01*
G01Y1557089D01*
G02X1480748Y1556940I-200J0D01*
G01X1480493Y1556712D01*
X1480413Y1556687D01*
X1480370Y1556692D01*
G03X1480199Y1556702I-173J-1492D01*
G03X1479802Y1556648I2J-1502D01*
G01X1478580Y1556313D01*
G02X1478527Y1556306I-52J193D01*
G01X1477138D01*
G02X1476996Y1556365I0J200D01*
G01X1476832Y1556529D01*
G02X1476773Y1556671I141J142D01*
G01Y1559602D01*
G02X1476832Y1559744I200J0D01*
G01X1477040Y1559952D01*
G02X1477182Y1560011I142J-141D01*
G37*
G36*
G01X1492747Y123842D02*
G03I-510J0D01*
G37*
G36*
G01X1491431Y763588D02*
X1520231D01*
X1522131Y761688D01*
Y756688D01*
X1523331Y755488D01*
X1541098D01*
X1541857Y754729D01*
Y748738D01*
X1541716Y748597D01*
X1513357D01*
X1512081Y749873D01*
Y755038D01*
X1509822Y757297D01*
X1491457D01*
X1490831Y757923D01*
Y762988D01*
X1491431Y763588D01*
G37*
G36*
G01X1493329Y828513D02*
G03I-656J0D01*
G37*
G36*
G01X1486217Y1505295D02*
G03I-519J0D01*
G37*
G36*
G01X1488127Y1502695D02*
G03I-519J0D01*
G37*
G36*
G01X1492907D02*
G03I-519J0D01*
G37*
G36*
G01X1494817Y1505295D02*
G03I-519J0D01*
G37*
G36*
G01X1494827Y1498195D02*
G03I-519J0D01*
G37*
G36*
G01X1492917Y1495595D02*
G03I-519J0D01*
G37*
G36*
G01X1494827Y1492995D02*
G03I-519J0D01*
G37*
G36*
G01X1488127Y1507895D02*
G03I-519J0D01*
G37*
G36*
G01X1492907D02*
G03I-519J0D01*
G37*
G36*
G01X1496001Y1560010D02*
X1496953D01*
G02X1497095Y1559951I0J-200D01*
G01X1497353Y1559693D01*
G02X1497412Y1559552I-141J-142D01*
G01Y1558527D01*
G03X1497470Y1558386I200J0D01*
G01X1497476Y1558380D01*
X1497506Y1558307D01*
Y1558276D01*
X1497843Y1557939D01*
X1497916Y1557909D01*
X1497947D01*
X1498239Y1557617D01*
G03X1498380Y1557558I142J141D01*
G01X1499504D01*
G02X1499704Y1557358I0J-200D01*
G01Y1557090D01*
G02X1499637Y1556941I-200J0D01*
G01X1499383Y1556714D01*
X1499303Y1556688D01*
X1499260Y1556693D01*
G03X1499097Y1556702I-164J-1493D01*
G03X1498700Y1556648I2J-1502D01*
G01X1497478Y1556313D01*
G02X1497425Y1556306I-52J193D01*
G01X1495738D01*
G02X1495668Y1556319I1J200D01*
G01X1494897Y1556607D01*
G03X1494372Y1556702I-526J-1407D01*
G03X1493975Y1556648I2J-1502D01*
G01X1492754Y1556313D01*
G02X1492701Y1556306I-52J193D01*
G01X1491014D01*
G02X1490944Y1556319I1J200D01*
G01X1490173Y1556607D01*
G03X1489648Y1556702I-526J-1407D01*
G03X1489251Y1556648I2J-1502D01*
G01X1488029Y1556313D01*
G02X1487976Y1556306I-52J193D01*
G01X1486582D01*
G02X1486440Y1556365I0J200D01*
G01X1486325Y1556480D01*
G02X1486266Y1556622I141J142D01*
G01Y1559271D01*
G02X1486325Y1559413I200J0D01*
G01X1486863Y1559951D01*
G02X1487005Y1560010I142J-141D01*
G01X1488184D01*
G02X1488249Y1559999I0J-200D01*
G01X1489160Y1559686D01*
G03X1489648Y1559604I489J1420D01*
G03X1490070Y1559665I-2J1502D01*
G01X1491221Y1560002D01*
G02X1491277Y1560010I56J-192D01*
G01X1492908D01*
G02X1492973Y1559999I0J-200D01*
G01X1493884Y1559686D01*
G03X1494372Y1559604I489J1420D01*
G03X1494794Y1559665I-2J1502D01*
G01X1495945Y1560002D01*
G02X1496001Y1560010I56J-192D01*
G37*
G36*
G01X1484159Y1738118D02*
X1783945D01*
G02X1784130Y1737994I0J-200D01*
G01X1784293Y1737594D01*
X1784269Y1737476D01*
X1784225Y1737433D01*
G03X1783023Y1736185I22078J-22467D01*
G02X1782875Y1736120I-148J135D01*
G01X1617804D01*
G02X1617775Y1736122I-1J200D01*
G01X1617732Y1736129D01*
X1617730D01*
G03X1617132Y1736222I-604J-1917D01*
G01X1617120D01*
G03X1616522Y1736129I6J-2010D01*
G01X1616492Y1736120D01*
X1602056D01*
G02X1602027Y1736122I-1J200D01*
G01X1601984Y1736129D01*
X1601982D01*
G03X1601384Y1736222I-604J-1917D01*
G01X1601372D01*
G03X1600774Y1736129I6J-2010D01*
G01X1600744Y1736120D01*
X1586308D01*
G02X1586279Y1736122I-1J200D01*
G01X1586236Y1736129D01*
X1586234D01*
G03X1585636Y1736222I-604J-1917D01*
G01X1585624D01*
G03X1585026Y1736129I6J-2010D01*
G01X1584996Y1736120D01*
X1571727D01*
X1571675Y1736135D01*
X1571651Y1736149D01*
G03X1571390Y1736222I-261J-428D01*
G01X1568374D01*
G03X1568113Y1736149I0J-501D01*
G01X1568089Y1736135D01*
X1568037Y1736120D01*
X1550874D01*
G02X1550845Y1736122I-1J200D01*
G01X1550802Y1736129D01*
X1550800D01*
G03X1550202Y1736222I-604J-1917D01*
G01X1550190D01*
G03X1549592Y1736129I6J-2010D01*
G01X1549562Y1736120D01*
X1535126D01*
G02X1535097Y1736122I-1J200D01*
G01X1535054Y1736129D01*
X1535052D01*
G03X1534454Y1736222I-604J-1917D01*
G01X1534442D01*
G03X1533844Y1736129I6J-2010D01*
G01X1533814Y1736120D01*
X1519378D01*
G02X1519349Y1736122I-1J200D01*
G01X1519306Y1736129D01*
X1519304D01*
G03X1518706Y1736222I-604J-1917D01*
G01X1518694D01*
G03X1518096Y1736129I6J-2010D01*
G01X1518066Y1736120D01*
X1504797D01*
X1504745Y1736135D01*
X1504721Y1736149D01*
G03X1504460Y1736222I-261J-428D01*
G01X1501444D01*
G03X1501183Y1736149I0J-501D01*
G01X1501159Y1736135D01*
X1501107Y1736120D01*
X1485229D01*
G02X1485081Y1736185I0J200D01*
G03X1483879Y1737433I-23280J-21219D01*
G01X1483835Y1737476D01*
X1483811Y1737594D01*
X1483974Y1737994D01*
G02X1484159Y1738118I185J-76D01*
G37*
G36*
G01X1499963Y803513D02*
G03I-720J0D01*
G37*
G36*
G01X1501994Y825147D02*
G03I-656J0D01*
G37*
G36*
G01X1501527Y1488495D02*
G03I-519J0D01*
G37*
G36*
G01X1499617Y1485895D02*
G03I-519J0D01*
G37*
G36*
G01X1501527Y1483295D02*
G03I-519J0D01*
G37*
G36*
G01X1506307D02*
G03I-519J0D01*
G37*
G36*
G01X1508217Y1485895D02*
G03I-519J0D01*
G37*
G36*
G01X1506307Y1488495D02*
G03I-519J0D01*
G37*
G36*
G01X1499607Y1492995D02*
G03I-519J0D01*
G37*
G36*
G01X1501517Y1495595D02*
G03I-519J0D01*
G37*
G36*
G01X1499607Y1498195D02*
G03I-519J0D01*
G37*
G36*
G01X1513017Y1505295D02*
G03I-519J0D01*
G37*
G36*
G01X1505453Y1560011D02*
X1506402D01*
G02X1506544Y1559952I0J-200D01*
G01X1506857Y1559639D01*
G02X1506916Y1559498I-141J-142D01*
G01Y1556809D01*
G02X1506857Y1556668I-200J1D01*
G01X1506554Y1556365D01*
G02X1506412Y1556306I-142J141D01*
G01X1505187D01*
G02X1505117Y1556319I1J200D01*
G01X1504346Y1556607D01*
G03X1503821Y1556702I-526J-1407D01*
G03X1503560Y1556679I0J-1492D01*
G01X1503512Y1556670D01*
X1503419Y1556699D01*
X1503341Y1556777D01*
G02X1503282Y1556918I141J142D01*
G01Y1559382D01*
G02X1503341Y1559523I200J-1D01*
G01X1503424Y1559606D01*
X1503515Y1559635D01*
X1503565Y1559627D01*
G03X1503821Y1559604I262J1478D01*
G03X1504243Y1559665I-2J1502D01*
G01X1505397Y1560003D01*
G02X1505453Y1560011I56J-192D01*
G37*
G36*
G01X1510177D02*
X1511428D01*
G02X1511628Y1559811I0J-200D01*
G01Y1556382D01*
X1511598Y1556309D01*
X1511595Y1556306D01*
X1509911D01*
G02X1509841Y1556319I1J200D01*
G01X1509070Y1556607D01*
G03X1508545Y1556702I-526J-1407D01*
G03X1508268Y1556676I1J-1502D01*
G01X1508219Y1556666D01*
X1508124Y1556696D01*
X1507976Y1556844D01*
G02X1507917Y1556986I141J142D01*
G01Y1559218D01*
G02X1507984Y1559368I200J1D01*
G01X1508240Y1559595D01*
X1508322Y1559620D01*
X1508365Y1559615D01*
G03X1508545Y1559604I181J1491D01*
G03X1508967Y1559665I-2J1502D01*
G01X1510121Y1560003D01*
G02X1510177Y1560011I56J-192D01*
G37*
G36*
G01X1500258Y1559873D02*
X1502055D01*
G02X1502197Y1559814I0J-200D01*
G01X1502222Y1559789D01*
G02X1502281Y1559647I-141J-142D01*
G01Y1556865D01*
G02X1502222Y1556723I-200J0D01*
G01X1501946Y1556447D01*
G02X1501804Y1556388I-142J141D01*
G01X1501074D01*
G02X1500932Y1556447I0J200D01*
G01X1500764Y1556615D01*
G02X1500705Y1556757I141J142D01*
G01Y1558154D01*
G03X1500646Y1558296I-200J0D01*
G01X1500441Y1558501D01*
G03X1500299Y1558560I-142J-141D01*
G01X1498795D01*
G02X1498653Y1558619I0J200D01*
G01X1498472Y1558800D01*
G02X1498413Y1558942I141J142D01*
G01Y1559384D01*
G02X1498472Y1559526I200J0D01*
G01X1498580Y1559634D01*
X1498681Y1559662D01*
X1498733Y1559649D01*
G03X1499097Y1559604I365J1457D01*
G03X1499519Y1559665I-2J1502D01*
G01X1500201Y1559865D01*
G02X1500258Y1559873I56J-192D01*
G37*
G36*
G01X1539814Y1620647D02*
Y1604493D01*
G02X1539755Y1604351I-200J0D01*
G01X1539013Y1603609D01*
G02X1538871Y1603550I-142J141D01*
G01X1507917D01*
G02X1507775Y1603609I0J200D01*
G01X1505883Y1605501D01*
G02X1505824Y1605643I141J142D01*
G01Y1620177D01*
G02X1505883Y1620319I200J0D01*
G01X1506625Y1621061D01*
G02X1506767Y1621120I142J-141D01*
G01X1539341D01*
G02X1539483Y1621061I0J-200D01*
G01X1539755Y1620789D01*
G02X1539814Y1620647I-141J-142D01*
G37*
G36*
G01X1523427Y119912D02*
G03I-510J0D01*
G37*
G36*
G01X1546977Y696639D02*
X1556436D01*
Y696623D01*
X1557736D01*
G02X1557936Y696423I0J-200D01*
G01X1564536D01*
G02X1564736Y696223I0J-200D01*
G01Y688646D01*
X1564715Y688625D01*
X1559134D01*
X1558597Y688088D01*
Y684758D01*
X1557270Y683430D01*
G03X1557211Y683288I141J-142D01*
G01Y674750D01*
X1558471Y673490D01*
X1558480D01*
X1560400Y671570D01*
X1575390D01*
X1576257Y670703D01*
Y664680D01*
G03X1576316Y664538I200J0D01*
G01X1577935Y662919D01*
G03X1578077Y662860I142J141D01*
G01X1589206D01*
Y662854D01*
X1590506D01*
G02X1590706Y662654I0J-200D01*
G01X1597306D01*
G02X1597506Y662454I0J-200D01*
G01Y655056D01*
G02X1597306Y654856I-200J0D01*
G01X1591945D01*
X1591367Y654278D01*
Y649708D01*
X1589816Y648156D01*
G03X1589757Y648014I141J-142D01*
G01Y642310D01*
G03X1589816Y642168I200J0D01*
G01X1593328Y638656D01*
G03X1593470Y638597I142J141D01*
G01X1610613D01*
G03X1610755Y638656I0J200D01*
G01X1612187Y640088D01*
G03X1612246Y640230I-141J142D01*
G01Y643606D01*
X1612276Y643680D01*
X1612305Y643708D01*
X1612498Y643901D01*
G02X1612640Y643960I142J-141D01*
G01X1630322D01*
X1630396Y643930D01*
X1630424Y643901D01*
X1630447Y643878D01*
X1630476Y643850D01*
X1630506Y643776D01*
Y635758D01*
G02X1630306Y635558I-200J0D01*
G01X1624817D01*
X1624343Y635084D01*
Y631342D01*
X1622320Y629319D01*
G03X1622261Y629177I141J-142D01*
G01Y624587D01*
X1620152Y622478D01*
X1582541D01*
X1578552Y618489D01*
Y602902D01*
X1575986Y600336D01*
X1518072D01*
X1515964Y602444D01*
Y658432D01*
X1525020Y667488D01*
X1538677D01*
X1546677Y675488D01*
Y696339D01*
X1546977Y696639D01*
G37*
G36*
G01X1551055Y838504D02*
G02I-13780J0D01*
G37*
G36*
G01Y1199922D02*
G02I-13780J0D01*
G37*
G36*
G01X1528327Y1488495D02*
G03I-519J0D01*
G37*
G36*
G01X1526417Y1485895D02*
G03I-519J0D01*
G37*
G36*
G01X1528327Y1483295D02*
G03I-519J0D01*
G37*
G36*
G01X1514927Y1502695D02*
G03I-519J0D01*
G37*
G36*
G01X1519707D02*
G03I-519J0D01*
G37*
G36*
G01X1521617Y1505295D02*
G03I-519J0D01*
G37*
G36*
G01X1526417D02*
G03I-519J0D01*
G37*
G36*
G01X1528327Y1502695D02*
G03I-519J0D01*
G37*
G36*
G01X1526407Y1498195D02*
G03I-519J0D01*
G37*
G36*
G01X1528317Y1495595D02*
G03I-519J0D01*
G37*
G36*
G01X1526407Y1492995D02*
G03I-519J0D01*
G37*
G36*
G01X1521627D02*
G03I-519J0D01*
G37*
G36*
G01X1519717Y1495595D02*
G03I-519J0D01*
G37*
G36*
G01X1521627Y1498195D02*
G03I-519J0D01*
G37*
G36*
G01X1514927Y1507895D02*
G03I-519J0D01*
G37*
G36*
G01X1519707D02*
G03I-519J0D01*
G37*
G36*
G01X1529075Y1560011D02*
X1530051D01*
G02X1530157Y1559981I1J-200D01*
G01X1530429Y1559810D01*
G02X1530465Y1559782I-104J-171D01*
G01X1530530Y1559717D01*
G02X1530589Y1559575I-141J-142D01*
G01Y1556591D01*
G02X1530530Y1556449I-200J0D01*
G01X1530446Y1556365D01*
G02X1530304Y1556306I-142J141D01*
G01X1528809D01*
G02X1528739Y1556319I1J200D01*
G01X1527968Y1556607D01*
G03X1527443Y1556702I-526J-1407D01*
G03X1527046Y1556648I2J-1502D01*
G01X1525825Y1556313D01*
G02X1525772Y1556306I-52J193D01*
G01X1524085D01*
G02X1524015Y1556319I1J200D01*
G01X1523244Y1556607D01*
G03X1522719Y1556702I-526J-1407D01*
G03X1522322Y1556648I2J-1502D01*
G01X1521100Y1556313D01*
G02X1521047Y1556306I-52J193D01*
G01X1519360D01*
G02X1519290Y1556319I1J200D01*
G01X1518519Y1556607D01*
G03X1517994Y1556702I-526J-1407D01*
G03X1517597Y1556648I2J-1502D01*
G01X1516376Y1556313D01*
G02X1516323Y1556306I-52J193D01*
G01X1514636D01*
G02X1514566Y1556319I1J200D01*
G01X1513795Y1556607D01*
G03X1513270Y1556702I-526J-1407D01*
G03X1513080Y1556689I7J-1502D01*
G01X1513037Y1556684D01*
X1512956Y1556709D01*
X1512698Y1556936D01*
G02X1512630Y1557086I132J150D01*
G01Y1559220D01*
G02X1512698Y1559370I200J0D01*
G01X1512956Y1559597D01*
X1513037Y1559622D01*
X1513080Y1559617D01*
G03X1513270Y1559604I197J1489D01*
G03X1513692Y1559665I-2J1502D01*
G01X1514846Y1560003D01*
G02X1514902Y1560011I56J-192D01*
G01X1516527D01*
G02X1516592Y1560000I0J-200D01*
G01X1517506Y1559686D01*
G03X1517994Y1559604I489J1420D01*
G03X1518416Y1559665I-2J1502D01*
G01X1519570Y1560003D01*
G02X1519626Y1560011I56J-192D01*
G01X1521252D01*
G02X1521317Y1560000I0J-200D01*
G01X1522231Y1559686D01*
G03X1522719Y1559604I489J1420D01*
G03X1523141Y1559665I-2J1502D01*
G01X1524295Y1560003D01*
G02X1524351Y1560011I56J-192D01*
G01X1525976D01*
G02X1526041Y1560000I0J-200D01*
G01X1526955Y1559686D01*
G03X1527443Y1559604I489J1420D01*
G03X1527865Y1559665I-2J1502D01*
G01X1529019Y1560003D01*
G02X1529075Y1560011I56J-192D01*
G37*
G36*
G01X1542210Y-38849D02*
G03I-630J0D01*
G37*
G36*
G01Y-28849D02*
G03I-630J0D01*
G37*
G36*
G01Y-19575D02*
G03I-630J0D01*
G37*
G36*
G01X1793345Y10878D02*
X1793470Y10936D01*
X1793917Y10830D01*
G02X1794071Y10636I-46J-195D01*
G01Y2200D01*
G02X1793871Y2000I-200J0D01*
G01X1528192D01*
G02X1527992Y2200I0J200D01*
G01Y10634D01*
G02X1528146Y10828I200J-1D01*
G01X1528592Y10935D01*
X1528718Y10876D01*
X1528749Y10814D01*
G03X1529906Y9466I3306J1667D01*
G02X1529988Y9327I-117J-162D01*
G01Y3996D01*
X1792074D01*
Y9305D01*
X1792158Y9467D01*
G03X1793314Y10816I-2151J3013D01*
G01X1793345Y10878D01*
G37*
G36*
G01X1533363Y560264D02*
G03I-510J0D01*
G37*
G36*
G01X1533107Y1483295D02*
G03I-519J0D01*
G37*
G36*
G01X1535017Y1485895D02*
G03I-519J0D01*
G37*
G36*
G01X1533107Y1488495D02*
G03I-519J0D01*
G37*
G36*
G01X1541727D02*
G03I-519J0D01*
G37*
G36*
G01X1539817Y1485895D02*
G03I-519J0D01*
G37*
G36*
G01X1541727Y1483295D02*
G03I-519J0D01*
G37*
G36*
G01X1557009Y707774D02*
X1556718Y708065D01*
Y722259D01*
X1556840Y722381D01*
X1575973D01*
X1576257Y722097D01*
Y711774D01*
X1577345Y710686D01*
X1579640D01*
X1580257Y710069D01*
Y708565D01*
X1579466Y707774D01*
X1557009D01*
G37*
G36*
G01X1556975Y733424D02*
X1584817D01*
X1584825Y733416D01*
X1584939D01*
X1588721Y729634D01*
Y711601D01*
X1592577Y707745D01*
X1609177D01*
X1609357Y707565D01*
Y701865D01*
X1609123Y701631D01*
X1588023D01*
X1585357Y704297D01*
Y710686D01*
X1582921Y713122D01*
Y722901D01*
X1579213Y726609D01*
X1557324D01*
X1556541Y727392D01*
Y732990D01*
X1556975Y733424D01*
G37*
G36*
G01X1611698Y708324D02*
X1610094Y709928D01*
X1593594D01*
X1593199Y710323D01*
X1593198Y710324D01*
X1590816Y712706D01*
G02X1590757Y712848I141J142D01*
G01Y730682D01*
G03X1590698Y730824I-200J0D01*
G01X1586003Y735519D01*
G03X1585861Y735578I-142J-141D01*
G01X1578180D01*
G02X1578038Y735637I0J200D01*
G01X1577456Y736219D01*
G02X1577397Y736361I141J142D01*
G01Y741595D01*
G03X1577338Y741737I-200J0D01*
G01X1576514Y742561D01*
G03X1576372Y742620I-142J-141D01*
G01X1553821D01*
G02X1553679Y742679I0J200D01*
G01X1552320Y744038D01*
G02X1552261Y744180I141J142D01*
G01Y783431D01*
X1553229Y784399D01*
X1581379D01*
X1599982Y765796D01*
G02X1600041Y765654I-141J-142D01*
G01Y750550D01*
G03X1600100Y750408I200J0D01*
G01X1614569Y735939D01*
X1618141D01*
X1625570Y728510D01*
X1630296D01*
X1639778Y719028D01*
X1639806Y718999D01*
X1646288Y712517D01*
G02X1646347Y712375I-141J-142D01*
G01Y700041D01*
G03X1646406Y699899I200J0D01*
G01X1647608Y698697D01*
X1647637Y698669D01*
X1647667Y698595D01*
Y691578D01*
X1647637Y691504D01*
X1647608Y691476D01*
X1647156Y691024D01*
G02X1647014Y690965I-142J141D01*
G01X1624540D01*
G02X1624398Y691024I0J200D01*
G01X1623816Y691606D01*
G02X1623757Y691748I141J142D01*
G01Y697982D01*
G03X1623698Y698124I-200J0D01*
G01X1620116Y701706D01*
G03X1619974Y701765I-142J-141D01*
G01X1612840D01*
G02X1612698Y701824I0J200D01*
G01X1611816Y702706D01*
G02X1611757Y702848I141J142D01*
G01Y708182D01*
G03X1611698Y708324I-200J0D01*
G37*
G36*
G01X1559886Y1254280D02*
X1568931D01*
X1571498Y1251713D01*
Y1240443D01*
X1571159Y1240104D01*
X1556670D01*
X1554766D01*
X1554278Y1240592D01*
Y1248672D01*
X1559886Y1254280D01*
G37*
G36*
G01X1546507Y1488495D02*
G03I-519J0D01*
G37*
G36*
G01X1548417Y1485895D02*
G03I-519J0D01*
G37*
G36*
G01X1546507Y1483295D02*
G03I-519J0D01*
G37*
G36*
G01X1550587Y1517772D02*
G03I-519J0D01*
G37*
G36*
G01Y1512992D02*
G03I-519J0D01*
G37*
G36*
G01X1553187Y1511082D02*
G03I-519J0D01*
G37*
G36*
G01X1555787Y1512992D02*
G03I-519J0D01*
G37*
G36*
G01Y1517772D02*
G03I-519J0D01*
G37*
G36*
G01X1553187Y1519682D02*
G03I-519J0D01*
G37*
G36*
G01X1550587Y1531172D02*
G03I-519J0D01*
G37*
G36*
G01Y1526392D02*
G03I-519J0D01*
G37*
G36*
G01X1553187Y1524482D02*
G03I-519J0D01*
G37*
G36*
G01X1555787Y1526392D02*
G03I-519J0D01*
G37*
G36*
G01Y1531172D02*
G03I-519J0D01*
G37*
G36*
G01X1551085Y1553883D02*
X1552589D01*
G02X1552731Y1553824I0J-200D01*
G01X1553162Y1553393D01*
G02X1553221Y1553251I-141J-142D01*
G01Y1552245D01*
G03X1553280Y1552103I200J0D01*
G01X1553737Y1551646D01*
G02X1553796Y1551505I-141J-142D01*
G01Y1551250D01*
G03X1554297Y1550748I502J0D01*
G01X1554541D01*
X1554578Y1550733D01*
G03X1555047Y1550638I470J1117D01*
G03X1555516Y1550733I-1J1212D01*
G01X1555553Y1550748D01*
X1555797D01*
G03X1556281Y1551118I0J502D01*
G01X1556299Y1551183D01*
X1556406Y1551265D01*
X1556888D01*
X1556995Y1551183D01*
X1557013Y1551118D01*
G03X1557497Y1550748I484J132D01*
G01X1557741D01*
X1557778Y1550733D01*
G03X1558247Y1550638I470J1117D01*
G03X1558716Y1550733I-1J1212D01*
G01X1558753Y1550748D01*
X1558997D01*
G03X1559481Y1551118I0J502D01*
G01X1559499Y1551183D01*
X1559606Y1551265D01*
X1559884D01*
X1559947Y1551244D01*
X1559974Y1551223D01*
G03X1561507Y1550698I1533J1976D01*
G03X1563198Y1551356I0J2502D01*
G02X1563333Y1551408I134J-148D01*
G01X1565100D01*
X1565174Y1551378D01*
X1565195Y1551357D01*
Y1549696D01*
G02X1565089Y1549519I-200J0D01*
G03X1564116Y1548584I1183J-2205D01*
G02X1563943Y1548486I-172J102D01*
G01X1563599D01*
G02X1563426Y1548584I-1J200D01*
G03X1561271Y1549816I-2155J-1269D01*
G03Y1544812I0J-2502D01*
G03X1562545Y1545161I-1J2502D01*
G02X1562789Y1545130I102J-172D01*
G01X1564276Y1543643D01*
X1564303Y1543592D01*
X1564309Y1543562D01*
G03X1564380Y1543331I1188J239D01*
G01X1564396Y1543294D01*
Y1543050D01*
G03X1564399Y1542994I501J-1D01*
G01X1564400Y1542983D01*
Y1542972D01*
G02X1564200Y1542772I-200J0D01*
G01X1561374D01*
X1561272Y1542841D01*
X1561249Y1542898D01*
G03X1558924Y1544477I-2325J-922D01*
G03X1556422Y1541975I0J-2502D01*
G03X1556491Y1541391I2502J0D01*
G01X1556504Y1541339D01*
X1556476Y1541240D01*
X1554739Y1539504D01*
G03X1554578Y1539303I860J-854D01*
G02X1554409Y1539212I-168J109D01*
G01X1552183D01*
G02X1552041Y1539270I-1J200D01*
G01X1551933Y1539379D01*
G02X1551874Y1539520I141J142D01*
G01Y1541186D01*
G03X1551815Y1541328I-200J0D01*
G01X1550737Y1542406D01*
G02X1550678Y1542548I141J142D01*
G01Y1553476D01*
G02X1550737Y1553618I200J0D01*
G01X1550943Y1553824D01*
G02X1551085Y1553883I142J-141D01*
G37*
G36*
G01X1562755Y1573138D02*
X1564286D01*
G02X1564428Y1573079I0J-200D01*
G01X1564888Y1572619D01*
G02X1564947Y1572477I-141J-142D01*
G01Y1568636D01*
G02X1564888Y1568494I-200J0D01*
G01X1564459Y1568065D01*
G02X1564318Y1568006I-142J141D01*
G01X1561208D01*
G03X1560639Y1567864I0J-1211D01*
G01X1560617Y1567853D01*
X1560570Y1567841D01*
X1559529D01*
G03X1559387Y1567782I0J-200D01*
G01X1558969Y1567364D01*
G02X1558828Y1567306I-141J142D01*
G01X1547107D01*
G02X1546907Y1567506I0J200D01*
G01Y1572541D01*
G02X1546966Y1572683I200J0D01*
G01X1547066Y1572783D01*
G02X1547208Y1572842I142J-141D01*
G01X1550012D01*
G02X1550154Y1572783I0J-200D01*
G01X1552694Y1570243D01*
G03X1552836Y1570184I142J141D01*
G01X1555957D01*
G03X1556060Y1570180I110J1498D01*
G03X1556163Y1570184I-7J1502D01*
G01X1558457D01*
G03X1558560Y1570180I110J1498D01*
G03X1558663Y1570184I-7J1502D01*
G01X1559635D01*
G03X1559777Y1570243I0J200D01*
G01X1562613Y1573079D01*
G02X1562755Y1573138I142J-141D01*
G37*
G36*
G01X1545817Y1617970D02*
X1553661D01*
G02X1553803Y1617911I0J-200D01*
G01X1557415Y1614299D01*
G03X1557557Y1614240I142J141D01*
G01X1569307D01*
G02X1569449Y1614181I0J-200D01*
G01X1569771Y1613859D01*
G02X1569830Y1613717I-141J-142D01*
G01Y1598619D01*
G02X1569771Y1598477I-200J0D01*
G01X1567843Y1596549D01*
G02X1567701Y1596490I-142J141D01*
G01X1567477D01*
G03X1567335Y1596431I0J-200D01*
G01X1557780Y1586876D01*
X1557704Y1586845D01*
X1557664Y1586846D01*
X1557633D01*
G03Y1582842I0J-2002D01*
G01X1557654D01*
G02X1557794Y1582787I2J-200D01*
G01X1557944Y1582645D01*
Y1582608D01*
X1558224Y1582328D01*
G02X1558262Y1582097I-141J-142D01*
G03X1558049Y1581199I1789J-899D01*
G03X1558306Y1580217I2002J-1D01*
G01X1558319Y1580194D01*
X1558332Y1580145D01*
Y1579833D01*
G03X1558391Y1579691I200J0D01*
G01X1559966Y1578116D01*
G02X1560025Y1577974I-141J-142D01*
G01Y1571990D01*
G02X1559966Y1571849I-200J1D01*
G01X1559362Y1571244D01*
G02X1559220Y1571186I-141J142D01*
G01X1553251D01*
G02X1553109Y1571244I-1J200D01*
G01X1550568Y1573785D01*
G03X1550427Y1573844I-142J-141D01*
G01X1550418D01*
X1545600Y1578661D01*
G02X1545541Y1578803I141J142D01*
G01Y1581493D01*
X1545519Y1581515D01*
X1545537Y1581618D01*
G03X1545556Y1581828I-1193J214D01*
G01Y1582997D01*
G02X1545614Y1583139I200J1D01*
G01X1546013Y1583537D01*
G03X1546368Y1584394I-857J857D01*
G01Y1586101D01*
G03X1546013Y1586958I-1212J0D01*
G01X1545403Y1587568D01*
G02X1545344Y1587709I141J142D01*
G01Y1593167D01*
G03X1545285Y1593309I-200J0D01*
G01X1543883Y1594711D01*
G02X1543824Y1594853I141J142D01*
G01Y1615977D01*
G02X1543883Y1616119I200J0D01*
G01X1545675Y1617911D01*
G02X1545817Y1617970I142J-141D01*
G37*
G36*
G01X1569866Y573913D02*
X1568166Y575613D01*
X1559366D01*
X1558366Y574613D01*
Y554713D01*
X1562966Y550113D01*
X1598906D01*
X1600004Y551211D01*
Y561867D01*
X1599528Y562343D01*
X1578736D01*
X1569766Y571313D01*
Y573813D01*
X1569866Y573913D01*
G37*
G36*
G01X1578966Y590813D02*
Y577513D01*
X1578366Y576913D01*
X1560121D01*
X1559845Y577189D01*
Y590513D01*
Y594686D01*
X1560498Y595339D01*
X1577885D01*
X1578966Y594258D01*
Y590813D01*
G37*
G36*
G01X1596331Y1019213D02*
G02I-13780J0D01*
G37*
G36*
G01X1572546Y1306083D02*
G03I-510J0D01*
G37*
G36*
G01X1569289Y1498195D02*
G03I-519J0D01*
G37*
G36*
G01X1567379Y1495595D02*
G03I-519J0D01*
G37*
G36*
G01X1569289Y1492995D02*
G03I-519J0D01*
G37*
G36*
G01X1563741Y1519190D02*
G03I-519J0D01*
G37*
G36*
G01X1561141Y1517280D02*
G03I-519J0D01*
G37*
G36*
G01Y1512500D02*
G03I-519J0D01*
G37*
G36*
G01X1563741Y1510590D02*
G03I-519J0D01*
G37*
G36*
G01X1566341Y1512500D02*
G03I-519J0D01*
G37*
G36*
G01Y1517280D02*
G03I-519J0D01*
G37*
G36*
G01Y1534300D02*
G03I-519J0D01*
G37*
G36*
G01X1563741Y1532490D02*
G03I-519J0D01*
G37*
G36*
G01X1561141Y1534300D02*
G03I-519J0D01*
G37*
G36*
G01X1563741Y1540990D02*
G03I-519J0D01*
G37*
G36*
G01X1566341Y1539080D02*
G03I-519J0D01*
G37*
G36*
G01X1563426Y1583581D02*
X1571087D01*
X1571178Y1583529D01*
X1571205Y1583483D01*
G03X1571389Y1583247I1040J621D01*
G01X1571528Y1583109D01*
G02X1571586Y1582967I-142J-141D01*
G01Y1574088D01*
G02X1571528Y1573947I-200J0D01*
G01X1571307Y1573726D01*
G02X1571165Y1573667I-142J141D01*
G01X1565339D01*
G02X1565198Y1573726I1J200D01*
G01X1564842Y1574081D01*
G03X1564701Y1574140I-142J-141D01*
G01X1562408D01*
X1562334Y1574170D01*
X1562309Y1574195D01*
Y1582527D01*
G02X1562368Y1582669I200J0D01*
G01X1563173Y1583474D01*
X1563204Y1583489D01*
G03X1563324Y1583553I-646J1356D01*
G02X1563426Y1583581I102J-172D01*
G37*
G36*
G01X1571710Y1608620D02*
X1701108D01*
G02X1701250Y1608561I0J-200D01*
G01X1701601Y1608210D01*
G02X1701660Y1608068I-141J-142D01*
G01Y1573881D01*
X1701630Y1573808D01*
X1701606Y1573784D01*
Y1551345D01*
G02X1701547Y1551203I-200J0D01*
G01X1697116Y1546772D01*
G02X1696898Y1546728I-142J141D01*
G01X1696815Y1546762D01*
G03X1696739Y1546778I-78J-184D01*
G01X1694480D01*
G03X1694280Y1546578I0J-200D01*
G01Y1546556D01*
X1693539D01*
G03X1693397Y1546497I0J-200D01*
G01X1687397Y1540497D01*
G02X1687255Y1540438I-142J141D01*
G01X1681618D01*
G02X1681476Y1540497I0J200D01*
G01X1681437Y1540536D01*
G02X1681378Y1540678I141J142D01*
G01Y1543382D01*
G03X1681319Y1543524I-200J0D01*
G01X1679859Y1544984D01*
G02X1679800Y1545126I141J142D01*
G01Y1549911D01*
G02X1679859Y1550053I200J0D01*
G01X1680340Y1550534D01*
G02X1680482Y1550593I142J-141D01*
G01X1683140D01*
G03X1683282Y1550652I0J200D01*
G01X1684283Y1551653D01*
G03X1684342Y1551795I-141J142D01*
G01Y1557229D01*
G03X1684283Y1557371I-200J0D01*
G01X1682730Y1558924D01*
G02X1682671Y1559066I141J142D01*
G01Y1564071D01*
G02X1682730Y1564213I200J0D01*
G01X1682740Y1564224D01*
X1689141D01*
G02X1689341Y1564024I0J-200D01*
G01Y1558656D01*
G02X1689282Y1558514I-200J0D01*
G01X1687598Y1556830D01*
X1687540Y1556801D01*
X1687507Y1556797D01*
G03X1687077Y1556367I67J-497D01*
G01X1687073Y1556334D01*
X1687044Y1556276D01*
X1687023Y1556255D01*
Y1551670D01*
G03X1687082Y1551528I200J0D01*
G01X1687958Y1550652D01*
G03X1688100Y1550593I142J141D01*
G01X1693843D01*
G03X1693985Y1550652I0J200D01*
G01X1696923Y1553590D01*
G03X1696982Y1553732I-141J142D01*
G01Y1576053D01*
X1696953Y1576082D01*
Y1577114D01*
G03X1696894Y1577256I-200J0D01*
G01X1695038Y1579112D01*
G03X1694896Y1579171I-142J-141D01*
G01X1689968D01*
G02X1689826Y1579230I0J200D01*
G01X1689333Y1579723D01*
G02X1689274Y1579865I141J142D01*
G01Y1582348D01*
G02X1689333Y1582490I200J0D01*
G01X1690472Y1583629D01*
G03X1690531Y1583771I-141J142D01*
G01Y1589398D01*
X1690625Y1589509D01*
X1690697Y1589522D01*
G03X1692355Y1591494I-344J1972D01*
G03X1690353Y1593496I-2002J0D01*
G03X1688363Y1591710I0J-2002D01*
G01X1688354Y1591633D01*
X1688241Y1591532D01*
X1669940D01*
G02X1669740Y1591732I0J200D01*
G01Y1592250D01*
G03X1669239Y1592752I-502J0D01*
G01X1669184D01*
G02X1669042Y1592810I-1J200D01*
G01X1668185Y1593668D01*
X1668156Y1593765D01*
X1668168Y1593816D01*
G03X1668228Y1594362I-2442J545D01*
G03X1663224I-2502J0D01*
G03X1663578Y1593079I2502J0D01*
G02X1663606Y1592977I-172J-102D01*
G01Y1591517D01*
G02X1663547Y1591375I-200J0D01*
G01X1662954Y1590782D01*
G02X1662812Y1590723I-142J141D01*
G01X1662433D01*
X1662410Y1590728D01*
G03X1662129Y1590762I-285J-1178D01*
G01X1661173D01*
G02X1661002Y1590857I-1J200D01*
G03X1659874Y1591841I-2133J-1307D01*
G01X1659840Y1591856D01*
X1657768Y1593928D01*
G03X1657626Y1593987I-142J-141D01*
G01X1584502D01*
X1584465Y1594002D01*
G03X1584273Y1594040I-191J-463D01*
G01X1584029D01*
X1583992Y1594056D01*
G03X1583523Y1594150I-468J-1117D01*
G03X1583054Y1594056I-1J-1211D01*
G01X1583017Y1594040D01*
X1582887D01*
X1582771Y1594149D01*
X1582767Y1594229D01*
G03X1580269Y1596581I-2498J-151D01*
G03X1577767Y1594079I0J-2502D01*
G03X1579803Y1591621I2502J0D01*
G01X1579874Y1591607D01*
X1579966Y1591497D01*
Y1590571D01*
G02X1579907Y1590430I-200J1D01*
G01X1579811Y1590334D01*
G02X1579669Y1590275I-142J141D01*
G01X1574728D01*
G02X1574586Y1590334I0J200D01*
G01X1572730Y1592190D01*
G03X1572588Y1592249I-142J-141D01*
G01X1571976D01*
G02X1571776Y1592449I0J200D01*
G01Y1593980D01*
G02X1571834Y1594122I200J1D01*
G01X1576764Y1599052D01*
G02X1576906Y1599110I141J-142D01*
G01X1577813D01*
G02X1577984Y1599015I1J-200D01*
G03X1580117Y1597820I2133J1306D01*
G03Y1602824I0J2502D01*
G03X1577984Y1601629I0J-2501D01*
G02X1577813Y1601534I-170J105D01*
G01X1576321D01*
G03X1575464Y1601179I0J-1212D01*
G01X1571851Y1597566D01*
G02X1571633Y1597522I-142J141D01*
G01X1571577Y1597546D01*
X1571510Y1597645D01*
Y1608420D01*
G02X1571710Y1608620I200J0D01*
G37*
G36*
G01X1662535Y612798D02*
Y598500D01*
X1661502Y597466D01*
X1606766D01*
X1605736D01*
X1601784Y593514D01*
Y592484D01*
G03X1601725Y592342I141J-142D01*
G01Y564935D01*
G02X1601666Y564793I-200J0D01*
G01X1600845Y563972D01*
G02X1600703Y563913I-142J141D01*
G01X1583553D01*
G02X1583411Y563972I0J200D01*
G01X1583125Y564258D01*
G02X1583066Y564400I141J142D01*
G01Y615493D01*
G02X1583125Y615635I200J0D01*
G01X1585690Y618200D01*
G02X1585832Y618259I142J-141D01*
G01X1644271D01*
X1647438Y615092D01*
X1648581Y613949D01*
X1661384D01*
X1662535Y612798D01*
G37*
G36*
G01X1583275Y710165D02*
Y706333D01*
X1582658Y705716D01*
X1581805Y704863D01*
X1579758D01*
X1579587Y705034D01*
Y706475D01*
X1581261Y708149D01*
Y708542D01*
Y710169D01*
X1581457Y710365D01*
X1583075D01*
X1583275Y710165D01*
G37*
G36*
G01X1588801Y1243107D02*
X1573796D01*
X1573303Y1243600D01*
Y1252573D01*
X1574852Y1254122D01*
X1589785D01*
X1591076Y1252831D01*
Y1244840D01*
X1589343Y1243107D01*
X1588801D01*
G37*
G36*
G01X1583517Y1288958D02*
G03I-510J0D01*
G37*
G36*
G01X1587538Y1307137D02*
G03I-510J0D01*
G37*
G36*
G01X1580769Y1488495D02*
G03I-519J0D01*
G37*
G36*
G01X1582679Y1485895D02*
G03I-519J0D01*
G37*
G36*
G01X1580769Y1483295D02*
G03I-519J0D01*
G37*
G36*
G01X1575989D02*
G03I-519J0D01*
G37*
G36*
G01X1574079Y1485895D02*
G03I-519J0D01*
G37*
G36*
G01X1575989Y1488495D02*
G03I-519J0D01*
G37*
G36*
G01X1574069Y1492995D02*
G03I-519J0D01*
G37*
G36*
G01X1575979Y1495595D02*
G03I-519J0D01*
G37*
G36*
G01X1574069Y1498195D02*
G03I-519J0D01*
G37*
G36*
G01X1587479Y1505295D02*
G03I-519J0D01*
G37*
G36*
G01X1600444Y1560011D02*
X1602070D01*
G02X1602135Y1560000I0J-200D01*
G01X1603049Y1559686D01*
G03X1603455Y1559607I487J1420D01*
G01X1603494Y1559605D01*
X1603563Y1559573D01*
X1603779Y1559345D01*
G02X1603834Y1559207I-145J-138D01*
G01Y1557099D01*
G02X1603779Y1556961I-200J0D01*
G01X1603563Y1556733D01*
X1603494Y1556701D01*
X1603455Y1556699D01*
G03X1603140Y1556648I81J-1499D01*
G01X1601918Y1556313D01*
G02X1601865Y1556306I-52J193D01*
G01X1600178D01*
G02X1600108Y1556319I1J200D01*
G01X1599337Y1556607D01*
G03X1598812Y1556702I-526J-1407D01*
G03X1598415Y1556648I2J-1502D01*
G01X1597194Y1556313D01*
G02X1597141Y1556306I-52J193D01*
G01X1595454D01*
G02X1595384Y1556319I1J200D01*
G01X1594613Y1556607D01*
G03X1594088Y1556702I-526J-1407D01*
G03X1593691Y1556648I2J-1502D01*
G01X1592469Y1556313D01*
G02X1592416Y1556306I-52J193D01*
G01X1590729D01*
G02X1590659Y1556319I1J200D01*
G01X1589888Y1556607D01*
G03X1589363Y1556702I-526J-1407D01*
G03X1588966Y1556648I2J-1502D01*
G01X1587745Y1556313D01*
G02X1587692Y1556306I-52J193D01*
G01X1586289D01*
G02X1586147Y1556365I0J200D01*
G01X1585985Y1556527D01*
G02X1585926Y1556669I141J142D01*
G01Y1559626D01*
G02X1586055Y1559813I200J0D01*
G01X1586539Y1559998D01*
G02X1586611Y1560011I71J-187D01*
G01X1587896D01*
G02X1587961Y1560000I0J-200D01*
G01X1588875Y1559686D01*
G03X1589363Y1559604I489J1420D01*
G03X1589785Y1559665I-2J1502D01*
G01X1590939Y1560003D01*
G02X1590995Y1560011I56J-192D01*
G01X1592621D01*
G02X1592686Y1560000I0J-200D01*
G01X1593600Y1559686D01*
G03X1594088Y1559604I489J1420D01*
G03X1594510Y1559665I-2J1502D01*
G01X1595664Y1560003D01*
G02X1595720Y1560011I56J-192D01*
G01X1597345D01*
G02X1597410Y1560000I0J-200D01*
G01X1598324Y1559686D01*
G03X1598812Y1559604I489J1420D01*
G03X1599234Y1559665I-2J1502D01*
G01X1600388Y1560003D01*
G02X1600444Y1560011I56J-192D01*
G37*
G36*
G01X1591257Y699265D02*
X1619589D01*
X1621257Y697597D01*
Y690765D01*
X1623157Y688865D01*
X1641957D01*
X1642157Y688665D01*
Y683265D01*
X1641757Y682865D01*
X1618657D01*
X1615757Y685765D01*
Y692097D01*
X1614789Y693065D01*
X1590957D01*
X1590757Y693265D01*
Y698765D01*
X1591257Y699265D01*
G37*
G36*
G01X1602789Y1488495D02*
G03I-519J0D01*
G37*
G36*
G01X1600879Y1485895D02*
G03I-519J0D01*
G37*
G36*
G01X1602789Y1483295D02*
G03I-519J0D01*
G37*
G36*
G01X1589389Y1502695D02*
G03I-519J0D01*
G37*
G36*
G01X1594169D02*
G03I-519J0D01*
G37*
G36*
G01X1596079Y1505295D02*
G03I-519J0D01*
G37*
G36*
G01X1596089Y1498195D02*
G03I-519J0D01*
G37*
G36*
G01X1594179Y1495595D02*
G03I-519J0D01*
G37*
G36*
G01X1596089Y1492995D02*
G03I-519J0D01*
G37*
G36*
G01X1600869D02*
G03I-519J0D01*
G37*
G36*
G01X1602779Y1495595D02*
G03I-519J0D01*
G37*
G36*
G01X1600869Y1498195D02*
G03I-519J0D01*
G37*
G36*
G01X1589389Y1507895D02*
G03I-519J0D01*
G37*
G36*
G01X1594169D02*
G03I-519J0D01*
G37*
G36*
G01X1612495Y533094D02*
X1615261D01*
X1616560Y531795D01*
Y524124D01*
X1615688Y523252D01*
X1608252D01*
X1607564Y523940D01*
Y528163D01*
X1612495Y533094D01*
G37*
G36*
G01X1619313Y565701D02*
Y562791D01*
X1620313Y561791D01*
X1623113D01*
X1623513Y561391D01*
Y560491D01*
X1623313Y560291D01*
X1619213D01*
X1616213Y563291D01*
Y565591D01*
X1616546Y565924D01*
X1619090D01*
X1619313Y565701D01*
G37*
G36*
G01X1629048Y555471D02*
X1628885Y555308D01*
X1627680D01*
X1627548Y555440D01*
Y559264D01*
Y568856D01*
X1626513Y569891D01*
X1622313D01*
X1619813D01*
X1619213Y569291D01*
Y567291D01*
X1618846Y566924D01*
X1616660D01*
X1615700Y567884D01*
Y582078D01*
X1617313Y583691D01*
X1635013D01*
X1635398Y583306D01*
X1636313Y582391D01*
Y571144D01*
X1629048Y563879D01*
Y555471D01*
G37*
G36*
G01X1648989Y517760D02*
X1631099D01*
X1630883Y517976D01*
Y559269D01*
X1630977Y559364D01*
X1640613D01*
X1645518D01*
X1649489Y563335D01*
Y585205D01*
X1648789Y585905D01*
X1609044D01*
X1608109Y586840D01*
Y589357D01*
Y596105D01*
X1608343Y596339D01*
X1664887D01*
X1664933Y596385D01*
X1664973Y596425D01*
X1665103Y596555D01*
Y614867D01*
X1667762Y617526D01*
X1677939D01*
X1679590Y615875D01*
Y523271D01*
X1674079Y517760D01*
X1660419D01*
X1648989D01*
G37*
G36*
G01X1778283Y761316D02*
X1782776D01*
G02X1782918Y761257I0J-200D01*
G01X1784632Y759543D01*
G02X1784690Y759402I-142J-141D01*
G01Y759154D01*
G03X1785192Y758652I502J0D01*
G01X1793310D01*
X1798780Y753182D01*
Y735940D01*
X1790580Y727740D01*
X1783140D01*
X1766420Y711020D01*
X1761280D01*
X1761100Y710840D01*
Y707310D01*
X1761270Y707140D01*
X1765870D01*
X1767276Y705734D01*
Y696716D01*
X1766280Y695720D01*
X1681640D01*
X1651130Y726230D01*
Y737130D01*
X1641220Y747040D01*
X1620960D01*
X1616580Y751420D01*
Y760966D01*
X1616930Y761316D01*
X1618827D01*
G03X1618946Y761312I134J2208D01*
G01X1623496D01*
G03X1623615Y761316I-15J2212D01*
G01X1626313D01*
G02X1626477Y761230I0J-200D01*
G01X1626692Y760919D01*
X1626704Y760822D01*
X1626687Y760775D01*
G03X1626594Y760265I1359J-511D01*
G03X1629498I1452J0D01*
G03X1629405Y760775I-1452J-1D01*
G01X1629388Y760822D01*
X1629400Y760919D01*
X1629615Y761230D01*
G02X1629779Y761316I164J-114D01*
G01X1635986D01*
G02X1636186Y761116I0J-200D01*
G01Y759154D01*
G03X1636688Y758652I502J0D01*
G01X1642588D01*
G03X1643090Y759154I0J502D01*
G01Y761116D01*
G02X1643290Y761316I200J0D01*
G01X1648528D01*
G03X1648647Y761312I134J2208D01*
G01X1653197D01*
G03X1653316Y761316I-15J2212D01*
G01X1656014D01*
G02X1656178Y761230I0J-200D01*
G01X1656393Y760919D01*
X1656405Y760822D01*
X1656388Y760775D01*
G03X1656295Y760265I1359J-511D01*
G03X1659199I1452J0D01*
G03X1659106Y760775I-1452J-1D01*
G01X1659089Y760822D01*
X1659101Y760919D01*
X1659316Y761230D01*
G02X1659480Y761316I164J-114D01*
G01X1665688D01*
G02X1665888Y761116I0J-200D01*
G01Y759152D01*
G03X1666389Y758652I501J1D01*
G01X1672289D01*
G03X1672790Y759152I0J501D01*
G01Y761116D01*
G02X1672990Y761316I200J0D01*
G01X1678229D01*
G03X1678348Y761312I134J2208D01*
G01X1682898D01*
G03X1683017Y761316I-15J2212D01*
G01X1685715D01*
G02X1685879Y761230I0J-200D01*
G01X1686094Y760919D01*
X1686106Y760822D01*
X1686089Y760775D01*
G03X1685996Y760265I1359J-511D01*
G03X1688900I1452J0D01*
G03X1688807Y760775I-1452J-1D01*
G01X1688790Y760822D01*
X1688802Y760919D01*
X1689017Y761230D01*
G02X1689181Y761316I164J-114D01*
G01X1695388D01*
G02X1695588Y761116I0J-200D01*
G01Y759154D01*
G03X1696090Y758652I502J0D01*
G01X1701990D01*
G03X1702492Y759154I0J502D01*
G01Y761116D01*
G02X1702692Y761316I200J0D01*
G01X1707930D01*
G03X1708049Y761312I134J2208D01*
G01X1712599D01*
G03X1712718Y761316I-15J2212D01*
G01X1715416D01*
G02X1715580Y761230I0J-200D01*
G01X1715795Y760919D01*
X1715807Y760822D01*
X1715790Y760775D01*
G03X1715697Y760265I1359J-511D01*
G03X1718601I1452J0D01*
G03X1718508Y760775I-1452J-1D01*
G01X1718491Y760822D01*
X1718503Y760919D01*
X1718718Y761230D01*
G02X1718882Y761316I164J-114D01*
G01X1725090D01*
G02X1725290Y761116I0J-200D01*
G01Y759152D01*
G03X1725791Y758652I501J1D01*
G01X1731691D01*
G03X1732192Y759152I0J501D01*
G01Y761116D01*
G02X1732392Y761316I200J0D01*
G01X1737631D01*
G03X1737750Y761312I134J2208D01*
G01X1742300D01*
G03X1742419Y761316I-15J2212D01*
G01X1745117D01*
G02X1745281Y761230I0J-200D01*
G01X1745496Y760919D01*
X1745508Y760822D01*
X1745491Y760775D01*
G03X1745398Y760265I1359J-511D01*
G03X1748302I1452J0D01*
G03X1748209Y760775I-1452J-1D01*
G01X1748192Y760822D01*
X1748204Y760919D01*
X1748419Y761230D01*
G02X1748583Y761316I164J-114D01*
G01X1754790D01*
G02X1754990Y761116I0J-200D01*
G01Y759154D01*
G03X1755492Y758652I502J0D01*
G01X1761392D01*
G03X1761894Y759154I0J502D01*
G01Y761116D01*
G02X1762094Y761316I200J0D01*
G01X1767331D01*
G03X1767450Y761312I134J2208D01*
G01X1772000D01*
G03X1772119Y761316I-15J2212D01*
G01X1774817D01*
G02X1774981Y761230I0J-200D01*
G01X1775196Y760919D01*
X1775208Y760822D01*
X1775191Y760775D01*
G03X1775098Y760265I1359J-511D01*
G03X1778002I1452J0D01*
G03X1777909Y760775I-1452J-1D01*
G01X1777892Y760822D01*
X1777904Y760919D01*
X1778119Y761230D01*
G02X1778283Y761316I164J-114D01*
G37*
G36*
G01X1754620Y1400490D02*
Y1348210D01*
X1753730Y1347320D01*
X1635980D01*
X1633170Y1344510D01*
Y1323500D01*
X1623610Y1313940D01*
Y1306190D01*
X1625260Y1304540D01*
X1635269D01*
X1636801Y1306072D01*
Y1308001D01*
X1637678Y1308878D01*
X1747537D01*
X1749507Y1306908D01*
Y1295298D01*
X1748029Y1293820D01*
X1712231D01*
X1730796Y1293818D01*
X1622092D01*
X1620190Y1295720D01*
Y1329990D01*
X1616150Y1334030D01*
X1608783Y1341397D01*
Y1395402D01*
X1609899Y1396518D01*
X1617517D01*
X1635567D01*
X1642387Y1389698D01*
Y1384216D01*
X1645521Y1381082D01*
X1656248D01*
X1658089Y1379241D01*
X1664291D01*
Y1382028D01*
X1662836Y1383483D01*
X1660683D01*
X1660404Y1383762D01*
X1657197D01*
X1657153Y1383806D01*
Y1384624D01*
X1657188Y1384659D01*
X1660800D01*
X1661000Y1384859D01*
Y1388700D01*
X1660618Y1389082D01*
X1656929D01*
X1656640Y1389371D01*
Y1389629D01*
X1656972Y1389961D01*
X1660558D01*
X1661000Y1390403D01*
Y1391203D01*
X1661030Y1391233D01*
X1667870D01*
X1667900Y1391203D01*
Y1383360D01*
X1669312Y1381948D01*
X1678768D01*
X1678900Y1382080D01*
X1683124D01*
X1683320Y1381884D01*
X1687179D01*
X1687944Y1381120D01*
X1689171D01*
X1690950Y1379341D01*
X1697073D01*
Y1382227D01*
X1695717Y1383583D01*
X1692759D01*
X1692480Y1383862D01*
X1690005D01*
X1689826Y1384041D01*
Y1384580D01*
X1690006Y1384760D01*
X1693583D01*
X1693782Y1384959D01*
Y1388858D01*
X1693425Y1389215D01*
X1689482D01*
X1689422Y1389275D01*
Y1389790D01*
X1689691Y1390059D01*
X1693338D01*
X1693782Y1390503D01*
Y1391303D01*
X1693812Y1391333D01*
X1700652D01*
X1700682Y1391303D01*
Y1383428D01*
X1701920Y1382190D01*
X1715492D01*
X1715396Y1382277D01*
X1715403Y1382284D01*
X1716454D01*
Y1382269D01*
X1726248D01*
X1728127Y1384148D01*
Y1388738D01*
X1728190Y1388800D01*
Y1401030D01*
Y1405424D01*
X1729441Y1406675D01*
X1752798D01*
X1754620Y1404853D01*
Y1400490D01*
G37*
G36*
G01X1607569Y1488495D02*
G03I-519J0D01*
G37*
G36*
G01Y1483295D02*
G03I-519J0D01*
G37*
G36*
G01X1609479Y1485895D02*
G03I-519J0D01*
G37*
G36*
G01X1614279Y1505295D02*
G03I-519J0D01*
G37*
G36*
G01X1616189Y1502695D02*
G03I-519J0D01*
G37*
G36*
G01Y1507895D02*
G03I-519J0D01*
G37*
G36*
G01X1610296Y1560011D02*
X1611518D01*
G02X1611583Y1560000I0J-200D01*
G01X1612497Y1559686D01*
G03X1612939Y1559605I489J1420D01*
G01X1612978Y1559604D01*
X1613049Y1559573D01*
X1613270Y1559345D01*
G02X1613326Y1559205I-144J-139D01*
G01Y1557101D01*
G02X1613270Y1556961I-200J-1D01*
G01X1613049Y1556733D01*
X1612978Y1556702D01*
X1612939Y1556701D01*
G03X1612588Y1556648I47J-1501D01*
G01X1611367Y1556313D01*
G02X1611314Y1556306I-52J193D01*
G01X1609962D01*
X1609889Y1556336D01*
X1609878Y1556346D01*
Y1559594D01*
G02X1609937Y1559735I200J-1D01*
G01X1610154Y1559952D01*
G02X1610296Y1560011I142J-141D01*
G37*
G36*
G01X1605244D02*
X1606794D01*
G02X1606859Y1560000I0J-200D01*
G01X1607773Y1559686D01*
G03X1608261Y1559604I489J1420D01*
G03X1608432Y1559614I-2J1502D01*
G01X1608475Y1559619D01*
X1608555Y1559594D01*
X1608810Y1559366D01*
G02X1608877Y1559217I-133J-149D01*
G01Y1557089D01*
G02X1608810Y1556940I-200J0D01*
G01X1608555Y1556712D01*
X1608475Y1556687D01*
X1608432Y1556692D01*
G03X1608261Y1556702I-173J-1492D01*
G03X1607864Y1556648I2J-1502D01*
G01X1606642Y1556313D01*
G02X1606589Y1556306I-52J193D01*
G01X1605200D01*
G02X1605058Y1556365I0J200D01*
G01X1604894Y1556529D01*
G02X1604835Y1556671I141J142D01*
G01Y1559602D01*
G02X1604894Y1559744I200J0D01*
G01X1605102Y1559952D01*
G02X1605244Y1560011I142J-141D01*
G37*
G36*
G01X1624063Y1560010D02*
X1625015D01*
G02X1625157Y1559951I0J-200D01*
G01X1625415Y1559693D01*
G02X1625474Y1559552I-141J-142D01*
G01Y1558527D01*
G03X1625532Y1558386I200J0D01*
G01X1625538Y1558380D01*
X1625568Y1558307D01*
Y1558276D01*
X1625905Y1557939D01*
X1625978Y1557909D01*
X1626009D01*
X1626301Y1557617D01*
G03X1626442Y1557558I142J141D01*
G01X1627566D01*
G02X1627766Y1557358I0J-200D01*
G01Y1557090D01*
G02X1627699Y1556941I-200J0D01*
G01X1627445Y1556714D01*
X1627365Y1556688D01*
X1627322Y1556693D01*
G03X1627159Y1556702I-164J-1493D01*
G03X1626762Y1556648I2J-1502D01*
G01X1625540Y1556313D01*
G02X1625487Y1556306I-52J193D01*
G01X1623800D01*
G02X1623730Y1556319I1J200D01*
G01X1622959Y1556607D01*
G03X1622434Y1556702I-526J-1407D01*
G03X1622037Y1556648I2J-1502D01*
G01X1620816Y1556313D01*
G02X1620763Y1556306I-52J193D01*
G01X1619076D01*
G02X1619006Y1556319I1J200D01*
G01X1618235Y1556607D01*
G03X1617710Y1556702I-526J-1407D01*
G03X1617313Y1556648I2J-1502D01*
G01X1616091Y1556313D01*
G02X1616038Y1556306I-52J193D01*
G01X1614644D01*
G02X1614502Y1556365I0J200D01*
G01X1614387Y1556480D01*
G02X1614328Y1556622I141J142D01*
G01Y1559271D01*
G02X1614387Y1559413I200J0D01*
G01X1614925Y1559951D01*
G02X1615067Y1560010I142J-141D01*
G01X1616246D01*
G02X1616311Y1559999I0J-200D01*
G01X1617222Y1559686D01*
G03X1617710Y1559604I489J1420D01*
G03X1618132Y1559665I-2J1502D01*
G01X1619283Y1560002D01*
G02X1619339Y1560010I56J-192D01*
G01X1620970D01*
G02X1621035Y1559999I0J-200D01*
G01X1621946Y1559686D01*
G03X1622434Y1559604I489J1420D01*
G03X1622856Y1559665I-2J1502D01*
G01X1624007Y1560002D01*
G02X1624063Y1560010I56J-192D01*
G37*
G36*
G01X1639833Y201770D02*
X1675787D01*
G02X1675929Y201711I0J-200D01*
G01X1676801Y200839D01*
G02X1676860Y200697I-141J-142D01*
G01Y197233D01*
G02X1676801Y197091I-200J0D01*
G01X1638559Y158849D01*
G02X1638417Y158790I-142J141D01*
G01X1629453D01*
G02X1629311Y158849I0J200D01*
G01X1617089Y171071D01*
G02X1617030Y171213I141J142D01*
G01Y178967D01*
G02X1617089Y179109I200J0D01*
G01X1639691Y201711D01*
G02X1639833Y201770I142J-141D01*
G37*
G36*
G01X1626548Y558264D02*
Y554181D01*
X1628689Y552040D01*
Y552031D01*
X1629405Y551315D01*
Y518299D01*
X1628760Y517654D01*
X1621480D01*
X1619160Y519974D01*
Y527364D01*
X1620580Y528784D01*
Y536854D01*
X1623596Y539870D01*
Y543008D01*
X1624880Y544291D01*
Y545194D01*
Y564962D01*
X1624509Y565333D01*
Y567787D01*
X1624713Y567991D01*
X1626313D01*
X1626548Y567756D01*
Y558264D01*
G37*
G36*
G01X1623313Y567991D02*
X1621413D01*
X1621213Y567791D01*
Y563391D01*
X1621513Y563091D01*
X1623213D01*
X1623479Y563357D01*
Y567825D01*
X1623313Y567991D01*
G37*
G36*
G01X1671789Y673897D02*
X1624025D01*
X1623857Y674065D01*
Y679865D01*
X1624357Y680365D01*
X1624670Y680678D01*
X1642969D01*
X1643103Y680812D01*
X1644857Y682565D01*
Y684968D01*
X1646077Y686188D01*
X1653109D01*
X1654114Y687193D01*
X1672502D01*
X1675632D01*
X1676127Y686698D01*
Y674398D01*
X1675626Y673897D01*
X1671789D01*
G37*
G36*
G01X1628552Y795315D02*
G03I-656J0D01*
G37*
G36*
G01Y832126D02*
G03I-656J0D01*
G37*
G36*
G01Y868937D02*
G03I-656J0D01*
G37*
G36*
G01Y905749D02*
G03I-656J0D01*
G37*
G36*
G01Y942560D02*
G03I-656J0D01*
G37*
G36*
G01Y1089804D02*
G03I-656J0D01*
G37*
G36*
G01Y1126615D02*
G03I-656J0D01*
G37*
G36*
G01Y1163426D02*
G03I-656J0D01*
G37*
G36*
G01Y1200237D02*
G03I-656J0D01*
G37*
G36*
G01Y1237048D02*
G03I-656J0D01*
G37*
G36*
G01X1626560Y1272950D02*
X1815570D01*
X1820456Y1268064D01*
Y781846D01*
X1833650Y768651D01*
G02X1833708Y768510I-142J-141D01*
G01Y677679D01*
G02X1833650Y677537I-200J-1D01*
G01X1824133Y668020D01*
G02X1823991Y667962I-141J142D01*
G01X1801821D01*
G03X1801002Y667804I2J-2212D01*
G01X1800966Y667790D01*
X1799573D01*
G03X1799431Y667731I0J-200D01*
G01X1779989Y648289D01*
G03X1779930Y648147I141J-142D01*
G01Y576700D01*
X1758500Y555270D01*
X1754230Y551000D01*
X1707175D01*
X1691499D01*
X1689999Y552500D01*
Y563447D01*
G02X1690058Y563589I200J0D01*
G01X1690234Y563766D01*
Y572534D01*
X1709700Y592000D01*
Y634067D01*
G02X1709759Y634209I200J0D01*
G01X1718321Y642771D01*
G02X1718463Y642830I142J-141D01*
G01X1739174D01*
G03X1739316Y642889I0J200D01*
G01X1776298Y679871D01*
G02X1776440Y679930I142J-141D01*
G01X1794430D01*
X1806010Y691510D01*
X1814920D01*
X1821772Y698362D01*
G03X1821831Y698504I-141J142D01*
G01Y758924D01*
G03X1821772Y759066I-200J0D01*
G01X1818381Y762457D01*
X1818380Y762458D01*
X1817688Y763150D01*
X1796215D01*
X1795185Y764180D01*
G02X1795127Y764319I139J140D01*
G01Y1253397D01*
G03X1795069Y1253536I-197J-1D01*
G01X1791135Y1257470D01*
G03X1790996Y1257528I-140J-139D01*
G01X1626589D01*
G02X1626447Y1257587I0J200D01*
G01X1625391Y1258643D01*
G02X1625332Y1258785I141J142D01*
G01Y1271722D01*
X1626560Y1272950D01*
G37*
G36*
G01X1629589Y1488495D02*
G03I-519J0D01*
G37*
G36*
G01X1627679Y1485895D02*
G03I-519J0D01*
G37*
G36*
G01X1629589Y1483295D02*
G03I-519J0D01*
G37*
G36*
G01X1620969Y1502695D02*
G03I-519J0D01*
G37*
G36*
G01X1622879Y1505295D02*
G03I-519J0D01*
G37*
G36*
G01X1622889Y1498195D02*
G03I-519J0D01*
G37*
G36*
G01X1620979Y1495595D02*
G03I-519J0D01*
G37*
G36*
G01X1622889Y1492995D02*
G03I-519J0D01*
G37*
G36*
G01X1627669D02*
G03I-519J0D01*
G37*
G36*
G01X1629579Y1495595D02*
G03I-519J0D01*
G37*
G36*
G01X1627669Y1498195D02*
G03I-519J0D01*
G37*
G36*
G01X1620969Y1507895D02*
G03I-519J0D01*
G37*
G36*
G01X1633515Y1560011D02*
X1634464D01*
G02X1634606Y1559952I0J-200D01*
G01X1634919Y1559639D01*
G02X1634978Y1559498I-141J-142D01*
G01Y1556809D01*
G02X1634919Y1556668I-200J1D01*
G01X1634616Y1556365D01*
G02X1634474Y1556306I-142J141D01*
G01X1633249D01*
G02X1633179Y1556319I1J200D01*
G01X1632408Y1556607D01*
G03X1631883Y1556702I-526J-1407D01*
G03X1631622Y1556679I0J-1492D01*
G01X1631574Y1556670D01*
X1631481Y1556699D01*
X1631403Y1556777D01*
G02X1631344Y1556918I141J142D01*
G01Y1559382D01*
G02X1631403Y1559523I200J-1D01*
G01X1631486Y1559606D01*
X1631577Y1559635D01*
X1631627Y1559627D01*
G03X1631883Y1559604I262J1478D01*
G03X1632305Y1559665I-2J1502D01*
G01X1633459Y1560003D01*
G02X1633515Y1560011I56J-192D01*
G37*
G36*
G01X1628320Y1559873D02*
X1630117D01*
G02X1630259Y1559814I0J-200D01*
G01X1630284Y1559789D01*
G02X1630343Y1559647I-141J-142D01*
G01Y1556865D01*
G02X1630284Y1556723I-200J0D01*
G01X1630008Y1556447D01*
G02X1629866Y1556388I-142J141D01*
G01X1629136D01*
G02X1628994Y1556447I0J200D01*
G01X1628826Y1556615D01*
G02X1628767Y1556757I141J142D01*
G01Y1558154D01*
G03X1628708Y1558296I-200J0D01*
G01X1628503Y1558501D01*
G03X1628361Y1558560I-142J-141D01*
G01X1626857D01*
G02X1626715Y1558619I0J200D01*
G01X1626534Y1558800D01*
G02X1626475Y1558942I141J142D01*
G01Y1559384D01*
G02X1626534Y1559526I200J0D01*
G01X1626642Y1559634D01*
X1626743Y1559662D01*
X1626795Y1559649D01*
G03X1627159Y1559604I365J1457D01*
G03X1627581Y1559665I-2J1502D01*
G01X1628263Y1559865D01*
G02X1628320Y1559873I56J-192D01*
G37*
G36*
G01X1646700Y71839D02*
G02I-720J0D01*
G37*
G36*
G01X1646420Y398152D02*
X1663520D01*
X1664720Y396952D01*
Y394352D01*
X1660820Y390452D01*
Y381452D01*
X1659720Y380352D01*
X1648320D01*
X1645320Y383352D01*
Y397052D01*
X1646420Y398152D01*
G37*
G36*
G01X1652710Y416152D02*
X1653838D01*
X1654870Y415120D01*
Y412782D01*
X1654640Y412552D01*
X1652820D01*
X1651440Y411172D01*
Y408592D01*
X1650650Y407802D01*
X1646840D01*
X1646190Y408452D01*
Y414922D01*
X1646620Y415352D01*
X1647420Y416152D01*
X1652710D01*
G37*
G36*
G01X1649347Y620878D02*
X1648505Y621720D01*
G02X1648447Y621860I139J140D01*
G01Y638996D01*
G03X1648389Y639136I-197J0D01*
G01X1647825Y639700D01*
G03X1647685Y639758I-140J-139D01*
G01X1647654D01*
X1647603Y639794D01*
G03X1646507Y640142I-1097J-1554D01*
G03X1645933Y640053I1J-1902D01*
G01X1645879Y640036D01*
X1645773Y640062D01*
X1645505Y640330D01*
G02X1645447Y640470I139J140D01*
G01Y643986D01*
G02X1645505Y644126I197J0D01*
G01X1645517Y644138D01*
G02X1645656Y644196I140J-139D01*
G01X1651722D01*
G02X1651861Y644138I-1J-197D01*
G01X1652019Y643979D01*
X1652049Y643899D01*
X1652046Y643857D01*
G03X1652015Y642954I12825J-892D01*
G03X1652222Y640652I12856J-4D01*
G01X1652225Y640634D01*
Y633745D01*
G03X1652283Y633605I197J0D01*
G01X1653049Y632839D01*
G02X1653107Y632700I-139J-140D01*
G01Y629940D01*
G03X1653165Y629800I197J0D01*
G01X1655809Y627156D01*
G02X1655867Y627016I-139J-140D01*
G01Y621480D01*
G02X1655809Y621340I-197J0D01*
G01X1655405Y620936D01*
G02X1655265Y620878I-140J139D01*
G01X1654576D01*
X1654556Y620882D01*
G03X1654147Y620924I-408J-1959D01*
G03X1653738Y620882I-1J-2001D01*
G01X1653718Y620878D01*
X1650587D01*
X1650560Y620886D01*
G03X1649979Y620972I-580J-1915D01*
G03X1649371Y620878I-2J-2001D01*
G01X1649347D01*
G37*
G36*
G01X1644694Y791969D02*
G03I-656J0D01*
G37*
G36*
G01Y828780D02*
G03I-656J0D01*
G37*
G36*
G01Y865591D02*
G03I-656J0D01*
G37*
G36*
G01Y902402D02*
G03I-656J0D01*
G37*
G36*
G01Y939213D02*
G03I-656J0D01*
G37*
G36*
G01Y1086457D02*
G03I-656J0D01*
G37*
G36*
G01Y1123268D02*
G03I-656J0D01*
G37*
G36*
G01Y1160079D02*
G03I-656J0D01*
G37*
G36*
G01Y1196890D02*
G03I-656J0D01*
G37*
G36*
G01Y1233701D02*
G03I-656J0D01*
G37*
G36*
G01X1637306Y1310049D02*
X1636817Y1310538D01*
Y1312748D01*
Y1342517D01*
X1640619Y1346319D01*
X1748166D01*
X1749187Y1345298D01*
Y1312188D01*
X1747048Y1310049D01*
X1637306D01*
G37*
G36*
G01X1649997Y1392338D02*
X1644387D01*
X1643797Y1391748D01*
Y1385358D01*
X1646397Y1382758D01*
X1654147D01*
X1654497Y1383108D01*
Y1386818D01*
X1654077Y1387238D01*
X1651477D01*
X1650317Y1388398D01*
Y1392018D01*
X1649997Y1392338D01*
G37*
G36*
G01X1660046Y1418104D02*
X1657390D01*
X1657324Y1418170D01*
X1642000D01*
X1641934Y1418104D01*
X1638631D01*
X1638511Y1418224D01*
Y1418677D01*
X1638636Y1418802D01*
X1641678D01*
X1642083Y1419207D01*
Y1420623D01*
X1641451Y1421255D01*
X1638603D01*
X1638481Y1421377D01*
Y1423383D01*
X1638624Y1423526D01*
X1641594D01*
X1642083Y1424015D01*
Y1432641D01*
X1642183Y1432741D01*
X1656283D01*
X1656417Y1432607D01*
Y1420907D01*
X1656950Y1420374D01*
X1660050D01*
X1660183Y1420241D01*
Y1418241D01*
X1660046Y1418104D01*
G37*
G36*
G01X1634369Y1483295D02*
G03I-519J0D01*
G37*
G36*
G01X1636279Y1485895D02*
G03I-519J0D01*
G37*
G36*
G01X1634369Y1488495D02*
G03I-519J0D01*
G37*
G36*
G01X1641079Y1505295D02*
G03I-519J0D01*
G37*
G36*
G01X1642989Y1502695D02*
G03I-519J0D01*
G37*
G36*
G01X1647769D02*
G03I-519J0D01*
G37*
G36*
G01X1647779Y1495595D02*
G03I-519J0D01*
G37*
G36*
G01X1642989Y1507895D02*
G03I-519J0D01*
G37*
G36*
G01X1647769D02*
G03I-519J0D01*
G37*
G36*
G01X1657137Y1560011D02*
X1658113D01*
G02X1658219Y1559981I1J-200D01*
G01X1658491Y1559810D01*
G02X1658527Y1559782I-104J-171D01*
G01X1658592Y1559717D01*
G02X1658651Y1559575I-141J-142D01*
G01Y1556591D01*
G02X1658592Y1556449I-200J0D01*
G01X1658508Y1556365D01*
G02X1658366Y1556306I-142J141D01*
G01X1656871D01*
G02X1656801Y1556319I1J200D01*
G01X1656030Y1556607D01*
G03X1655505Y1556702I-526J-1407D01*
G03X1655108Y1556648I2J-1502D01*
G01X1653887Y1556313D01*
G02X1653834Y1556306I-52J193D01*
G01X1652147D01*
G02X1652077Y1556319I1J200D01*
G01X1651306Y1556607D01*
G03X1650781Y1556702I-526J-1407D01*
G03X1650384Y1556648I2J-1502D01*
G01X1649162Y1556313D01*
G02X1649109Y1556306I-52J193D01*
G01X1647422D01*
G02X1647352Y1556319I1J200D01*
G01X1646581Y1556607D01*
G03X1646056Y1556702I-526J-1407D01*
G03X1645659Y1556648I2J-1502D01*
G01X1644438Y1556313D01*
G02X1644385Y1556306I-52J193D01*
G01X1642698D01*
G02X1642628Y1556319I1J200D01*
G01X1641857Y1556607D01*
G03X1641422Y1556699I-525J-1407D01*
G01X1641383Y1556701D01*
X1641314Y1556733D01*
X1641100Y1556961D01*
G02X1641046Y1557098I146J137D01*
G01Y1559208D01*
G02X1641100Y1559345I200J0D01*
G01X1641314Y1559573D01*
X1641383Y1559605D01*
X1641422Y1559607D01*
G03X1641754Y1559665I-91J1499D01*
G01X1642908Y1560003D01*
G02X1642964Y1560011I56J-192D01*
G01X1644589D01*
G02X1644654Y1560000I0J-200D01*
G01X1645568Y1559686D01*
G03X1646056Y1559604I489J1420D01*
G03X1646478Y1559665I-2J1502D01*
G01X1647632Y1560003D01*
G02X1647688Y1560011I56J-192D01*
G01X1649314D01*
G02X1649379Y1560000I0J-200D01*
G01X1650293Y1559686D01*
G03X1650781Y1559604I489J1420D01*
G03X1651203Y1559665I-2J1502D01*
G01X1652357Y1560003D01*
G02X1652413Y1560011I56J-192D01*
G01X1654038D01*
G02X1654103Y1560000I0J-200D01*
G01X1655017Y1559686D01*
G03X1655505Y1559604I489J1420D01*
G03X1655927Y1559665I-2J1502D01*
G01X1657081Y1560003D01*
G02X1657137Y1560011I56J-192D01*
G37*
G36*
G01X1638239D02*
X1639724D01*
G02X1639866Y1559952I0J-200D01*
G01X1639985Y1559833D01*
G02X1640044Y1559691I-141J-142D01*
G01Y1556776D01*
G02X1639985Y1556634I-200J0D01*
G01X1639716Y1556365D01*
G02X1639574Y1556306I-142J141D01*
G01X1637973D01*
G02X1637903Y1556319I1J200D01*
G01X1637132Y1556607D01*
G03X1636607Y1556702I-526J-1407D01*
G03X1636330Y1556676I1J-1502D01*
G01X1636281Y1556666D01*
X1636186Y1556696D01*
X1636038Y1556844D01*
G02X1635979Y1556986I141J142D01*
G01Y1559218D01*
G02X1636046Y1559368I200J1D01*
G01X1636302Y1559595D01*
X1636384Y1559620D01*
X1636427Y1559615D01*
G03X1636607Y1559604I181J1491D01*
G03X1637029Y1559665I-2J1502D01*
G01X1638183Y1560003D01*
G02X1638239Y1560011I56J-192D01*
G37*
G36*
G01X1653590Y69340D02*
G02I-720J0D01*
G37*
G36*
G01X1655786Y75343D02*
G02I-720J0D01*
G37*
G36*
G01X1662785Y72850D02*
G02I-720J0D01*
G37*
G36*
G01X1657700D02*
G02I-720J0D01*
G37*
G36*
G01X1651680Y71839D02*
G02I-720J0D01*
G37*
G36*
G01X1677150Y430094D02*
X1682230D01*
X1683399Y428925D01*
Y421242D01*
X1689516Y415125D01*
X1703224D01*
X1703500Y414849D01*
Y414465D01*
X1703269Y414234D01*
X1695524D01*
X1695140Y413850D01*
Y411581D01*
X1695530Y411191D01*
X1701277D01*
X1701539Y410929D01*
Y410546D01*
X1701293Y410300D01*
X1695484D01*
X1695115Y409931D01*
X1695098D01*
X1694038Y408871D01*
X1688076D01*
X1687988Y408782D01*
X1683582D01*
X1682900Y408100D01*
Y397140D01*
X1685831Y394209D01*
X1689922D01*
X1691950D01*
X1692933Y393226D01*
Y375438D01*
X1697413Y370958D01*
X1701839D01*
X1702453Y370344D01*
Y369052D01*
X1701224Y367823D01*
X1669074D01*
X1666800Y370097D01*
Y407411D01*
X1661514Y412697D01*
X1656873D01*
X1656381Y413189D01*
Y415279D01*
X1656811Y415709D01*
X1662089D01*
X1664594Y418214D01*
X1670649D01*
X1671326Y418891D01*
Y427497D01*
X1672955Y429126D01*
X1676182D01*
X1677150Y430094D01*
G37*
G36*
G01X1658253Y795315D02*
G03I-656J0D01*
G37*
G36*
G01Y832126D02*
G03I-656J0D01*
G37*
G36*
G01Y868937D02*
G03I-656J0D01*
G37*
G36*
G01Y905749D02*
G03I-656J0D01*
G37*
G36*
G01Y942560D02*
G03I-656J0D01*
G37*
G36*
G01Y1089804D02*
G03I-656J0D01*
G37*
G36*
G01Y1126615D02*
G03I-656J0D01*
G37*
G36*
G01Y1163426D02*
G03I-656J0D01*
G37*
G36*
G01Y1200237D02*
G03I-656J0D01*
G37*
G36*
G01Y1237048D02*
G03I-656J0D01*
G37*
G36*
G01X1649767Y1402248D02*
X1647537D01*
X1646817Y1402968D01*
Y1406961D01*
X1647629Y1407773D01*
X1669722D01*
X1671827Y1405668D01*
Y1404368D01*
X1671597Y1404138D01*
X1667857D01*
X1667147Y1404848D01*
X1652367D01*
X1649767Y1402248D01*
G37*
G36*
G01X1660983Y1430741D02*
X1662157Y1431914D01*
Y1432758D01*
X1663783Y1434384D01*
Y1435941D01*
X1664383Y1436541D01*
X1669683D01*
X1670730D01*
X1671337Y1437148D01*
Y1439493D01*
X1671189Y1439641D01*
X1670083D01*
X1661641D01*
X1661017Y1439017D01*
Y1431998D01*
X1660357Y1431338D01*
X1657607D01*
X1657550Y1431281D01*
Y1430781D01*
X1657590Y1430741D01*
X1660983D01*
G37*
G36*
G01X1659883Y1432358D02*
X1657567D01*
X1657547Y1432378D01*
Y1436141D01*
Y1436177D01*
X1657483Y1436241D01*
X1656883Y1436841D01*
X1652883D01*
X1652422Y1437302D01*
Y1441109D01*
X1652654Y1441341D01*
X1659083D01*
X1659883Y1440541D01*
Y1432358D01*
G37*
G36*
G01X1656389Y1488495D02*
G03I-519J0D01*
G37*
G36*
G01X1654479Y1485895D02*
G03I-519J0D01*
G37*
G36*
G01X1656389Y1483295D02*
G03I-519J0D01*
G37*
G36*
G01X1661169D02*
G03I-519J0D01*
G37*
G36*
G01Y1488495D02*
G03I-519J0D01*
G37*
G36*
G01X1649679Y1505295D02*
G03I-519J0D01*
G37*
G36*
G01X1649689Y1498195D02*
G03I-519J0D01*
G37*
G36*
G01Y1492995D02*
G03I-519J0D01*
G37*
G36*
G01X1654469D02*
G03I-519J0D01*
G37*
G36*
G01X1656379Y1495595D02*
G03I-519J0D01*
G37*
G36*
G01X1654469Y1498195D02*
G03I-519J0D01*
G37*
G36*
G01X1653974Y1668416D02*
G03I-510J0D01*
G37*
G36*
G01X1648523Y1713684D02*
G03I-510J0D01*
G37*
G36*
G01Y1728834D02*
G03I-510J0D01*
G37*
G36*
G01X1664586Y75343D02*
G02I-720J0D01*
G37*
G36*
G01X1668700Y71839D02*
G02I-720J0D01*
G37*
G36*
G01X1666790Y69340D02*
G02I-720J0D01*
G37*
G36*
G01X1694500Y229500D02*
X1675500D01*
X1675000Y229000D01*
Y227000D01*
X1675500Y226500D01*
X1694500D01*
X1695000Y227000D01*
Y229000D01*
X1694500Y229500D01*
G37*
G36*
G01X1666803Y440952D02*
X1714737D01*
G02X1714879Y440893I0J-200D01*
G01X1715811Y439961D01*
G02X1715870Y439819I-141J-142D01*
G01Y436045D01*
X1715900Y435972D01*
X1715920Y435952D01*
Y425668D01*
X1715918Y425667D01*
Y423033D01*
G02X1715860Y422892I-200J0D01*
G01X1715572Y422604D01*
G02X1715430Y422545I-142J141D01*
G01X1709427D01*
G02X1709285Y422604I0J200D01*
G01X1709203Y422686D01*
G02X1709144Y422828I141J142D01*
G01Y431862D01*
G03X1709085Y432004I-200J0D01*
G01X1709028Y432061D01*
X1709002Y432106D01*
X1708995Y432132D01*
G03X1707544Y433247I-1451J-387D01*
G03X1706133Y432261I0J-1503D01*
G01X1706118Y432219D01*
X1706103Y432204D01*
G03X1706044Y432062I141J-142D01*
G01Y431818D01*
G03X1706042Y431745I1500J-78D01*
G03X1706044Y431672I1502J5D01*
G01Y430268D01*
G02X1705985Y430126I-200J0D01*
G01X1705673Y429814D01*
G02X1705531Y429755I-142J141D01*
G01X1700197D01*
G03X1700055Y429696I0J-200D01*
G01X1700044Y429684D01*
X1699992D01*
X1699874Y429568D01*
Y429516D01*
X1699663Y429304D01*
G03X1699604Y429162I141J-142D01*
G01Y419588D01*
G03X1699663Y419446I200J0D01*
G01X1699975Y419134D01*
G03X1700117Y419075I142J141D01*
G01X1701211D01*
G02X1701353Y419016I0J-200D01*
G01X1701525Y418844D01*
G02X1701584Y418702I-141J-142D01*
G01Y418538D01*
G02X1701525Y418396I-200J0D01*
G01X1701343Y418214D01*
G02X1701201Y418155I-142J141D01*
G01X1698927D01*
G02X1698785Y418214I0J200D01*
G01X1698743Y418256D01*
G02X1698684Y418398I141J142D01*
G01Y421072D01*
G03X1698625Y421214I-200J0D01*
G01X1696684Y423155D01*
G02X1696664Y423178I141J142D01*
G03X1696346Y423496I-1209J-891D01*
G01X1696334Y423505D01*
X1696073Y423766D01*
G02X1696014Y423908I141J142D01*
G01Y429830D01*
G03X1695955Y429972I-200J0D01*
G01X1695531Y430396D01*
G03X1695389Y430455I-142J-141D01*
G01X1693097D01*
G02X1692955Y430514I0J200D01*
G01X1692873Y430596D01*
G02X1692814Y430738I141J142D01*
G01Y435230D01*
X1692888Y435334D01*
X1692948Y435355D01*
G03X1693952Y436772I-498J1417D01*
G03X1690948I-1502J0D01*
G03X1690951Y436677I1502J0D01*
G01X1690954Y436636D01*
X1690926Y436558D01*
X1690698Y436315D01*
G02X1690552Y436252I-146J137D01*
G01X1688003D01*
G03X1687861Y436193I0J-200D01*
G01X1687679Y436011D01*
G03X1687620Y435869I141J-142D01*
G01Y432035D01*
G02X1687561Y431893I-200J0D01*
G01X1686879Y431211D01*
G02X1686737Y431152I-142J141D01*
G01X1676003D01*
G03X1675861Y431093I0J-200D01*
G01X1675179Y430411D01*
G02X1675037Y430352I-142J141D01*
G01X1672303D01*
G03X1672161Y430293I0J-200D01*
G01X1670679Y428811D01*
G03X1670620Y428669I141J-142D01*
G01Y428290D01*
G02X1670561Y428149I-200J1D01*
G01X1670383Y427970D01*
G03X1670324Y427829I141J-142D01*
G01Y420239D01*
G02X1670266Y420098I-200J0D01*
G01X1669779Y419611D01*
G02X1669637Y419552I-142J141D01*
G01X1665803D01*
G02X1665661Y419611I0J200D01*
G01X1665279Y419993D01*
G02X1665220Y420135I141J142D01*
G01Y439369D01*
G02X1665279Y439511I200J0D01*
G01X1666661Y440893D01*
G02X1666803Y440952I142J-141D01*
G37*
G36*
G01X1674395Y791969D02*
G03I-656J0D01*
G37*
G36*
G01Y828780D02*
G03I-656J0D01*
G37*
G36*
G01Y865591D02*
G03I-656J0D01*
G37*
G36*
G01Y902402D02*
G03I-656J0D01*
G37*
G36*
G01Y939213D02*
G03I-656J0D01*
G37*
G36*
G01Y1086457D02*
G03I-656J0D01*
G37*
G36*
G01Y1123268D02*
G03I-656J0D01*
G37*
G36*
G01Y1160079D02*
G03I-656J0D01*
G37*
G36*
G01Y1196890D02*
G03I-656J0D01*
G37*
G36*
G01Y1233701D02*
G03I-656J0D01*
G37*
G36*
G01X1679177Y1428988D02*
X1725352D01*
X1726070Y1428270D01*
Y1383811D01*
X1725564Y1383305D01*
X1702288D01*
X1702141Y1383452D01*
Y1391373D01*
X1702465Y1391697D01*
X1707811D01*
X1708354Y1392240D01*
Y1395301D01*
X1709539Y1396486D01*
Y1403738D01*
X1707537Y1405740D01*
X1686553D01*
X1683633Y1402820D01*
Y1383605D01*
X1683233Y1383205D01*
X1669506D01*
X1669421Y1383290D01*
Y1391335D01*
X1669482Y1391396D01*
X1674828D01*
X1675566Y1392134D01*
Y1395195D01*
X1676989Y1396618D01*
Y1413050D01*
X1677762Y1413823D01*
Y1427573D01*
X1679177Y1428988D01*
G37*
G36*
G01X1675897Y1413978D02*
Y1407118D01*
X1675337Y1406558D01*
X1672397D01*
X1670977Y1407978D01*
Y1414048D01*
X1671327Y1414398D01*
X1675457D01*
X1675877Y1413978D01*
X1675897D01*
G37*
G36*
G01X1663079Y1485895D02*
G03I-519J0D01*
G37*
G36*
G01X1669789Y1488495D02*
G03I-519J0D01*
G37*
G36*
G01X1667879Y1485895D02*
G03I-519J0D01*
G37*
G36*
G01X1669789Y1483295D02*
G03I-519J0D01*
G37*
G36*
G01X1674569D02*
G03I-519J0D01*
G37*
G36*
G01X1676479Y1485895D02*
G03I-519J0D01*
G37*
G36*
G01X1674569Y1488495D02*
G03I-519J0D01*
G37*
G36*
G01X1676468Y1564224D02*
X1678324D01*
G02X1678524Y1564024I0J-200D01*
G01Y1558814D01*
G02X1678465Y1558672I-200J0D01*
G01X1677321Y1557528D01*
G03X1677262Y1557386I141J-142D01*
G01Y1544858D01*
G02X1677203Y1544716I-200J0D01*
G01X1676848Y1544361D01*
G02X1676706Y1544302I-142J141D01*
G01X1669555D01*
G02X1669413Y1544361I0J200D01*
G01X1668726Y1545048D01*
G02X1668667Y1545190I141J142D01*
G01Y1545660D01*
X1668687Y1545721D01*
X1668707Y1545747D01*
G03X1669148Y1547073I-1770J1325D01*
G03X1668864Y1548159I-2211J2D01*
G02X1668859Y1548347I174J99D01*
G03X1669092Y1549336I-1978J988D01*
G03X1668141Y1551153I-2211J0D01*
G01X1667776Y1551407D01*
G02X1667690Y1551571I114J164D01*
G01Y1553441D01*
G02X1667729Y1553560I200J0D01*
G03X1667954Y1554103I-973J721D01*
G01X1667958Y1554136D01*
X1667987Y1554192D01*
X1669916Y1556122D01*
X1669929D01*
Y1556135D01*
X1670046Y1556251D01*
G03X1670400Y1557108I-857J856D01*
G01Y1559304D01*
G02X1670459Y1559446I200J0D01*
G01X1672303Y1561289D01*
G02X1672444Y1561348I142J-141D01*
G01X1675350D01*
G03X1675492Y1561407I0J200D01*
G01X1676209Y1562124D01*
G03X1676268Y1562266I-141J142D01*
G01Y1564024D01*
G02X1676468Y1564224I200J0D01*
G37*
G36*
G01X1672198Y1579131D02*
X1676165D01*
G02X1676307Y1579072I0J-200D01*
G01X1676536Y1578843D01*
G02X1676595Y1578701I-141J-142D01*
G01Y1567726D01*
G02X1676395Y1567526I-200J0D01*
G01X1672123D01*
G03X1671938Y1567512I-1J-1211D01*
G01X1671890Y1567505D01*
X1671801Y1567534D01*
X1671435Y1567900D01*
X1671420Y1567934D01*
G03X1670748Y1568606I-1193J-521D01*
G01X1670714Y1568621D01*
X1668134Y1571201D01*
X1668105Y1571297D01*
X1668116Y1571347D01*
G03X1668148Y1571658I-1469J308D01*
G03X1667912Y1572466I-1501J0D01*
G02X1667881Y1572574I169J107D01*
G01Y1575576D01*
G02X1667940Y1575717I200J-1D01*
G01X1670613Y1578391D01*
G02X1670678Y1578434I141J-142D01*
G01X1671727Y1578869D01*
G03X1672066Y1579081I-464J1119D01*
G02X1672198Y1579131I132J-150D01*
G37*
G36*
G01X1681549Y1655082D02*
X1670487D01*
G02X1670345Y1655141I0J200D01*
G01X1669946Y1655540D01*
G02X1669887Y1655682I141J142D01*
G01Y1658959D01*
G02X1669946Y1659101I200J0D01*
G01X1670394Y1659549D01*
G02X1670536Y1659608I142J-141D01*
G01X1681965D01*
G02X1682107Y1659549I0J-200D01*
G01X1682285Y1659371D01*
G02X1682344Y1659229I-141J-142D01*
G01Y1655877D01*
G02X1682285Y1655735I-200J0D01*
G01X1681691Y1655141D01*
G02X1681549Y1655082I-142J141D01*
G37*
G36*
G01X1673755Y1673475D02*
G03I-510J0D01*
G37*
G36*
G01X1673642Y1690741D02*
G03I-510J0D01*
G37*
G36*
G01X1688920Y69343D02*
G02I-720J0D01*
G37*
G36*
G01X1690834Y71842D02*
G02I-720J0D01*
G37*
G36*
G01X1686514Y75340D02*
G03I-510J0D01*
G37*
G36*
G01X1684604Y72847D02*
G03I-510J0D01*
G37*
G36*
G01X1749155Y306510D02*
X1753422D01*
G02X1753562Y306453I0J-200D01*
G01X1756039Y303976D01*
G03X1756181Y303917I142J141D01*
G01X1840374D01*
G02X1840514Y303860I0J-200D01*
G01X1845815Y298559D01*
G02X1845817Y298557I-140J-142D01*
G02X1845874Y298417I-143J-140D01*
G01Y212792D01*
G02X1845768Y212616I-200J1D01*
G01X1845407Y212424D01*
X1845297Y212430D01*
X1845250Y212461D01*
G03X1838150Y214631I-7101J-10532D01*
G01X1838099D01*
G03X1825448Y201929I51J-12702D01*
G03X1838150Y189227I12702J0D01*
G03X1845250Y191397I-1J12702D01*
G01X1845297Y191428D01*
X1845407Y191434D01*
X1845768Y191242D01*
G02X1845874Y191066I-94J-177D01*
G01Y175652D01*
G02X1845815Y175510I-200J0D01*
G01X1839353Y169048D01*
X1839325Y169019D01*
X1839251Y168989D01*
X1809816D01*
G02X1809628Y169122I0J200D01*
G01X1809481Y169539D01*
X1809515Y169659D01*
X1809565Y169700D01*
G03X1810124Y170869I-943J1169D01*
G03X1807120I-1502J0D01*
G03X1807679Y169700I1502J0D01*
G01X1807729Y169660D01*
X1807763Y169539D01*
X1807616Y169122D01*
G02X1807428Y168989I-188J67D01*
G01X1774748D01*
G02X1774606Y169048I0J200D01*
G01X1770004Y173650D01*
X1745790D01*
X1690750D01*
X1689540Y174860D01*
Y224540D01*
X1690500Y225500D01*
X1695000D01*
X1695500Y226000D01*
X1696500Y227000D01*
Y234500D01*
X1697500Y235500D01*
X1722000D01*
X1723000Y236500D01*
Y257533D01*
X1724000Y258533D01*
X1826638D01*
G03X1826780Y258592I0J200D01*
G01X1829589Y261401D01*
G03X1829648Y261543I-141J142D01*
G01Y289143D01*
G03X1829589Y289285I-200J0D01*
G01X1827731Y291143D01*
G03X1827589Y291202I-142J-141D01*
G01X1825145D01*
X1825135Y291212D01*
X1758059D01*
X1758049Y291202D01*
X1755888D01*
G03X1755746Y291143I0J-200D01*
G01X1754777Y290174D01*
X1754749Y290145D01*
X1754675Y290115D01*
X1750242D01*
G02X1750100Y290174I0J200D01*
G01X1748044Y292230D01*
X1748015Y292258D01*
X1747985Y292332D01*
Y305340D01*
G02X1748042Y305480I200J0D01*
G01X1749013Y306451D01*
G02X1749015Y306453I142J-140D01*
G02X1749155Y306510I140J-143D01*
G37*
G36*
G01X1687954Y832126D02*
G03I-656J0D01*
G37*
G36*
G01Y868937D02*
G03I-656J0D01*
G37*
G36*
G01Y905749D02*
G03I-656J0D01*
G37*
G36*
G01Y942560D02*
G03I-656J0D01*
G37*
G36*
G01Y1089804D02*
G03I-656J0D01*
G37*
G36*
G01Y1126615D02*
G03I-656J0D01*
G37*
G36*
G01Y1163426D02*
G03I-656J0D01*
G37*
G36*
G01Y1200237D02*
G03I-656J0D01*
G37*
G36*
G01Y1237048D02*
G03I-656J0D01*
G37*
G36*
G01X1685808Y1451231D02*
G03I-510J0D01*
G37*
G36*
G01X1681249Y1519682D02*
G03I-519J0D01*
G37*
G36*
G01X1683849Y1517772D02*
G03I-519J0D01*
G37*
G36*
G01X1683279Y1512169D02*
G03I-519J0D01*
G37*
G36*
G01X1680949Y1511198D02*
G03I-519J0D01*
G37*
G36*
G01X1678649Y1512992D02*
G03I-519J0D01*
G37*
G36*
G01Y1517772D02*
G03I-519J0D01*
G37*
G36*
G01X1681249Y1533082D02*
G03I-519J0D01*
G37*
G36*
G01X1678649Y1531172D02*
G03I-519J0D01*
G37*
G36*
G01X1683849D02*
G03I-519J0D01*
G37*
G36*
G01Y1526392D02*
G03I-519J0D01*
G37*
G36*
G01X1681249Y1524482D02*
G03I-519J0D01*
G37*
G36*
G01X1678649Y1526392D02*
G03I-519J0D01*
G37*
G36*
G01X1685757Y1683018D02*
Y1689218D01*
X1686057Y1689518D01*
X1689157D01*
X1689657Y1690018D01*
Y1692718D01*
X1689757Y1692818D01*
X1690357D01*
X1690457Y1692718D01*
Y1689918D01*
X1690857Y1689518D01*
X1692057D01*
X1692357Y1689218D01*
Y1683418D01*
X1691857Y1682918D01*
X1685857D01*
X1685757Y1683018D01*
G37*
G36*
G01X1679930Y1683597D02*
G03I-510J0D01*
G37*
G36*
G01X1683523Y1713684D02*
G03I-510J0D01*
G37*
G36*
G01X1681029Y1726825D02*
G03I-510J0D01*
G37*
G36*
G01X1706814Y77839D02*
G03I-720J0D01*
G37*
G36*
G01X1697910Y394082D02*
X1719520D01*
X1720960Y392642D01*
Y377712D01*
X1719648Y376400D01*
X1704438D01*
X1702760Y374722D01*
Y372702D01*
X1700550D01*
X1699650Y373602D01*
Y377282D01*
X1696550Y380382D01*
Y392722D01*
X1697910Y394082D01*
G37*
G36*
G01X1700594Y408505D02*
Y409005D01*
X1700824Y409235D01*
X1704014D01*
X1707754D01*
X1708444Y408545D01*
X1711444D01*
X1711944Y408045D01*
Y406545D01*
X1711444Y406045D01*
X1707204D01*
X1703054D01*
X1700594Y408505D01*
G37*
G36*
G01X1720869Y422680D02*
Y412185D01*
X1708918D01*
X1708743Y412360D01*
X1706668D01*
X1706492Y412185D01*
X1696984D01*
X1696704Y412465D01*
Y412915D01*
X1696914Y413125D01*
X1703424D01*
X1704484Y414185D01*
Y415425D01*
X1703734Y416175D01*
X1698874D01*
X1698684Y416365D01*
Y416985D01*
X1698814Y417115D01*
X1708154D01*
X1709506Y418466D01*
X1716034D01*
X1716538Y418970D01*
X1716920Y419352D01*
Y425252D01*
X1717520Y425852D01*
X1720320D01*
X1720820Y425352D01*
Y422652D01*
X1720830Y422642D01*
X1720869Y422680D01*
G37*
G36*
G01X1704096Y791969D02*
G03I-656J0D01*
G37*
G36*
G01Y828780D02*
G03I-656J0D01*
G37*
G36*
G01Y865591D02*
G03I-656J0D01*
G37*
G36*
G01Y902402D02*
G03I-656J0D01*
G37*
G36*
G01Y939213D02*
G03I-656J0D01*
G37*
G36*
G01Y1086457D02*
G03I-656J0D01*
G37*
G36*
G01Y1123268D02*
G03I-656J0D01*
G37*
G36*
G01Y1160079D02*
G03I-656J0D01*
G37*
G36*
G01Y1233701D02*
G03I-656J0D01*
G37*
G36*
G01X1792607Y1654769D02*
X1826088D01*
G02X1826230Y1654710I0J-200D01*
G01X1826785Y1654155D01*
G02X1826844Y1654013I-141J-142D01*
G01Y1606362D01*
G03X1826903Y1606220I200J0D01*
G01X1837547Y1595576D01*
G02X1837606Y1595434I-141J-142D01*
G01Y1473773D01*
G02X1837547Y1473631I-200J0D01*
G01X1836605Y1472689D01*
G02X1836463Y1472630I-142J141D01*
G01X1734391D01*
G02X1734249Y1472689I0J200D01*
G01X1732628Y1474310D01*
G02X1732569Y1474452I141J142D01*
G01Y1494475D01*
G02X1732628Y1494617I200J0D01*
G01X1733623Y1495612D01*
G02X1733765Y1495671I142J-141D01*
G01X1827947D01*
G03X1828089Y1495730I0J200D01*
G01X1830424Y1498065D01*
G03X1830483Y1498207I-141J142D01*
G01Y1530895D01*
G03X1830424Y1531037I-200J0D01*
G01X1827594Y1533867D01*
G03X1827452Y1533926I-142J-141D01*
G01X1809752D01*
X1809728Y1533950D01*
X1732858D01*
G02X1732716Y1534009I0J200D01*
G01X1732185Y1534540D01*
G02X1732126Y1534682I141J142D01*
G01Y1539047D01*
G03X1732067Y1539189I-200J0D01*
G01X1731316Y1539940D01*
G02X1731287Y1540185I142J141D01*
G03X1731507Y1540968I-1283J783D01*
G03X1730004Y1542471I-1503J0D01*
G03X1729221Y1542251I0J-1503D01*
G02X1728976Y1542280I-104J171D01*
G01X1725999Y1545257D01*
G03X1725857Y1545316I-142J-141D01*
G01X1705490D01*
G02X1705348Y1545375I0J200D01*
G01X1703314Y1547409D01*
G02X1703255Y1547551I141J142D01*
G01Y1581701D01*
G02X1703314Y1581843I200J0D01*
G01X1704277Y1582806D01*
G02X1704419Y1582865I142J-141D01*
G01X1722265D01*
G02X1722407Y1582806I0J-200D01*
G01X1727044Y1578169D01*
G02X1727103Y1578027I-141J-142D01*
G01Y1568367D01*
G03X1727162Y1568225I200J0D01*
G01X1731223Y1564164D01*
G03X1731365Y1564105I142J141D01*
G01X1739836D01*
X1739910Y1564075D01*
X1739938Y1564046D01*
X1739992Y1563992D01*
G02X1740051Y1563850I-141J-142D01*
G01Y1561315D01*
G03X1740110Y1561173I200J0D01*
G01X1740391Y1560892D01*
G03X1740533Y1560833I142J141D01*
G01X1742552D01*
X1742558Y1560827D01*
X1748675D01*
G03X1748817Y1560886I0J200D01*
G01X1748899Y1560968D01*
G03X1748958Y1561110I-141J142D01*
G01Y1564144D01*
G03X1748899Y1564286I-200J0D01*
G01X1748117Y1565068D01*
G03X1747975Y1565127I-142J-141D01*
G01X1745740D01*
G02X1745540Y1565327I0J200D01*
G01Y1570295D01*
G03X1745481Y1570437I-200J0D01*
G01X1745318Y1570600D01*
G03X1745177Y1570658I-141J-142D01*
G01X1741882D01*
G02X1741740Y1570717I0J200D01*
G01X1741738Y1570719D01*
G02X1741679Y1570861I141J142D01*
G01Y1571378D01*
G02X1741879Y1571578I200J0D01*
G01X1745196D01*
G03X1745338Y1571637I0J200D01*
G01X1745516Y1571815D01*
G03X1745575Y1571957I-141J142D01*
G01Y1572670D01*
G02X1745775Y1572870I200J0D01*
G01X1752321D01*
G02X1752521Y1572670I0J-200D01*
G01Y1564047D01*
G03X1752580Y1563905I200J0D01*
G01X1752843Y1563642D01*
G03X1752985Y1563583I142J141D01*
G01X1763322D01*
G03X1763464Y1563642I0J200D01*
G01X1763844Y1564022D01*
G02X1763986Y1564081I142J-141D01*
G01X1769005D01*
G03X1769147Y1564140I0J200D01*
G01X1769580Y1564573D01*
G02X1769722Y1564632I142J-141D01*
G01X1775151D01*
X1775225Y1564602D01*
X1775253Y1564573D01*
X1775735Y1564091D01*
G02X1775794Y1563949I-141J-142D01*
G01Y1561315D01*
G03X1775853Y1561173I200J0D01*
G01X1776134Y1560892D01*
G03X1776276Y1560833I142J141D01*
G01X1778295D01*
X1778301Y1560827D01*
X1784418D01*
G03X1784560Y1560886I0J200D01*
G01X1784642Y1560968D01*
G03X1784701Y1561110I-141J142D01*
G01Y1564144D01*
G03X1784642Y1564286I-200J0D01*
G01X1783860Y1565068D01*
G03X1783718Y1565127I-142J-141D01*
G01X1781334D01*
X1781326Y1565135D01*
Y1570196D01*
G03X1781268Y1570337I-200J0D01*
G01X1781012Y1570593D01*
G03X1780870Y1570652I-142J-141D01*
G01X1777688D01*
G02X1777546Y1570711I0J200D01*
G01X1777538Y1570719D01*
G02X1777479Y1570861I141J142D01*
G01Y1571378D01*
G02X1777679Y1571578I200J0D01*
G01X1780749D01*
G03X1780891Y1571637I0J200D01*
G01X1781273Y1572019D01*
G03X1781332Y1572161I-141J142D01*
G01Y1572829D01*
X1781340Y1572837D01*
X1788069D01*
G02X1788269Y1572637I0J-200D01*
G01Y1564042D01*
G03X1788328Y1563900I200J0D01*
G01X1788586Y1563642D01*
G03X1788728Y1563583I142J141D01*
G01X1804621D01*
G03X1804763Y1563642I0J200D01*
G01X1805815Y1564694D01*
G03X1805874Y1564836I-141J142D01*
G01Y1594979D01*
G02X1805933Y1595121I200J0D01*
G01X1805960Y1595148D01*
Y1625615D01*
G03X1805901Y1625757I-200J0D01*
G01X1804795Y1626863D01*
G03X1804653Y1626922I-142J-141D01*
G01X1792500D01*
G02X1792358Y1626981I0J200D01*
G01X1791142Y1628197D01*
G02X1791083Y1628339I141J142D01*
G01Y1653245D01*
G02X1791142Y1653387I200J0D01*
G01X1792465Y1654710D01*
G02X1792607Y1654769I142J-141D01*
G37*
G36*
G01X1705332Y1694243D02*
G03I-510J0D01*
G37*
G36*
G01X1703495Y1700328D02*
G03I-510J0D01*
G37*
G36*
G01X1720658Y22910D02*
G03I-510J0D01*
G37*
G36*
G01X1733180Y35608D02*
X1736003D01*
G02X1736145Y35549I0J-200D01*
G01X1736927Y34767D01*
G02X1736986Y34625I-141J-142D01*
G01Y27591D01*
G02X1736927Y27449I-200J0D01*
G01X1735845Y26367D01*
G02X1735703Y26308I-142J141D01*
G01X1723614D01*
X1723513Y26378D01*
X1723491Y26437D01*
G03X1722085Y27410I-1406J-529D01*
G01X1722083D01*
G03X1721757Y27374I1J-1502D01*
G01X1721706Y27362D01*
X1721609Y27391D01*
X1721245Y27755D01*
G02X1721186Y27896I141J142D01*
G01Y35325D01*
G02X1721245Y35467I200J0D01*
G01X1721327Y35549D01*
G02X1721469Y35608I142J-141D01*
G01X1722464D01*
G02X1722664Y35422I0J-201D01*
G01Y29905D01*
X1722866Y29702D01*
X1723330D01*
X1723532Y29905D01*
Y35422D01*
G02X1723732Y35608I200J-15D01*
G01X1724826D01*
G02X1725026Y35422I0J-201D01*
G01Y29905D01*
X1725228Y29702D01*
X1725692D01*
X1725894Y29905D01*
Y35422D01*
G02X1726094Y35608I200J-15D01*
G01X1727188D01*
G02X1727388Y35422I0J-201D01*
G01Y29905D01*
X1727590Y29702D01*
X1728054D01*
X1728256Y29905D01*
Y35422D01*
G02X1728456Y35608I200J-15D01*
G01X1729550D01*
G02X1729750Y35422I0J-201D01*
G01Y29905D01*
X1729952Y29702D01*
X1730416D01*
X1730618Y29905D01*
Y35422D01*
G02X1730818Y35608I200J-15D01*
G01X1731914D01*
G02X1732112Y35432I0J-199D01*
G01Y29905D01*
X1732315Y29702D01*
X1732779D01*
X1732982Y29905D01*
Y35432D01*
G02X1733180Y35608I198J-23D01*
G37*
G36*
G01X1739328Y67340D02*
Y38815D01*
X1738831Y38318D01*
X1722349D01*
G02X1722207Y38377I0J200D01*
G01X1721255Y39329D01*
X1721226Y39357D01*
X1721196Y39431D01*
Y48575D01*
Y49911D01*
X1723569Y52284D01*
X1724822D01*
X1729847D01*
X1730345D01*
X1730967Y51662D01*
X1733567D01*
X1734300Y52395D01*
Y52864D01*
Y55012D01*
Y65268D01*
X1731993Y67575D01*
X1725107D01*
X1724067Y68615D01*
Y81146D01*
X1724927Y82006D01*
X1733648D01*
X1735683Y84041D01*
Y85782D01*
X1736068Y86167D01*
X1737628D01*
X1737854Y85941D01*
Y82865D01*
X1739328Y81391D01*
Y80045D01*
Y67340D01*
G37*
G36*
G01X1708724Y75340D02*
G03I-720J0D01*
G37*
G36*
G01X1721184Y93413D02*
Y106613D01*
X1721384Y106813D01*
X1723884D01*
X1723984Y106713D01*
Y97243D01*
X1724859Y96368D01*
X1728060D01*
X1728484Y95944D01*
Y95013D01*
Y93440D01*
X1727577Y92533D01*
X1722064D01*
X1721184Y93413D01*
G37*
G36*
G01X1723284Y111613D02*
Y117913D01*
X1722884Y118313D01*
X1719184D01*
X1718484Y117613D01*
Y112213D01*
X1719184Y111513D01*
X1723184D01*
X1723284Y111613D01*
G37*
G36*
G01X1707198Y169299D02*
Y171727D01*
X1707798Y172327D01*
X1727927D01*
X1735638D01*
X1736398Y171567D01*
Y171067D01*
Y152967D01*
X1735898Y152467D01*
X1709798D01*
X1707798D01*
X1707198Y153067D01*
Y169299D01*
G37*
G36*
G01X1718751Y652105D02*
G03I-510J0D01*
G37*
G36*
G01X1708815Y679720D02*
G03I-510J0D01*
G37*
G36*
G01X1717655Y795315D02*
G03I-656J0D01*
G37*
G36*
G01Y832126D02*
G03I-656J0D01*
G37*
G36*
G01Y868937D02*
G03I-656J0D01*
G37*
G36*
G01Y905749D02*
G03I-656J0D01*
G37*
G36*
G01Y942560D02*
G03I-656J0D01*
G37*
G36*
G01Y1089804D02*
G03I-656J0D01*
G37*
G36*
G01Y1126615D02*
G03I-656J0D01*
G37*
G36*
G01Y1163426D02*
G03I-656J0D01*
G37*
G36*
G01Y1200237D02*
G03I-656J0D01*
G37*
G36*
G01Y1237048D02*
G03I-656J0D01*
G37*
G36*
G01X1717487Y1614772D02*
X1721308D01*
G02X1721450Y1614713I0J-200D01*
G01X1721785Y1614378D01*
G02X1721844Y1614236I-141J-142D01*
G01Y1594569D01*
G02X1721785Y1594427I-200J0D01*
G01X1721330Y1593972D01*
G02X1721188Y1593913I-142J141D01*
G01X1717520D01*
G02X1717378Y1593972I0J200D01*
G01X1717157Y1594193D01*
G02X1717098Y1594335I141J142D01*
G01Y1596658D01*
X1717109Y1596690D01*
G03X1717195Y1597190I-1416J501D01*
G03X1717109Y1597690I-1502J-1D01*
G01X1717098Y1597722D01*
Y1614383D01*
G02X1717157Y1614525I200J0D01*
G01X1717345Y1614713D01*
G02X1717487Y1614772I142J-141D01*
G37*
G36*
G01X1719659Y1703190D02*
G03I-510J0D01*
G37*
G36*
G01X1727741Y-38849D02*
G03I-630J0D01*
G37*
G36*
G01Y-28849D02*
G03I-630J0D01*
G37*
G36*
G01Y-19575D02*
G03I-630J0D01*
G37*
G36*
G01X1732206Y65585D02*
Y59556D01*
X1733280Y58482D01*
Y56590D01*
X1733272Y56582D01*
Y53097D01*
X1732911Y52736D01*
X1731600D01*
X1730808Y53528D01*
X1729202D01*
X1725809D01*
X1725447Y53890D01*
Y57283D01*
Y65313D01*
X1725999Y65865D01*
X1731926D01*
X1732206Y65585D01*
G37*
G36*
G01X1734066Y88972D02*
Y107063D01*
X1732744D01*
X1732444Y106763D01*
Y102530D01*
X1730644Y100730D01*
Y93203D01*
X1728037Y90596D01*
Y90008D01*
Y89312D01*
X1728603Y88746D01*
X1733840D01*
X1734066Y88972D01*
G37*
G36*
G01X1735294Y107083D02*
X1749734D01*
X1749880Y106937D01*
Y101590D01*
X1749934Y98342D01*
X1754323Y93953D01*
Y68644D01*
X1755316Y67651D01*
G03X1755375Y67509I200J0D01*
G01X1756052Y66832D01*
G03X1756194Y66773I142J141D01*
G01X1757668D01*
X1757686Y66769D01*
G03X1758047Y66736I353J1869D01*
G01X1760463D01*
G03X1760824Y66769I8J1902D01*
G01X1760842Y66773D01*
X1774366D01*
Y66798D01*
X1777017Y69449D01*
G03X1777076Y69591I-141J142D01*
G01Y85725D01*
G02X1777135Y85867I200J0D01*
G01X1777237Y85969D01*
G02X1777379Y86028I142J-141D01*
G01X1777673D01*
G02X1777815Y85969I0J-200D01*
G01X1777887Y85897D01*
G02X1777946Y85755I-141J-142D01*
G01Y78871D01*
G03X1778005Y78729I200J0D01*
G01X1778337Y78397D01*
G03X1778479Y78338I142J141D01*
G01X1780383D01*
G03X1780525Y78397I0J200D01*
G01X1780853Y78725D01*
G02X1780929Y78773I142J-141D01*
G01X1780984Y78828D01*
G03X1781043Y78970I-141J142D01*
G01Y83671D01*
G02X1781102Y83813I200J0D01*
G01X1781248Y83959D01*
G02X1781390Y84018I142J-141D01*
G01X1781550D01*
G02X1781692Y83959I0J-200D01*
G01X1781887Y83764D01*
G02X1781946Y83622I-141J-142D01*
G01Y83490D01*
X1781966Y83470D01*
Y73321D01*
G03X1782025Y73179I200J0D01*
G01X1788372Y66832D01*
G03X1788514Y66773I142J141D01*
G01X1792256D01*
G02X1792398Y66714I0J-200D01*
G01X1792985Y66127D01*
G02X1793044Y65985I-141J-142D01*
G01Y55789D01*
G02X1792985Y55647I-200J0D01*
G01X1792285Y54947D01*
X1792257Y54918D01*
X1792183Y54888D01*
X1785760D01*
X1784130Y56518D01*
X1765934D01*
X1764761Y55345D01*
X1764760Y55344D01*
X1764362Y54947D01*
G02X1764220Y54888I-142J141D01*
G01X1741323D01*
X1740850Y55361D01*
Y81750D01*
X1740806Y81794D01*
Y83068D01*
X1741213Y83475D01*
X1745115D01*
X1745646Y84006D01*
Y93813D01*
X1744018Y95441D01*
X1738996D01*
X1738273Y94718D01*
Y89291D01*
X1737821Y88839D01*
X1735331D01*
X1735094Y89076D01*
Y106883D01*
G02X1735294Y107083I200J0D01*
G37*
G36*
G01X1727984Y106813D02*
X1725484D01*
X1724990Y106319D01*
Y98449D01*
X1725178Y98260D01*
X1728161D01*
X1728584Y98683D01*
Y106213D01*
X1727984Y106813D01*
G37*
G36*
G01X1757153Y118213D02*
X1784591D01*
G02X1784733Y118154I0J-200D01*
G01X1789945Y112942D01*
G02X1790004Y112800I-141J-142D01*
G01Y104451D01*
G02X1789945Y104309I-200J0D01*
G01X1789723Y104087D01*
G02X1789581Y104028I-142J141D01*
G01X1781279D01*
G03X1781137Y103969I0J-200D01*
G01X1779855Y102687D01*
G03X1779796Y102545I141J-142D01*
G01Y99601D01*
G03X1779855Y99459I200J0D01*
G01X1779857Y99457D01*
G02X1779916Y99315I-141J-142D01*
G01Y89594D01*
G02X1779874Y89471I-200J0D01*
G03Y87005I1576J-1233D01*
G02X1779916Y86882I-158J-123D01*
G01Y79511D01*
G02X1779857Y79369I-200J0D01*
G01X1779828Y79340D01*
X1779287D01*
G02X1779146Y79398I0J200D01*
G01X1779065Y79479D01*
G02X1779006Y79621I141J142D01*
G01Y86125D01*
G03X1778947Y86267I-200J0D01*
G01X1778426Y86788D01*
X1778412D01*
X1778229Y86971D01*
G03X1778088Y87030I-142J-141D01*
G01X1776964D01*
G03X1776823Y86971I1J-200D01*
G01X1776698Y86847D01*
G02X1776557Y86788I-142J141D01*
G01X1776429D01*
G03X1776287Y86729I0J-200D01*
G01X1776005Y86447D01*
G03X1775946Y86305I141J-142D01*
G01Y81451D01*
G02X1775887Y81309I-200J0D01*
G01X1775855Y81277D01*
G02X1775713Y81218I-142J141D01*
G01X1775389D01*
G02X1775247Y81277I0J200D01*
G01X1775095Y81429D01*
G02X1775036Y81571I141J142D01*
G01Y86891D01*
G02X1775085Y87023I200J1D01*
G03X1775579Y88339I-1508J1317D01*
G03X1775085Y89655I-2002J-1D01*
G02X1775036Y89787I151J131D01*
G01Y97555D01*
G03X1774977Y97697I-200J0D01*
G01X1773325Y99349D01*
G03X1773183Y99408I-142J-141D01*
G01X1767469D01*
G02X1767327Y99467I0J200D01*
G01X1764145Y102649D01*
G03X1764003Y102708I-142J-141D01*
G01X1757172D01*
G02X1757030Y102767I0J200D01*
G01X1751638Y108159D01*
G03X1751496Y108218I-142J-141D01*
G01X1734962D01*
G02X1734820Y108277I0J200D01*
G01X1734643Y108454D01*
G02X1734584Y108596I141J142D01*
G01Y113330D01*
G02X1734643Y113472I200J0D01*
G01X1734825Y113654D01*
G02X1734967Y113713I142J-141D01*
G01X1752487D01*
G03X1752629Y113772I0J200D01*
G01X1757011Y118154D01*
G02X1757153Y118213I142J-141D01*
G37*
G36*
G01X1725776Y119698D02*
X1732296D01*
X1734086Y117908D01*
Y115108D01*
X1733886Y114908D01*
X1724786D01*
X1724386Y115308D01*
Y118308D01*
X1725776Y119698D01*
G37*
G36*
G01X1727384Y127313D02*
X1737484D01*
X1737784Y127613D01*
Y130113D01*
X1738384Y130713D01*
X1744284D01*
X1745384Y129613D01*
Y127930D01*
X1746164Y127150D01*
X1748627D01*
X1749020Y127543D01*
Y135700D01*
X1748307Y136413D01*
X1728084D01*
X1724584D01*
X1724024Y135853D01*
Y127653D01*
X1724364Y127313D01*
X1727384D01*
G37*
G36*
G01X1826990Y284694D02*
Y260882D01*
X1826237Y260129D01*
X1758544D01*
X1729163D01*
X1726613Y262679D01*
Y280078D01*
X1729206Y282671D01*
X1747860D01*
X1750474Y285285D01*
Y288213D01*
X1750972Y288711D01*
X1753900D01*
X1756974D01*
X1758474Y290211D01*
X1802581D01*
X1824720D01*
X1826990Y287941D01*
Y284694D01*
G37*
G36*
G01X1746971Y301157D02*
Y284755D01*
X1746771Y284555D01*
X1734371D01*
X1734171Y284755D01*
Y290629D01*
X1733280Y291520D01*
X1729780D01*
X1728330Y292970D01*
Y309480D01*
X1733025Y314175D01*
X1740010D01*
X1745956D01*
X1746971Y313160D01*
Y310436D01*
Y304985D01*
Y301157D01*
G37*
G36*
G01X1733593Y654034D02*
G03I-510J0D01*
G37*
G36*
G01X1733797Y791969D02*
G03I-656J0D01*
G37*
G36*
G01Y865591D02*
G03I-656J0D01*
G37*
G36*
G01Y902402D02*
G03I-656J0D01*
G37*
G36*
G01Y939213D02*
G03I-656J0D01*
G37*
G36*
G01Y1086457D02*
G03I-656J0D01*
G37*
G36*
G01Y1123268D02*
G03I-656J0D01*
G37*
G36*
G01Y1160079D02*
G03I-656J0D01*
G37*
G36*
G01Y1196890D02*
G03I-656J0D01*
G37*
G36*
G01Y1233701D02*
G03I-656J0D01*
G37*
G36*
G01X1746303Y1424574D02*
Y1409000D01*
X1745803Y1408500D01*
X1730650D01*
X1730150Y1409000D01*
Y1438020D01*
X1730487Y1438357D01*
X1732256D01*
X1740184D01*
X1740923Y1437618D01*
Y1429954D01*
X1746303Y1424574D01*
G37*
G36*
G01X1732389Y1532414D02*
X1732113Y1532138D01*
Y1528469D01*
Y1503846D01*
Y1498472D01*
X1733684Y1496901D01*
X1826927D01*
X1828713Y1498687D01*
Y1500936D01*
Y1505141D01*
Y1530353D01*
X1826652Y1532414D01*
X1732389D01*
G37*
G36*
G01X1740560Y1638200D02*
X1742256D01*
X1743779D01*
X1765434D01*
X1765885Y1637749D01*
Y1629314D01*
X1764221Y1627650D01*
X1759579D01*
X1757506D01*
X1757491Y1627635D01*
X1756212D01*
X1755119Y1626542D01*
Y1611987D01*
X1756079Y1611027D01*
X1759587Y1607519D01*
Y1607221D01*
Y1595309D01*
Y1592473D01*
X1758517Y1591403D01*
X1737564D01*
X1735018Y1593949D01*
Y1634872D01*
X1738346Y1638200D01*
X1740560D01*
G37*
G36*
G01X1722643Y1725340D02*
G03I-510J0D01*
G37*
G36*
G01X1748626Y37058D02*
G03I-510J0D01*
G37*
G36*
G01X1773404Y84113D02*
X1773734D01*
X1774034Y83813D01*
Y81373D01*
X1773874Y81213D01*
X1771354D01*
X1771034D01*
X1768364Y78543D01*
X1762276D01*
X1761734Y78001D01*
Y75543D01*
X1761534Y75343D01*
X1757734D01*
X1755974D01*
X1755644Y75673D01*
Y94766D01*
X1750920Y99490D01*
Y101210D01*
X1751118Y101408D01*
X1754896D01*
X1758096Y98208D01*
X1769286D01*
X1769644Y97850D01*
Y94473D01*
Y91873D01*
X1769444Y91673D01*
X1760244D01*
X1759244Y90673D01*
Y89373D01*
X1760257Y88360D01*
X1762217D01*
X1762434Y88143D01*
Y82643D01*
Y82166D01*
X1762830Y81770D01*
X1765437D01*
X1765800Y82133D01*
X1771424D01*
X1772684D01*
X1773114Y82563D01*
Y83823D01*
X1773404Y84113D01*
G37*
G36*
G01X1743162Y671494D02*
G03I-510J0D01*
G37*
G36*
G01X1746012Y660088D02*
G03I-510J0D01*
G37*
G36*
G01X1747356Y795315D02*
G03I-656J0D01*
G37*
G36*
G01Y832126D02*
G03I-656J0D01*
G37*
G36*
G01Y868937D02*
G03I-656J0D01*
G37*
G36*
G01Y905749D02*
G03I-656J0D01*
G37*
G36*
G01Y942560D02*
G03I-656J0D01*
G37*
G36*
G01Y1089804D02*
G03I-656J0D01*
G37*
G36*
G01Y1126615D02*
G03I-656J0D01*
G37*
G36*
G01Y1163426D02*
G03I-656J0D01*
G37*
G36*
G01Y1200237D02*
G03I-656J0D01*
G37*
G36*
G01Y1237048D02*
G03I-656J0D01*
G37*
G36*
G01X1762930Y17031D02*
G03I-510J0D01*
G37*
G36*
G01X1752728Y25146D02*
G03I-720J0D01*
G37*
G36*
G01X1765027Y135273D02*
X1796348D01*
G02X1796490Y135214I0J-200D01*
G01X1797289Y134415D01*
G02X1797344Y134236I-141J-141D01*
G01X1797273Y133862D01*
X1797211Y133785D01*
X1797165Y133765D01*
G03X1792196Y126194I3283J-7571D01*
G03X1798200Y118254I8252J0D01*
G02X1798346Y118061I-54J-193D01*
G01Y73401D01*
G03X1798405Y73259I200J0D01*
G01X1805947Y65717D01*
G03X1806089Y65658I142J141D01*
G01X1807470D01*
X1807543Y65627D01*
X1807572Y65599D01*
G03X1811771Y62051I22351J22194D01*
G02X1811856Y61888I-115J-164D01*
G01Y55401D01*
G02X1811797Y55259I-200J0D01*
G01X1811298Y54760D01*
G02X1811156Y54701I-142J141D01*
G01X1795407D01*
G02X1795265Y54760I0J200D01*
G01X1795003Y55022D01*
G02X1794944Y55164I141J142D01*
G01Y63690D01*
G02X1795003Y63832I200J0D01*
G01X1795863Y64693D01*
G03X1795922Y64835I-141J142D01*
G01Y100159D01*
G03X1795863Y100301I-200J0D01*
G01X1791303Y104861D01*
G02X1791244Y105003I141J142D01*
G01Y113390D01*
G03X1791185Y113532I-200J0D01*
G01X1785503Y119214D01*
G03X1785361Y119273I-142J-141D01*
G01X1763127D01*
G02X1762985Y119332I0J200D01*
G01X1762974Y119343D01*
X1762944Y119416D01*
Y133190D01*
G02X1763003Y133332I200J0D01*
G01X1764885Y135214D01*
G02X1765027Y135273I142J-141D01*
G37*
G36*
G01X1763498Y791969D02*
G03I-656J0D01*
G37*
G36*
G01Y865591D02*
G03I-656J0D01*
G37*
G36*
G01Y902402D02*
G03I-656J0D01*
G37*
G36*
G01Y939213D02*
G03I-656J0D01*
G37*
G36*
G01Y1086457D02*
G03I-656J0D01*
G37*
G36*
G01Y1160079D02*
G03I-656J0D01*
G37*
G36*
G01Y1196890D02*
G03I-656J0D01*
G37*
G36*
G01Y1233701D02*
G03I-656J0D01*
G37*
G36*
G01X1757440Y1625010D02*
X1803778D01*
G02X1803920Y1624951I0J-200D01*
G01X1804468Y1624403D01*
G02X1804527Y1624261I-141J-142D01*
G01Y1565792D01*
G02X1804468Y1565650I-200J0D01*
G01X1803811Y1564993D01*
G02X1803669Y1564934I-142J141D01*
G01X1789780D01*
X1789760Y1564954D01*
Y1573036D01*
X1789785Y1573061D01*
X1795240D01*
G03X1795382Y1573120I0J200D01*
G01X1795838Y1573576D01*
G03X1795897Y1573718I-141J142D01*
G01Y1577349D01*
G02X1795954Y1577489I200J0D01*
G01X1795955Y1577490D01*
X1797074Y1578608D01*
G03X1797133Y1578750I-141J142D01*
G01Y1578882D01*
G02X1797135Y1578906I200J-5D01*
G01X1797137Y1578925D01*
G02X1797162Y1579000I198J-24D01*
G01X1797169Y1579012D01*
X1797184Y1579041D01*
G03X1797281Y1579445I-795J404D01*
G01Y1580300D01*
G03X1797222Y1580442I-200J0D01*
G01X1797164Y1580500D01*
X1797133D01*
Y1582427D01*
X1797143Y1582448D01*
Y1582451D01*
X1797153Y1582471D01*
G03X1797295Y1583107I-1359J637D01*
G03X1797283Y1583299I-1501J3D01*
G01X1797281Y1583312D01*
Y1583619D01*
G03X1797160Y1584068I-892J0D01*
G01X1797147Y1584091D01*
X1797133Y1584141D01*
Y1584422D01*
G03X1797074Y1584564I-200J0D01*
G01X1796115Y1585523D01*
G03X1795973Y1585582I-142J-141D01*
G01X1793822D01*
X1793748Y1585612D01*
X1793720Y1585641D01*
X1793485Y1585876D01*
G02X1793455Y1586121I141J142D01*
G03X1793730Y1587105I-1626J985D01*
G03X1793445Y1588106I-1900J0D01*
G01X1793430Y1588130D01*
X1793415Y1588183D01*
Y1588239D01*
X1793298Y1588356D01*
X1793279D01*
Y1589322D01*
G03X1793220Y1589464I-200J0D01*
G01X1792738Y1589946D01*
G03X1792596Y1590005I-142J-141D01*
G01X1791424D01*
G02X1791283Y1590063I0J200D01*
G01X1791025Y1590320D01*
G03X1790884Y1590379I-142J-141D01*
G01X1789379D01*
G03X1787723Y1589410I0J-1900D01*
G01X1787721Y1589407D01*
X1787717Y1589400D01*
G02X1787546Y1589305I-170J105D01*
G01X1769462D01*
G03X1769320Y1589246I0J-200D01*
G01X1767338Y1587264D01*
G03X1767279Y1587122I141J-142D01*
G01Y1580988D01*
G03X1767338Y1580846I200J0D01*
G01X1767969Y1580215D01*
G02X1767971Y1580213I-140J-142D01*
G02X1768028Y1580073I-143J-140D01*
G01Y1565708D01*
Y1565706D01*
Y1565667D01*
X1767998Y1565593D01*
X1767573Y1565168D01*
G02X1767431Y1565109I-142J141D01*
G01X1763427D01*
G03X1763285Y1565050I0J-200D01*
G01X1763240Y1565005D01*
G02X1763098Y1564946I-142J141D01*
G01X1754219D01*
G02X1754019Y1565146I0J200D01*
G01Y1573063D01*
X1754045Y1573089D01*
X1759525D01*
G03X1759667Y1573148I0J200D01*
G01X1760095Y1573576D01*
G03X1760154Y1573718I-141J142D01*
G01Y1577349D01*
G02X1760211Y1577489I200J0D01*
G01X1760212Y1577490D01*
X1761402Y1578680D01*
G03X1761461Y1578822I-141J142D01*
G01Y1578832D01*
X1761663Y1579034D01*
Y1584923D01*
X1761422Y1585164D01*
Y1608077D01*
G03X1761363Y1608219I-200J0D01*
G01X1756945Y1612637D01*
G02X1756886Y1612779I141J142D01*
G01Y1624456D01*
G02X1756943Y1624596I200J0D01*
G01X1756944Y1624597D01*
X1757298Y1624951D01*
G02X1757440Y1625010I142J-141D01*
G37*
G36*
G01X1759998Y1675700D02*
Y1675697D01*
X1759987Y1675686D01*
X1757568D01*
X1757539Y1675715D01*
Y1675813D01*
Y1676871D01*
X1757548Y1676880D01*
Y1680865D01*
Y1686450D01*
X1757963Y1686865D01*
X1764463D01*
X1764663Y1686665D01*
Y1683465D01*
X1763663Y1682465D01*
X1761963D01*
X1760463Y1680965D01*
Y1676165D01*
X1759998Y1675700D01*
G37*
G36*
G01X1776779Y1714960D02*
G02I-9850J0D01*
G37*
G36*
G01X1753374Y1716383D02*
G03I-510J0D01*
G37*
G36*
G01X1769930Y19506D02*
G03I-510J0D01*
G37*
G36*
G01X1777930D02*
G03I-510J0D01*
G37*
G36*
G01Y24506D02*
G03I-510J0D01*
G37*
G36*
G01X1771746Y557224D02*
G03I-510J0D01*
G37*
G36*
G01X1777056Y795315D02*
G03I-656J0D01*
G37*
G36*
G01Y832126D02*
G03I-656J0D01*
G37*
G36*
G01Y868937D02*
G03I-656J0D01*
G37*
G36*
G01Y905749D02*
G03I-656J0D01*
G37*
G36*
G01Y942560D02*
G03I-656J0D01*
G37*
G36*
G01Y1126615D02*
G03I-656J0D01*
G37*
G36*
G01Y1163426D02*
G03I-656J0D01*
G37*
G36*
G01Y1200237D02*
G03I-656J0D01*
G37*
G36*
G01Y1237048D02*
G03I-656J0D01*
G37*
G36*
G01X1787179Y1630150D02*
X1771779D01*
X1768554D01*
X1767814D01*
X1767039Y1630925D01*
Y1636714D01*
Y1638279D01*
X1767390Y1638630D01*
X1787143D01*
X1787818Y1637955D01*
Y1636589D01*
X1787779Y1636550D01*
Y1630750D01*
X1787179Y1630150D01*
G37*
G36*
G01X1775429Y1657956D02*
Y1654456D01*
X1774429Y1653456D01*
X1770429D01*
X1769929Y1653956D01*
Y1658456D01*
X1770429Y1658956D01*
X1774429D01*
X1775429Y1657956D01*
G37*
G36*
G01X1771892Y1686635D02*
X1776197D01*
G02X1776339Y1686576I0J-200D01*
G01X1776370Y1686545D01*
G02X1776429Y1686403I-141J-142D01*
G01Y1661705D01*
G02X1776370Y1661563I-200J0D01*
G01X1774823Y1660016D01*
G02X1774682Y1659958I-141J142D01*
G01X1770644D01*
G02X1770503Y1660016I0J200D01*
G01X1770122Y1660397D01*
G02X1770063Y1660539I141J142D01*
G01Y1686236D01*
G02X1770122Y1686378I200J0D01*
G01X1770280Y1686536D01*
G02X1770422Y1686595I142J-141D01*
G01X1771809D01*
X1771882Y1686625D01*
X1771892Y1686635D01*
G37*
G36*
G01X1855480Y67697D02*
Y54252D01*
G02X1849606Y48378I-5874J0D01*
G01X1803945D01*
G03X1794071Y38504I0J-9874D01*
G01Y14323D01*
G02X1793917Y14129I-200J1D01*
G01X1793471Y14023D01*
X1793345Y14082D01*
X1793314Y14144D01*
G03X1792158Y15493I-3307J-1664D01*
G02X1792074Y15656I116J163D01*
G01Y38506D01*
G02X1803945Y50376I11871J-1D01*
G01X1849606D01*
G03X1853482Y54252I0J3876D01*
G01Y66878D01*
X1854496Y67892D01*
X1855285D01*
X1855480Y67697D01*
G37*
G36*
G01X1783684Y83123D02*
X1783227D01*
X1782990Y83360D01*
Y90319D01*
X1783644Y90973D01*
Y90978D01*
X1784136Y91470D01*
Y93983D01*
X1784626Y94473D01*
X1785644D01*
X1786144Y93973D01*
Y89733D01*
Y85583D01*
X1783684Y83123D01*
G37*
G36*
G01X1783625Y721385D02*
X1814175D01*
X1816668Y718892D01*
Y699000D01*
G02X1816609Y698858I-200J0D01*
G01X1813694Y695943D01*
G02X1813552Y695884I-142J141D01*
G01X1786106D01*
X1782880Y699110D01*
Y705760D01*
X1784280Y707160D01*
X1788800D01*
X1788940Y707300D01*
Y710740D01*
X1788690Y710990D01*
X1784250D01*
X1782880Y712360D01*
Y720640D01*
X1783625Y721385D01*
G37*
G36*
G01X1793198Y828780D02*
G03I-656J0D01*
G37*
G36*
G01Y865591D02*
G03I-656J0D01*
G37*
G36*
G01Y902402D02*
G03I-656J0D01*
G37*
G36*
G01Y939213D02*
G03I-656J0D01*
G37*
G36*
G01Y1086457D02*
G03I-656J0D01*
G37*
G36*
G01Y1123268D02*
G03I-656J0D01*
G37*
G36*
G01Y1160079D02*
G03I-656J0D01*
G37*
G36*
G01Y1196890D02*
G03I-656J0D01*
G37*
G36*
G01Y1233701D02*
G03I-656J0D01*
G37*
G36*
G01X1852349Y308534D02*
X1843181Y317702D01*
G02X1839704Y326095I8394J8394D01*
G01Y610179D01*
G02X1839718Y610253I200J0D01*
G01X1839758Y610353D01*
X1839784Y610381D01*
G03X1840993Y611752I-23010J21510D01*
G01X1841013Y611776D01*
X1841065Y611809D01*
X1841095Y611818D01*
G02X1841215Y611813I52J-193D01*
G01X1841569Y611685D01*
G02X1841701Y611497I-68J-188D01*
G01Y326095D01*
G03X1844593Y319114I9874J1D01*
G01X1853760Y309947D01*
G02X1855480Y305795I-4153J-4153D01*
G01Y107849D01*
X1855324Y107693D01*
X1854830D01*
X1853482Y109041D01*
Y305796D01*
G03X1852349Y308534I-3876J0D01*
G37*
G36*
G01X1839758Y1347361D02*
G03X1840993Y1348761I-22993J21528D01*
G01X1841034Y1348809D01*
X1841156Y1348842D01*
X1841569Y1348693D01*
G02X1841701Y1348505I-68J-188D01*
G01Y652281D01*
G02X1841569Y652093I-200J0D01*
G01X1841156Y651944D01*
X1841034Y651977D01*
X1840993Y652025D01*
G03X1839758Y653425I-24228J-20128D01*
G02X1839704Y653562I146J137D01*
G01Y1347224D01*
G02X1839758Y1347361I200J0D01*
G37*
G36*
G01X1827955Y1692089D02*
G03X1829199Y1693335I-21660J22869D01*
G01X1829242Y1693380D01*
X1829361Y1693406D01*
X1829764Y1693246D01*
G02X1829890Y1693060I-74J-186D01*
G01Y1612316D01*
G03X1832782Y1605335I9874J1D01*
G01X1839981Y1598136D01*
G02X1841701Y1593984I-4153J-4153D01*
G01Y1389289D01*
G02X1841569Y1389101I-200J0D01*
G01X1841156Y1388952D01*
X1841034Y1388985D01*
X1840993Y1389033D01*
G03X1839758Y1390433I-24228J-20128D01*
G02X1839704Y1390570I146J137D01*
G01Y1413158D01*
Y1427428D01*
X1839715Y1427439D01*
G02X1839704Y1427504I189J65D01*
G01Y1593984D01*
G03X1838569Y1596724I-3876J0D01*
G01X1831370Y1603923D01*
G02X1827893Y1612316I8394J8394D01*
G01X1827892D01*
Y1691944D01*
G02X1827955Y1692089I200J-1D01*
G37*
%LPC*%
G75*
G36*
G01X90453Y1507656D02*
Y1512269D01*
X90394D01*
Y1516787D01*
X90364Y1516861D01*
X90335Y1516889D01*
X90150Y1517074D01*
G03X90008Y1517133I-142J-141D01*
G01X86373D01*
G02X86233Y1517191I1J200D01*
G01X86232Y1517192D01*
X86194Y1517229D01*
G03X85916I-139J-144D01*
G01X85878Y1517192D01*
X85877Y1517191D01*
G02X85737Y1517133I-141J142D01*
G01X83173D01*
G02X83032Y1517192I1J200D01*
G01X82462Y1517762D01*
G02X82404Y1517902I142J141D01*
G01Y1524468D01*
G02X82462Y1524608I200J-1D01*
G01X83032Y1525178D01*
G02X83173Y1525237I142J-141D01*
G01X85737D01*
G02X85878Y1525178I-1J-200D01*
G01X86448Y1524608D01*
G02X86506Y1524468I-142J-141D01*
G01Y1521893D01*
G03X86706Y1521693I200J0D01*
G01X90903D01*
G03X91102Y1521878I0J200D01*
G01Y1521905D01*
X91132Y1521978D01*
X91160Y1522006D01*
G02X91302Y1522065I142J-141D01*
G01X110594D01*
G02X110794Y1521879I0J-201D01*
G01X110800Y1521800D01*
X110914Y1521693D01*
X112137D01*
G02X112278Y1521634I-1J-200D01*
G01X113248Y1520664D01*
G02X113306Y1520524I-142J-141D01*
G01Y1514001D01*
X113307Y1514000D01*
Y1511305D01*
X113309Y1511303D01*
Y1508677D01*
G02X113250Y1508535I-200J0D01*
G01X111650Y1506935D01*
X111645D01*
G02X111503Y1506876I-142J141D01*
G01X91233D01*
G02X91091Y1506935I0J200D01*
G01X90512Y1507514D01*
G02X90453Y1507656I141J142D01*
G37*
G36*
G01X57662Y1508406D02*
Y1512269D01*
X57604D01*
Y1515570D01*
X57583Y1515633D01*
X57563Y1515658D01*
G03X57545Y1515679I-161J-119D01*
G01X56250Y1516974D01*
G03X56108Y1517033I-142J-141D01*
G01X50573D01*
G02X50432Y1517092I1J200D01*
G01X50346Y1517177D01*
G03X50069Y1517182I-141J-142D01*
G01X50050Y1517164D01*
X50014Y1517149D01*
G02X49936Y1517133I-78J184D01*
G01X47373D01*
G02X47232Y1517192I1J200D01*
G01X46662Y1517762D01*
G02X46604Y1517902I142J141D01*
G01Y1524468D01*
G02X46662Y1524608I200J-1D01*
G01X47232Y1525178D01*
G02X47373Y1525237I142J-141D01*
G01X49937D01*
G02X50078Y1525178I-1J-200D01*
G01X50648Y1524608D01*
G02X50706Y1524468I-142J-141D01*
G01Y1521893D01*
G03X50906Y1521693I200J0D01*
G01X55160D01*
G03X55358Y1521869I0J200D01*
G01Y1521905D01*
X55388Y1521978D01*
X55416Y1522006D01*
G02X55558Y1522065I142J-141D01*
G01X74852D01*
G02X75052Y1521879I0J-201D01*
G01X75058Y1521800D01*
X75172Y1521693D01*
X79506D01*
G02X79647Y1521634I-1J-200D01*
G01X80639Y1520642D01*
G02X80698Y1520501I-141J-142D01*
G01Y1512269D01*
X80690D01*
Y1507689D01*
G02X80631Y1507547I-200J0D01*
G01X79891Y1506807D01*
G02X79749Y1506748I-142J141D01*
G01X59320D01*
G02X59178Y1506807I0J200D01*
G01X57721Y1508264D01*
G02X57662Y1508406I141J142D01*
G37*
G36*
G01X188846Y734588D02*
G02X192747Y738490I3901J1D01*
G01X199647D01*
G02Y730686I0J-3902D01*
G01X192747D01*
G02X190181Y731649I1J3902D01*
G01X190140Y731685D01*
X190036Y731706D01*
X189607Y731561D01*
X189537Y731482D01*
X189526Y731429D01*
G02X188055Y730232I-1471J305D01*
G02Y733236I0J1502D01*
G02X188461Y733180I0J-1502D01*
G01X188513Y733166D01*
X188615Y733192D01*
X188941Y733506D01*
X188970Y733608D01*
X188957Y733660D01*
G02X188846Y734588I3790J924D01*
G37*
G36*
G01X163046Y730686D02*
G02Y738490I0J3902D01*
G01X169946D01*
G02Y730686I0J-3902D01*
G01X163046D01*
G37*
G36*
G01X133345D02*
G02Y738490I0J3902D01*
G01X140245D01*
G02Y730686I0J-3902D01*
G01X133345D01*
G37*
G36*
G01X103645D02*
G02Y738490I0J3902D01*
G01X110545D01*
G02Y730686I0J-3902D01*
G01X103645D01*
G37*
G36*
G01X73944D02*
G02Y738490I0J3902D01*
G01X80844D01*
G02Y730686I0J-3902D01*
G01X73944D01*
G37*
G36*
G01X87117Y725019D02*
G03X87213I48J194D01*
G02X88415Y725166I1204J-4855D01*
G02Y715162I0J-5002D01*
G02X87213Y715309I2J5002D01*
G03X87117I-48J-194D01*
G02X85915Y715162I-1204J4855D01*
G02Y725166I0J5002D01*
G02X87117Y725019I-2J-5002D01*
G37*
G36*
G01X94063Y1356618D02*
X96172Y1358727D01*
X99463D01*
X100283Y1357907D01*
Y1356632D01*
X100583Y1356332D01*
X122862D01*
X123193Y1356001D01*
Y1339287D01*
X122891Y1338985D01*
X103449D01*
X102551Y1339883D01*
Y1348879D01*
X100663Y1350767D01*
X94782D01*
X94063Y1351486D01*
Y1356618D01*
G37*
G36*
G01X159363D02*
X161462Y1358717D01*
X164823D01*
X165553Y1357987D01*
Y1356537D01*
X165777Y1356313D01*
X187851D01*
X188423Y1355741D01*
Y1339894D01*
X188075Y1339546D01*
Y1339403D01*
X187657Y1338985D01*
X169234D01*
X169063Y1339156D01*
X168667D01*
X167851Y1339972D01*
Y1348879D01*
X165963Y1350767D01*
X160082D01*
X159363Y1351486D01*
Y1356618D01*
G37*
G36*
G01X227437Y1358527D02*
X227618Y1358708D01*
X230495D01*
X231254Y1357949D01*
Y1356297D01*
X253377D01*
X254123Y1355551D01*
Y1339894D01*
X253669Y1339440D01*
Y1339403D01*
X253469Y1339203D01*
Y1339197D01*
X253175Y1338903D01*
X234516D01*
X233969Y1339450D01*
Y1339554D01*
X233551Y1339972D01*
Y1348879D01*
X231843Y1350587D01*
X226567D01*
X226359Y1350795D01*
X226281D01*
X225560Y1351516D01*
Y1351594D01*
X225063Y1352091D01*
Y1356600D01*
X226990Y1358527D01*
X227437D01*
G37*
G36*
G01X192263Y1356618D02*
X194372Y1358727D01*
X197833D01*
X198475Y1358085D01*
Y1356555D01*
X198713Y1356317D01*
X220571D01*
X221323Y1355565D01*
Y1339894D01*
X220613Y1339184D01*
X220556D01*
X220371Y1338999D01*
X219287D01*
X219286Y1338997D01*
X202122D01*
X201963Y1339156D01*
X201567D01*
X200751Y1339972D01*
Y1348879D01*
X198863Y1350767D01*
X192982D01*
X192263Y1351486D01*
Y1356618D01*
G37*
G36*
G01X126663D02*
X128772Y1358727D01*
X132143D01*
X132853Y1358017D01*
Y1356577D01*
X133113Y1356317D01*
X155071D01*
X155723Y1355665D01*
Y1339894D01*
X155275Y1339446D01*
Y1339303D01*
X154957Y1338985D01*
X136334D01*
X136163Y1339156D01*
X135967D01*
X135151Y1339972D01*
Y1348879D01*
X133263Y1350767D01*
X127382D01*
X126663Y1351486D01*
Y1356618D01*
G37*
G36*
G01X303018Y698818D02*
X302078Y697878D01*
X298451D01*
X298116Y698213D01*
X296189D01*
X294740Y699662D01*
Y702135D01*
X294784Y702179D01*
Y702415D01*
X299984D01*
Y702915D01*
X300986D01*
Y702412D01*
X302140D01*
X303018Y701534D01*
Y698818D01*
G37*
G36*
G01X346493Y744346D02*
X347203Y745056D01*
X365750D01*
X366568Y744238D01*
Y735523D01*
X368733Y733358D01*
X371324D01*
X371341Y733341D01*
X371628D01*
X371729Y733442D01*
X374334D01*
X375053Y732723D01*
Y727333D01*
X373239Y725519D01*
X370298D01*
X370282Y725535D01*
X370122D01*
X369365Y726292D01*
Y726452D01*
X367922Y727895D01*
X366807D01*
Y727896D01*
X347315D01*
X346493Y728718D01*
Y744346D01*
G37*
G36*
G01X313433Y744614D02*
X314143Y745324D01*
X332690D01*
X332872Y745142D01*
X333154D01*
X333972Y744324D01*
Y736316D01*
X336459Y733829D01*
X341155D01*
X341993Y732991D01*
Y727859D01*
X340276Y726142D01*
Y725792D01*
X339688Y725204D01*
X336797D01*
X336465Y725536D01*
Y726400D01*
X336305Y726560D01*
Y726586D01*
X334727Y728164D01*
X314269D01*
X313433Y729000D01*
Y744614D01*
G37*
G36*
G01X332754Y722565D02*
Y723065D01*
X333756D01*
Y722457D01*
X334995D01*
X335839Y721613D01*
Y719255D01*
X334622Y718038D01*
X331181D01*
X330896Y718323D01*
X329090D01*
X327542Y719871D01*
Y722047D01*
X327554Y722059D01*
Y722565D01*
X332754D01*
G37*
G36*
G01X412533Y726614D02*
X413243Y727324D01*
X434866D01*
X435660Y726530D01*
Y716330D01*
X435900Y716090D01*
X439594D01*
X439974Y715710D01*
X440374D01*
X441093Y714991D01*
Y709859D01*
X440335Y709101D01*
Y707750D01*
X440100Y707515D01*
X436605D01*
X436604Y707516D01*
X436003D01*
X433207Y710312D01*
X413216D01*
X412533Y710995D01*
Y726614D01*
G37*
G36*
G01X267254Y668208D02*
Y668674D01*
X268256D01*
Y668208D01*
X268876D01*
X270219Y666865D01*
Y664763D01*
X269104Y663648D01*
X265661D01*
X265376Y663933D01*
X263527D01*
X262054Y665406D01*
Y665924D01*
X262051Y665927D01*
Y667806D01*
X262054Y667809D01*
Y668174D01*
X262419D01*
X262453Y668208D01*
X267254D01*
G37*
G36*
G01X365814Y722297D02*
Y722797D01*
X366816D01*
Y722206D01*
X368592Y720430D01*
Y718599D01*
X368407Y718414D01*
Y718413D01*
X367772Y717778D01*
X364344D01*
X363899Y718223D01*
X361897D01*
X360614Y719506D01*
Y722297D01*
X365814D01*
G37*
G36*
G01X398854Y722365D02*
Y722865D01*
X399856D01*
Y722316D01*
X401614Y720558D01*
Y718602D01*
X400850Y717838D01*
X397251D01*
X396966Y718123D01*
X395167D01*
X393654Y719636D01*
Y719984D01*
X393651Y719987D01*
Y722178D01*
X393654Y722181D01*
Y722365D01*
X398854D01*
G37*
G36*
G01X431854Y704565D02*
Y705065D01*
X432856D01*
Y704466D01*
X434728Y702594D01*
Y700916D01*
X433850Y700038D01*
X430251D01*
X429966Y700323D01*
X428097D01*
X426654Y701766D01*
Y704565D01*
X431854D01*
G37*
G36*
G01X510833Y641414D02*
X511543Y642124D01*
X531266D01*
X532160Y641230D01*
Y631430D01*
X532732Y630858D01*
X538330D01*
X539396Y629792D01*
Y624658D01*
X537338Y622600D01*
X534461D01*
X533702Y623359D01*
Y625511D01*
X531300D01*
Y624964D01*
X511628D01*
X510833Y625759D01*
Y641414D01*
G37*
G36*
G01X294056Y1312415D02*
G02X294198Y1312474I142J-141D01*
G01X296907D01*
G02X297049Y1312415I0J-200D01*
G01X299235Y1310229D01*
G03X299377Y1310170I142J141D01*
G01X319802D01*
X320611Y1309361D01*
Y1309180D01*
G02X320616Y1309135I-195J-44D01*
G01Y1308690D01*
X320619Y1308687D01*
Y1293746D01*
G02X320560Y1293604I-200J0D01*
G01X319968Y1293012D01*
G02X319826Y1292953I-142J141D01*
G01X301445D01*
G02X301303Y1293012I0J200D01*
G01X300603Y1293712D01*
G02X300544Y1293854I141J142D01*
G01Y1293962D01*
X300514Y1294036D01*
X300485Y1294064D01*
X300459Y1294090D01*
Y1302720D01*
X300429Y1302794D01*
X300400Y1302822D01*
X298843Y1304379D01*
G03X298701Y1304438I-142J-141D01*
G01X292732D01*
G02X292590Y1304497I0J200D01*
G01X292118Y1304969D01*
G02X292059Y1305111I141J142D01*
G01Y1310335D01*
G02X292118Y1310477I200J0D01*
G01X294056Y1312415D01*
G37*
G36*
G01X385671Y1293215D02*
G02X385529Y1293156I-142J141D01*
G01X366357D01*
G02X366215Y1293215I0J200D01*
G01X365828Y1293602D01*
G02X365769Y1293744I141J142D01*
G01Y1303277D01*
G03X365710Y1303419I-200J0D01*
G01X364724Y1304405D01*
X358840D01*
X357819Y1305426D01*
G02X357760Y1305568I141J142D01*
G01Y1310536D01*
G02X357819Y1310678I200J0D01*
G01X359759Y1312618D01*
G02X359901Y1312677I142J-141D01*
G01X362612D01*
G02X362754Y1312618I0J-200D01*
G01X363454Y1311918D01*
Y1311914D01*
X364996Y1310372D01*
G03X365138Y1310313I142J141D01*
G01X385208D01*
X385527D01*
X386288Y1309552D01*
Y1309310D01*
G02X386320Y1309201I-168J-108D01*
G01Y1293947D01*
G02X386261Y1293805I-200J0D01*
G01X385671Y1293215D01*
G37*
G36*
G01X352812Y1292956D02*
X352805Y1292953D01*
X334349D01*
G02X334207Y1293012I0J200D01*
G01X333507Y1293712D01*
G02X333448Y1293854I141J142D01*
G01Y1293905D01*
X333418Y1293979D01*
X333389Y1294007D01*
X333363Y1294033D01*
Y1302720D01*
X333333Y1302794D01*
X333304Y1302822D01*
X332105Y1304021D01*
X332097Y1304014D01*
X325611D01*
X324960Y1304665D01*
Y1310336D01*
G02X325019Y1310478I200J0D01*
G01X326959Y1312418D01*
G02X327101Y1312477I142J-141D01*
G01X329812D01*
G02X329954Y1312418I0J-200D01*
G01X330654Y1311718D01*
Y1311714D01*
X332196Y1310172D01*
G03X332338Y1310113I142J141D01*
G01X352748D01*
G02X352890Y1310054I0J-200D01*
G01X353461Y1309483D01*
G02X353520Y1309341I-141J-142D01*
G01Y1308690D01*
X353523Y1308687D01*
Y1293754D01*
G02X353508Y1293678I-200J0D01*
G01X353505Y1293671D01*
Y1293670D01*
G02X353462Y1293606I-184J77D01*
G01X352812Y1292956D01*
G37*
G36*
G01X641042Y1572092D02*
G02X641909Y1570443I-1135J-1649D01*
G02X637905I-2002J0D01*
G02X638068Y1571234I2001J0D01*
G03X637997Y1571478I-184J79D01*
G02X637130Y1573127I1135J1649D01*
G02X641134I2002J0D01*
G02X640971Y1572336I-2001J0D01*
G03X641042Y1572092I184J-79D01*
G37*
G36*
G01X707876Y1368465D02*
X703263D01*
G02X703121Y1368524I0J200D01*
G01X702178Y1369467D01*
G02X702119Y1369609I141J142D01*
G01Y1374575D01*
G02X702178Y1374717I200J0D01*
G01X704116Y1376655D01*
G02X704258Y1376714I142J-141D01*
G01X706967D01*
G02X707109Y1376655I0J-200D01*
G01X707748Y1376016D01*
G02X707807Y1375874I-141J-142D01*
G01Y1374201D01*
G03X708007Y1374001I200J0D01*
G01X710073D01*
G03X710273Y1374201I0J200D01*
G01Y1374236D01*
X710390Y1374353D01*
X729957D01*
Y1374355D01*
X730074D01*
G02X730216Y1374296I0J-200D01*
G01X730305Y1374207D01*
G02X730364Y1374065I-141J-142D01*
G01Y1355878D01*
G02X730305Y1355736I-200J0D01*
G01X728559Y1353990D01*
G02X728417Y1353931I-142J141D01*
G01X711883D01*
G02X711741Y1353990I0J200D01*
G01X710400Y1355331D01*
X710356D01*
Y1365985D01*
G03X710297Y1366127I-200J0D01*
G01X708018Y1368406D01*
G03X707876Y1368465I-142J-141D01*
G37*
G36*
G01X740712Y1368492D02*
X736118D01*
G02X735976Y1368551I0J200D01*
G01X734960Y1369567D01*
G02X734901Y1369709I141J142D01*
G01Y1374675D01*
G02X734960Y1374817I200J0D01*
G01X736898Y1376755D01*
G02X737040Y1376814I142J-141D01*
G01X739749D01*
G02X739891Y1376755I0J-200D01*
G01X740530Y1376116D01*
G02X740589Y1375974I-141J-142D01*
G01Y1374301D01*
G03X740789Y1374101I200J0D01*
G01X742944D01*
X743017Y1374131D01*
X743037Y1374151D01*
Y1374253D01*
G02X743237Y1374453I200J0D01*
G01X762739D01*
X762837Y1374355D01*
X762956D01*
G02X763098Y1374296I0J-200D01*
G01X763116Y1374278D01*
X763146Y1374205D01*
Y1355960D01*
G02X763087Y1355818I-200J0D01*
G01X761359Y1354090D01*
G02X761217Y1354031I-142J141D01*
G01X744483D01*
G02X744341Y1354090I0J200D01*
G01X743197Y1355234D01*
G02X743138Y1355376I141J142D01*
G01Y1366066D01*
G03X743079Y1366208I-200J0D01*
G01X740854Y1368433D01*
G03X740712Y1368492I-142J-141D01*
G37*
G36*
G01X664202Y152989D02*
X664402Y153189D01*
X670702D01*
X670902Y152989D01*
Y152520D01*
X670702Y152320D01*
X664402D01*
X664202Y152520D01*
Y152989D01*
G37*
G36*
G01Y151021D02*
X664402Y151221D01*
X670702D01*
X670902Y151021D01*
Y150552D01*
X670702Y150352D01*
X664402D01*
X664202Y150552D01*
Y151021D01*
G37*
G36*
G01X693927Y152005D02*
X694127Y152205D01*
X700427D01*
X700627Y152005D01*
Y151536D01*
X700427Y151336D01*
X694127D01*
X693927Y151536D01*
Y152005D01*
G37*
G36*
G01Y150037D02*
X694127Y150237D01*
X700427D01*
X700627Y150037D01*
Y149568D01*
X700427Y149368D01*
X694127D01*
X693927Y149568D01*
Y150037D01*
G37*
G36*
G01X869834Y1243023D02*
X871474Y1244663D01*
X923706D01*
X925243Y1243126D01*
Y1212512D01*
X920848Y1208117D01*
Y1159447D01*
X922440Y1157855D01*
Y1157854D01*
X922534Y1157761D01*
X923883D01*
X924445Y1157199D01*
Y1153897D01*
X924413Y1153865D01*
X915262D01*
X915052Y1153655D01*
Y1138936D01*
X919488Y1134500D01*
Y1106859D01*
X919572Y1106775D01*
Y1091170D01*
X912160Y1083758D01*
Y1063002D01*
X910274Y1061116D01*
X890283D01*
X888345Y1059178D01*
Y1054281D01*
X887530Y1053466D01*
X872312D01*
X870600Y1055178D01*
Y1078137D01*
X871874Y1079411D01*
X886042D01*
X886854Y1080223D01*
Y1103255D01*
X889484Y1105885D01*
X901028D01*
X903878Y1108735D01*
Y1133608D01*
X903253Y1134233D01*
X896164D01*
X894305Y1132374D01*
X887770D01*
X885286Y1134858D01*
Y1150491D01*
X869834Y1165943D01*
Y1168566D01*
Y1243023D01*
G37*
G36*
G01X937343Y309604D02*
X920137D01*
G02X937343I8603J12050D01*
G37*
G36*
G01X1166522Y1358655D02*
X1166556Y1358689D01*
X1169433D01*
X1170192Y1357930D01*
Y1356298D01*
X1192545D01*
X1193061Y1355782D01*
Y1339875D01*
X1192351Y1339165D01*
X1192294D01*
X1192109Y1338980D01*
X1191025D01*
X1191024Y1338978D01*
X1173860D01*
X1173701Y1339137D01*
X1173305D01*
X1172489Y1339953D01*
Y1348860D01*
X1170601Y1350748D01*
X1164720D01*
X1164001Y1351467D01*
Y1356599D01*
X1166057Y1358655D01*
X1166522D01*
G37*
G36*
G01X1199175Y1358508D02*
X1199356Y1358689D01*
X1202233D01*
X1202992Y1357930D01*
Y1356278D01*
X1225275D01*
X1225861Y1355692D01*
Y1339875D01*
X1225407Y1339421D01*
Y1339384D01*
X1225207Y1339184D01*
Y1339178D01*
X1224913Y1338884D01*
X1206254D01*
X1205707Y1339431D01*
Y1339535D01*
X1205289Y1339953D01*
Y1348860D01*
X1203581Y1350568D01*
X1198305D01*
X1198097Y1350776D01*
X1198019D01*
X1197298Y1351497D01*
Y1351575D01*
X1196801Y1352072D01*
Y1356581D01*
X1198728Y1358508D01*
X1199175D01*
G37*
G36*
G01X1065801Y1356599D02*
X1067900Y1358698D01*
X1071285D01*
X1071965Y1358018D01*
Y1356648D01*
X1072325Y1356288D01*
X1094112D01*
X1094861Y1355539D01*
Y1339875D01*
X1094407Y1339421D01*
Y1339366D01*
X1094007Y1338966D01*
X1075187D01*
X1074289Y1339864D01*
Y1348860D01*
X1072401Y1350748D01*
X1066520D01*
X1065801Y1351467D01*
Y1356599D01*
G37*
G36*
G01X1098401D02*
X1100500Y1358698D01*
X1104095D01*
X1104645Y1358148D01*
Y1356738D01*
X1105085Y1356298D01*
X1126708D01*
X1127461Y1355545D01*
Y1339875D01*
X1127013Y1339427D01*
Y1339284D01*
X1126695Y1338966D01*
X1108072D01*
X1107901Y1339137D01*
X1107705D01*
X1106889Y1339953D01*
Y1348860D01*
X1105001Y1350748D01*
X1099120D01*
X1098401Y1351467D01*
Y1356599D01*
G37*
G36*
G01X1131101D02*
X1133200Y1358698D01*
X1136985D01*
X1137455Y1358228D01*
Y1356758D01*
X1137915Y1356298D01*
X1137911Y1356294D01*
X1159589D01*
X1160161Y1355722D01*
Y1339875D01*
X1159813Y1339527D01*
Y1339384D01*
X1159395Y1338966D01*
X1140972D01*
X1140801Y1339137D01*
X1140405D01*
X1139589Y1339953D01*
Y1348860D01*
X1137701Y1350748D01*
X1131820D01*
X1131101Y1351467D01*
Y1356599D01*
G37*
G36*
G01X1168889Y1281598D02*
X1175789D01*
G02Y1273796I0J-3901D01*
G01X1168889D01*
G02Y1281598I0J3901D01*
G37*
G36*
G01X1139188D02*
X1146088D01*
G02Y1273796I0J-3901D01*
G01X1139188D01*
G02Y1281598I0J3901D01*
G37*
G36*
G01X1109487D02*
X1116387D01*
G02Y1273796I0J-3901D01*
G01X1109487D01*
G02Y1281598I0J3901D01*
G37*
G36*
G01X1079787D02*
X1086687D01*
G02Y1273796I0J-3901D01*
G01X1079787D01*
G02Y1281598I0J3901D01*
G37*
G36*
G01X1115451Y1514084D02*
Y1514204D01*
G03X1115402Y1514334I-200J-1D01*
G02X1114915Y1515643I1515J1309D01*
G01Y1515644D01*
G02X1116917Y1517646I2002J0D01*
G02X1118224Y1517161I1J-2002D01*
G03X1118354Y1517112I131J151D01*
G01X1118475D01*
G03X1118605Y1517161I-1J200D01*
G02X1119912Y1517646I1306J-1517D01*
G02X1121914Y1515644I0J-2002D01*
G01Y1515643D01*
G02X1121427Y1514334I-2002J0D01*
G03X1121378Y1514204I151J-131D01*
G01Y1514084D01*
G03X1121427Y1513954I200J1D01*
G02X1121914Y1512645I-1515J-1309D01*
G01Y1512644D01*
G02X1121475Y1511393I-2002J0D01*
G03Y1511143I156J-125D01*
G02X1121914Y1509892I-1563J-1251D01*
G01Y1509891D01*
G02X1121443Y1508602I-2002J1D01*
G03X1121396Y1508473I153J-129D01*
G01Y1508354D01*
G03X1121443Y1508225I200J0D01*
G02X1121914Y1506936I-1531J-1290D01*
G02X1119912Y1504934I-2002J0D01*
G02X1118662Y1505372I-1J2001D01*
G03X1118530Y1505416I-125J-156D01*
G01X1118411Y1505412D01*
G03X1118282Y1505358I8J-200D01*
G02X1116917Y1504821I-1364J1465D01*
G02X1114915Y1506823I0J2002D01*
G02X1115432Y1508166I2003J0D01*
G03X1115484Y1508300I-148J134D01*
G01Y1508421D01*
G03X1115432Y1508555I-200J0D01*
G02X1114915Y1509898I1486J1343D01*
G02X1115352Y1511146I2002J0D01*
G03Y1511396I-157J125D01*
G02X1114915Y1512644I1565J1248D01*
G01Y1512645D01*
G02X1115402Y1513954I2002J0D01*
G03X1115451Y1514084I-151J131D01*
G37*
G36*
G01X1160031Y1589661D02*
G02Y1592665I0J1502D01*
G02X1161095Y1592223I0J-1502D01*
G01X1161123Y1592195D01*
X1161196Y1592164D01*
X1161503D01*
G03X1161607Y1592193I0J200D01*
G02X1161865Y1592264I258J-433D01*
G01X1163365D01*
G02X1163866Y1591763I0J-501D01*
G01Y1590563D01*
G02X1163365Y1590062I-501J0D01*
G01X1161865D01*
G02X1161607Y1590133I0J504D01*
G03X1161503Y1590162I-104J-171D01*
G01X1161196D01*
X1161123Y1590131D01*
X1161095Y1590103D01*
G02X1160031Y1589661I-1064J1060D01*
G37*
G36*
G01X1268188Y1310399D02*
X1270305Y1312516D01*
X1273211D01*
X1275576Y1310151D01*
X1296059D01*
X1296745Y1309465D01*
Y1293645D01*
X1296037Y1292937D01*
X1277257D01*
X1276588Y1293606D01*
Y1302748D01*
X1274788Y1304548D01*
X1268907D01*
X1268188Y1305267D01*
Y1310399D01*
G37*
G36*
G01X1333892Y1310599D02*
X1335948Y1312655D01*
X1338823D01*
X1341184Y1310294D01*
X1361658D01*
X1362449Y1309503D01*
Y1293845D01*
X1361741Y1293137D01*
X1342958D01*
X1342380Y1293715D01*
Y1302417D01*
X1340233Y1304564D01*
X1334549D01*
X1333918Y1305195D01*
Y1305441D01*
X1333892Y1305467D01*
Y1310599D01*
G37*
G36*
G01X1329649Y1293645D02*
X1328941Y1292937D01*
X1310071D01*
X1309492Y1293516D01*
Y1302748D01*
X1307692Y1304548D01*
X1301812D01*
X1301804Y1304556D01*
X1301092Y1305267D01*
Y1310399D01*
X1303148Y1312455D01*
X1306023D01*
X1308384Y1310094D01*
X1328960D01*
X1329649Y1309405D01*
Y1293645D01*
G37*
G36*
G01X1456703Y744614D02*
X1457413Y745324D01*
X1475960D01*
X1476778Y744506D01*
Y735599D01*
X1478748Y733629D01*
X1481535D01*
X1481694Y733470D01*
X1481938Y733713D01*
X1484545D01*
X1485266Y732992D01*
Y727858D01*
X1483208Y725800D01*
X1480331D01*
X1479572Y726559D01*
Y728711D01*
X1477113D01*
Y728164D01*
X1457310D01*
Y728983D01*
X1456703Y729590D01*
Y744614D01*
G37*
G36*
G01X1621485Y669905D02*
X1622195Y670615D01*
X1642357D01*
X1643160Y669812D01*
Y659290D01*
X1643530Y658920D01*
X1646317D01*
X1646476Y658761D01*
X1646720Y659004D01*
X1649327D01*
X1650048Y658283D01*
Y653149D01*
X1647990Y651091D01*
X1645113D01*
X1644354Y651850D01*
Y654002D01*
X1641915D01*
Y653455D01*
X1622118D01*
Y654248D01*
X1621485Y654881D01*
Y669905D01*
G37*
G36*
G01X1588485Y688905D02*
X1589195Y689615D01*
X1609457D01*
X1610260Y688812D01*
Y678190D01*
X1610506Y677944D01*
X1610527Y677965D01*
X1613681D01*
X1613720Y678004D01*
X1616327D01*
X1616366Y677965D01*
X1616397D01*
X1616907Y677455D01*
Y677424D01*
X1617048Y677283D01*
Y672149D01*
X1614990Y670091D01*
X1612113D01*
X1611354Y670850D01*
Y672328D01*
X1611217Y672465D01*
X1608807D01*
Y672455D01*
X1589057D01*
Y673309D01*
X1588485Y673881D01*
Y688905D01*
G37*
G36*
G01X1522585Y744782D02*
X1523295Y745492D01*
X1541842D01*
X1542660Y744674D01*
Y735767D01*
X1544630Y733797D01*
X1547417D01*
X1547576Y733638D01*
X1547820Y733881D01*
X1550427D01*
X1551148Y733160D01*
Y727688D01*
X1549250Y725790D01*
X1546100D01*
X1545440Y726450D01*
Y728705D01*
X1542958D01*
Y728305D01*
X1523084D01*
Y728744D01*
X1522585Y729243D01*
Y744782D01*
G37*
G36*
G01X1489785D02*
X1490495Y745492D01*
X1509042D01*
X1509860Y744674D01*
Y735767D01*
X1511830Y733797D01*
X1514617D01*
X1514776Y733638D01*
X1515020Y733881D01*
X1517627D01*
X1518348Y733160D01*
Y727818D01*
X1516290Y725760D01*
X1513500D01*
X1512654Y726606D01*
Y728597D01*
X1510206D01*
Y728332D01*
X1490377D01*
Y728776D01*
X1489785Y729368D01*
Y744782D01*
G37*
G36*
G01X1776621Y730686D02*
G02Y738488I0J3901D01*
G01X1783521D01*
G02Y730686I0J-3901D01*
G01X1776621D01*
G37*
G36*
G01X1657818Y730684D02*
G02Y738490I0J3903D01*
G01X1664718D01*
G02Y730684I0J-3903D01*
G01X1657818D01*
G37*
G36*
G01X1687519Y738488D02*
X1694419D01*
G02Y730686I0J-3901D01*
G01X1687519D01*
G02Y738488I0J3901D01*
G37*
G36*
G01X1746921D02*
X1753821D01*
G02Y730686I0J-3901D01*
G01X1746921D01*
G02Y738488I0J3901D01*
G37*
G36*
G01X1717220D02*
X1724120D01*
G02Y730686I0J-3901D01*
G01X1717220D01*
G02Y738488I0J3901D01*
G37*
G36*
G01X1682634Y1374047D02*
X1684690Y1376103D01*
X1687565D01*
X1688322Y1375346D01*
Y1374803D01*
X1689345Y1373780D01*
X1710636D01*
X1710879Y1373537D01*
Y1353630D01*
X1710047Y1352798D01*
X1691757D01*
X1690871Y1353684D01*
Y1365696D01*
X1688551Y1368016D01*
X1683533D01*
X1682634Y1368915D01*
Y1374047D01*
G37*
G36*
G01X1649852Y1373947D02*
X1651908Y1376003D01*
X1654783D01*
X1655540Y1375246D01*
Y1374246D01*
X1656106Y1373680D01*
X1677924D01*
X1678097Y1373507D01*
Y1353598D01*
X1677137Y1352638D01*
X1659127D01*
X1658089Y1353676D01*
Y1365175D01*
X1655629Y1367635D01*
X1650837D01*
X1649852Y1368620D01*
Y1373947D01*
G37*
G36*
G01X1625976Y170578D02*
X1626028Y170925D01*
X1626012Y170998D01*
X1625989Y171030D01*
G02X1625684Y172008I1417J978D01*
G02X1629128I1722J0D01*
G02X1628644Y170812I-1722J1D01*
G01X1628617Y170783D01*
X1628588Y170715D01*
X1628583Y170363D01*
X1628609Y170294D01*
X1628635Y170265D01*
G02X1629154Y168920I-1483J-1345D01*
G02X1625150I-2002J0D01*
G02X1625909Y170489I2001J0D01*
G01X1625939Y170513D01*
X1625976Y170578D01*
G37*
G36*
G01X1785687Y230225D02*
G02X1785828Y230284I142J-141D01*
G01X1805392D01*
G02X1805533Y230225I-1J-200D01*
G01X1806783Y228975D01*
G02X1806842Y228834I-141J-142D01*
G01Y211391D01*
G03X1807042Y211192I200J1D01*
G01X1807048D01*
G02X1807248Y210992I-1J-201D01*
G01Y210698D01*
G02X1807048Y210498I-200J0D01*
G01X1806435D01*
G03X1806293Y210439I0J-200D01*
G01X1806103Y210249D01*
G02X1805962Y210190I-142J141D01*
G01X1790018D01*
G02X1789877Y210249I1J200D01*
G01X1789874Y210252D01*
X1785996D01*
G02X1785856Y210310I1J200D01*
G01X1784947Y211219D01*
G02X1784888Y211360I141J142D01*
G01Y229344D01*
G02X1784947Y229485I200J-1D01*
G01X1785687Y230225D01*
G37*
G36*
G01X1768506Y209522D02*
X1768526Y209514D01*
X1779586D01*
X1779602Y209530D01*
X1780427D01*
G02X1780567Y209472I-1J-200D01*
G01X1780619Y209420D01*
G03X1780740Y209368I135J148D01*
G01X1792855D01*
G02X1792995Y209310I-1J-200D01*
G01X1793061Y209244D01*
G03X1793076Y209232I132J150D01*
G03X1793196Y209192I120J160D01*
G01X1794780D01*
X1794790Y209182D01*
Y198692D01*
X1794780Y198682D01*
X1790460D01*
G03X1790260Y198482I0J-200D01*
G01Y192112D01*
X1790270Y192102D01*
X1804210D01*
X1804230Y192122D01*
Y199852D01*
X1804220Y199862D01*
X1801280D01*
X1801270Y199872D01*
Y203412D01*
X1801280Y203422D01*
X1807690D01*
X1807710Y203442D01*
Y206109D01*
G02X1807769Y206251I200J0D01*
G01X1808121Y206603D01*
G02X1808263Y206662I142J-141D01*
G01X1813227D01*
X1813301Y206692D01*
X1813329Y206721D01*
X1813531Y206923D01*
G03X1813590Y207065I-141J142D01*
G01Y210229D01*
G02X1813649Y210371I200J0D01*
G01X1815815Y212537D01*
G02X1815957Y212596I142J-141D01*
G01X1819305D01*
G02X1819447Y212537I0J-200D01*
G01X1821501Y210483D01*
G02X1821560Y210341I-141J-142D01*
G01Y179657D01*
G02X1821501Y179515I-200J0D01*
G01X1819251Y177265D01*
X1819238Y177243D01*
G03X1819214Y177102I172J-102D01*
G01X1819289Y176726D01*
X1819352Y176650D01*
X1819399Y176630D01*
G02X1820330Y175241I-571J-1389D01*
G02X1818828Y173739I-1502J0D01*
G02X1817439Y174670I0J1502D01*
G01X1817419Y174717D01*
X1817343Y174780D01*
X1816967Y174855D01*
G03X1816787Y174801I-39J-196D01*
G01X1816447Y174461D01*
G02X1816305Y174402I-142J141D01*
G01X1809167D01*
G03X1808996Y174306I0J-200D01*
G02X1806426I-1285J776D01*
G03X1806255Y174402I-171J-104D01*
G01X1777987D01*
G02X1777845Y174461I0J200D01*
G01X1775212Y177094D01*
G02X1775153Y177236I141J142D01*
G01Y185203D01*
G03X1775096Y185343I-200J0D01*
G03X1775094Y185345I-142J-140D01*
G01X1774697Y185742D01*
G03X1774557Y185799I-140J-143D01*
G01X1748757D01*
G03X1748617Y185742I0J-200D01*
G03X1748615Y185740I140J-142D01*
G01X1742615Y179740D01*
X1697470D01*
X1694350Y182860D01*
Y212900D01*
Y217550D01*
X1696820Y220020D01*
X1737974D01*
Y219926D01*
X1748378Y209522D01*
X1768506D01*
G37*
G36*
G01X1770314Y1558215D02*
G02X1770455Y1558274I142J-141D01*
G01X1773021D01*
G02X1773162Y1558215I-1J-200D01*
G01X1773732Y1557645D01*
G02X1773791Y1557504I-141J-142D01*
G01Y1554892D01*
G03X1773953Y1554730I197J35D01*
G01X1799421D01*
G02X1799562Y1554671I-1J-200D01*
G01X1800532Y1553701D01*
G02X1800591Y1553560I-141J-142D01*
G01Y1546005D01*
X1800590D01*
Y1540776D01*
G02X1800531Y1540634I-200J0D01*
G01X1799501Y1539604D01*
G02X1799359Y1539545I-142J141D01*
G01X1778598D01*
G02X1778456Y1539604I0J200D01*
G01X1777903Y1540157D01*
G02X1777844Y1540299I141J142D01*
G01Y1549344D01*
G03X1777785Y1549486I-200J0D01*
G01X1777162Y1550109D01*
G03X1777020Y1550168I-142J-141D01*
G01X1773655D01*
G02X1773515Y1550226I1J200D01*
G01X1773514Y1550227D01*
X1773477Y1550263D01*
G03X1773199I-139J-144D01*
G01X1773162Y1550227D01*
X1773161Y1550226D01*
G02X1773021Y1550168I-141J142D01*
G01X1770455D01*
G02X1770314Y1550227I1J200D01*
G01X1769744Y1550797D01*
G02X1769685Y1550938I141J142D01*
G01Y1557504D01*
G02X1769744Y1557645I200J-1D01*
G01X1770314Y1558215D01*
G37*
G36*
G01X1734514D02*
G02X1734655Y1558274I142J-141D01*
G01X1737221D01*
G02X1737362Y1558215I-1J-200D01*
G01X1737932Y1557645D01*
G02X1737991Y1557504I-141J-142D01*
G01Y1554892D01*
G03X1738153Y1554730I197J35D01*
G01X1766790D01*
G02X1766931Y1554671I-1J-200D01*
G01X1767923Y1553679D01*
G02X1767982Y1553538I-141J-142D01*
G01Y1544584D01*
X1767971D01*
Y1540305D01*
G02X1767912Y1540163I-200J0D01*
G01X1767258Y1539509D01*
G02X1767116Y1539450I-142J141D01*
G01X1746511D01*
G02X1746369Y1539509I0J200D01*
G01X1744896Y1540982D01*
G02X1744837Y1541124I141J142D01*
G01Y1548620D01*
G03X1744778Y1548762I-200J0D01*
G01X1743531Y1550009D01*
G03X1743529Y1550011I-142J-140D01*
G03X1743389Y1550068I-140J-143D01*
G01X1737855D01*
G02X1737714Y1550127I1J200D01*
G01X1737629Y1550211D01*
G03X1737623Y1550217I-144J-138D01*
G01X1737622D01*
G03X1737347Y1550211I-134J-148D01*
G01X1737334Y1550198D01*
X1737296Y1550183D01*
X1737295D01*
G02X1737221Y1550168I-76J185D01*
G01X1734655D01*
G02X1734514Y1550227I1J200D01*
G01X1733944Y1550797D01*
G02X1733885Y1550938I141J142D01*
G01Y1557504D01*
G02X1733944Y1557645I200J-1D01*
G01X1734514Y1558215D01*
G37*
G36*
G01X1722667Y47220D02*
X1722867Y47420D01*
X1723329D01*
X1723529Y47220D01*
Y41520D01*
X1723329Y41320D01*
X1722867D01*
X1722667Y41520D01*
Y47220D01*
G37*
G36*
G01X1725029D02*
X1725229Y47420D01*
X1725691D01*
X1725891Y47220D01*
Y41520D01*
X1725691Y41320D01*
X1725229D01*
X1725029Y41520D01*
Y47220D01*
G37*
G36*
G01X1727391D02*
X1727591Y47420D01*
X1728053D01*
X1728253Y47220D01*
Y41520D01*
X1728053Y41320D01*
X1727591D01*
X1727391Y41520D01*
Y47220D01*
G37*
G36*
G01X1729753D02*
X1729953Y47420D01*
X1730415D01*
X1730615Y47220D01*
Y41520D01*
X1730415Y41320D01*
X1729953D01*
X1729753Y41520D01*
Y47220D01*
G37*
G36*
G01X1732116D02*
X1732316Y47420D01*
X1732778D01*
X1732978Y47220D01*
Y41520D01*
X1732778Y41320D01*
X1732316D01*
X1732116Y41520D01*
Y47220D01*
G37*
G54D356*
X712725Y84714D03*
X1751352Y293386D03*
X1774338Y1676865D03*
G54D351*
X155071Y1543604D03*
X1631455Y167875D03*
G54D348*
X139802Y1556133D03*
X479148Y315502D03*
X566148Y324502D03*
X714259Y1447483D03*
X715745Y86300D03*
X782712Y260466D03*
X1003090Y1037329D03*
X1551887Y606938D03*
G54D358*
X766889Y1530256D03*
G54D352*
X326731Y663237D03*
X363731D03*
X443467Y594259D03*
X754645Y1436735D03*
X1291146Y1385558D03*
X1320516D03*
X1425533Y601230D03*
X1487677Y649988D03*
X1524437Y650208D03*
G54D362*
X1764366Y57508D03*
X1759666Y57708D03*
G54D349*
X199718Y756766D03*
X192676D03*
X170017D03*
X162975D03*
X140316D03*
X133124D03*
X110616D03*
X103574D03*
X80915D03*
X73873D03*
X807450D03*
X800408D03*
X777900D03*
X770708D03*
X748049D03*
X741007D03*
X711306D03*
X718348D03*
X681605D03*
X688647D03*
X658946D03*
X651904D03*
X1783592Y756765D03*
X1776550D03*
X1746850D03*
X1753892D03*
X1724191D03*
X1717149D03*
X1694490D03*
X1687448D03*
X1664789D03*
X1657747D03*
X1628046D03*
X1635088D03*
G54D350*
X59259Y737422D03*
X1776986Y749023D03*
X1685890Y708610D03*
G54D363*
X1766929Y1714960D03*
G54D357*
X887519Y1528191D03*
G54D361*
X1739745Y605411D03*
G54D359*
X805690Y204724D03*
X1057659D03*
G54D360*
X1145935Y1515270D03*
G54D353*
X274913Y1019214D03*
X606409D03*
X841240Y1420331D03*
X1016240D03*
X1251055Y1019213D03*
X1582551D03*
G54D355*
X561133Y838505D03*
Y1199923D03*
X1537275Y838504D03*
Y1199922D03*
G54D354*
X320189Y838505D03*
Y1199923D03*
X1296331Y838504D03*
Y1199922D03*
%LPD*%
G75*
G36*
G01X55705Y1518035D02*
X51105D01*
X50905D01*
X50705Y1518235D01*
Y1520535D01*
X50861Y1520691D01*
X51261D01*
X56718D01*
X58175D01*
X75237D01*
X79174D01*
X79696Y1520169D01*
Y1508432D01*
X78979Y1507715D01*
X59741D01*
X58605Y1508851D01*
Y1515135D01*
Y1516035D01*
X56605Y1518035D01*
X55705D01*
G37*
G36*
G01X49662Y1524235D02*
X49762Y1524135D01*
Y1518235D01*
X49662Y1518135D01*
X47762D01*
X47662Y1518235D01*
Y1524135D01*
X47762Y1524235D01*
X49662D01*
G37*
G36*
G01X97033Y1357705D02*
X99005D01*
X99251Y1357459D01*
Y1356093D01*
X97558Y1354400D01*
Y1351883D01*
X97473Y1351798D01*
X95696D01*
X95563Y1351931D01*
Y1356235D01*
X97033Y1357705D01*
G37*
G36*
G01X91396Y1507969D02*
Y1517244D01*
X90505Y1518135D01*
X87005D01*
X86705D01*
X86505Y1518335D01*
Y1520435D01*
X86761Y1520691D01*
X86961D01*
X91718D01*
X92418D01*
X109480D01*
X111805D01*
X112305Y1520191D01*
Y1512616D01*
Y1510522D01*
Y1508934D01*
X111086Y1507715D01*
X109498D01*
X107404D01*
X91650D01*
X91396Y1507969D01*
G37*
G36*
G01X85405Y1524235D02*
X85505Y1524135D01*
Y1518235D01*
X85405Y1518135D01*
X83505D01*
X83405Y1518235D01*
Y1524135D01*
X83505Y1524235D01*
X85405D01*
G37*
G36*
G01X99463Y1354877D02*
X121746D01*
X122015Y1354608D01*
Y1340344D01*
X121965Y1340294D01*
X104165D01*
X104115Y1340344D01*
Y1349260D01*
X101577Y1351798D01*
X98790D01*
X98558Y1352030D01*
Y1353972D01*
X99463Y1354877D01*
G37*
G36*
G01X154429Y1354794D02*
X154720Y1354503D01*
Y1340309D01*
X154598Y1340187D01*
X136881D01*
X136651Y1340417D01*
Y1349324D01*
X134209Y1351766D01*
X134093Y1351882D01*
X132068D01*
X131306D01*
X131193Y1351995D01*
Y1354007D01*
X131980Y1354794D01*
X154429D01*
G37*
G36*
G01X130073Y1351798D02*
X128908D01*
X128296D01*
X128163Y1351931D01*
Y1356235D01*
X128780Y1356852D01*
X129633Y1357705D01*
X131680D01*
X131851Y1357534D01*
Y1356093D01*
X130177Y1354419D01*
Y1354026D01*
Y1351902D01*
X130073Y1351798D01*
G37*
G36*
G01X187129Y1354794D02*
X187420Y1354503D01*
Y1340309D01*
X187298Y1340187D01*
X169581D01*
X169351Y1340417D01*
Y1349324D01*
X166909Y1351766D01*
X166793Y1351882D01*
X164768D01*
X164006D01*
X163893Y1351995D01*
Y1354007D01*
X164680Y1354794D01*
X187129D01*
G37*
G36*
G01X162773Y1351798D02*
X161608D01*
X160996D01*
X160863Y1351931D01*
Y1356235D01*
X161480Y1356852D01*
X162333Y1357705D01*
X164380D01*
X164551Y1357534D01*
Y1356093D01*
X162877Y1354419D01*
Y1354026D01*
Y1351902D01*
X162773Y1351798D01*
G37*
G36*
G01X220029Y1354794D02*
X220320Y1354503D01*
Y1340309D01*
X220198Y1340187D01*
X202481D01*
X202251Y1340417D01*
Y1349324D01*
X199809Y1351766D01*
X199693Y1351882D01*
X197668D01*
X196906D01*
X196793Y1351995D01*
Y1354007D01*
X197580Y1354794D01*
X220029D01*
G37*
G36*
G01X195673Y1351798D02*
X194508D01*
X193896D01*
X193763Y1351931D01*
Y1356235D01*
X194380Y1356852D01*
X195233Y1357705D01*
X197125D01*
X197393Y1357437D01*
Y1356035D01*
X195777Y1354419D01*
Y1354026D01*
Y1351902D01*
X195673Y1351798D01*
G37*
G36*
G01X252829Y1354794D02*
X253120Y1354503D01*
Y1340309D01*
X252998Y1340187D01*
X235281D01*
X235051Y1340417D01*
Y1349324D01*
X232609Y1351766D01*
X232493Y1351882D01*
X230468D01*
X229706D01*
X229603Y1351985D01*
Y1353977D01*
X230420Y1354794D01*
X252829D01*
G37*
G36*
G01X228473Y1351798D02*
X227308D01*
X226696D01*
X226563Y1351931D01*
Y1356235D01*
X227180Y1356852D01*
X228033Y1357705D01*
X230080D01*
X230251Y1357534D01*
Y1356093D01*
X228577Y1354419D01*
Y1354026D01*
Y1351902D01*
X228473Y1351798D01*
G37*
G36*
G01X301655Y1308563D02*
X319325D01*
X319616Y1308272D01*
Y1294078D01*
X319494Y1293956D01*
X301777D01*
X301547Y1294186D01*
Y1303093D01*
X299105Y1305535D01*
X298989Y1305651D01*
X296964D01*
X296392D01*
X296134Y1305909D01*
Y1307872D01*
X296825Y1308563D01*
X297183D01*
X301655D01*
G37*
G36*
G01X294969Y1305567D02*
X293804D01*
X293192D01*
X293059Y1305700D01*
Y1309824D01*
X294709Y1311474D01*
X296518D01*
X296647Y1311345D01*
Y1309846D01*
X295073Y1308273D01*
Y1305671D01*
X294969Y1305567D01*
G37*
G36*
G01X314727Y729714D02*
X314436Y730005D01*
Y744199D01*
X314558Y744321D01*
X332275D01*
X332505Y744091D01*
Y735184D01*
X334947Y732742D01*
X335063Y732626D01*
X337088D01*
X337850D01*
X337984Y732492D01*
Y730558D01*
X337140Y729714D01*
X314727D01*
G37*
G36*
G01X352312Y1293956D02*
X334681D01*
X334451Y1294186D01*
Y1303093D01*
X331893Y1305651D01*
X329106D01*
X328979Y1305778D01*
Y1307735D01*
X329807Y1308563D01*
X352229D01*
X352520Y1308272D01*
Y1294164D01*
X352312Y1293956D01*
G37*
G36*
G01X327841Y1305567D02*
X326708D01*
X326096D01*
X325963Y1305700D01*
Y1310004D01*
X326580Y1310621D01*
X327433Y1311474D01*
X329480D01*
X329651Y1311303D01*
Y1309862D01*
X327958Y1308169D01*
Y1305684D01*
X327841Y1305567D01*
G37*
G36*
G01X339083Y732710D02*
X340666D01*
X340993Y732383D01*
Y728422D01*
X339374Y726803D01*
X337476D01*
X337305Y726974D01*
Y728415D01*
X338979Y730089D01*
X338999Y730109D01*
Y732626D01*
X339083Y732710D01*
G37*
G36*
G01X347787Y729446D02*
X347496Y729737D01*
Y743931D01*
X347618Y744053D01*
X365335D01*
X365565Y743823D01*
Y734916D01*
X368007Y732474D01*
X368123Y732358D01*
X370148D01*
X370910D01*
X371052Y732216D01*
Y730265D01*
X370233Y729446D01*
X347787D01*
G37*
G36*
G01X384905Y1294156D02*
X367481D01*
X367251Y1294386D01*
Y1303293D01*
X364693Y1305851D01*
X361906D01*
X361800Y1305957D01*
Y1307888D01*
X362675Y1308763D01*
X385029D01*
X385320Y1308472D01*
Y1294571D01*
X384905Y1294156D01*
G37*
G36*
G01X360673Y1305767D02*
X359508D01*
X358896D01*
X358763Y1305900D01*
Y1310204D01*
X359380Y1310821D01*
X360233Y1311674D01*
X362280D01*
X362451Y1311503D01*
Y1310062D01*
X360777Y1308388D01*
Y1307995D01*
Y1305871D01*
X360673Y1305767D01*
G37*
G36*
G01X374013Y727965D02*
X373436Y727388D01*
X372583Y726535D01*
X370733D01*
X370365Y726903D01*
Y728147D01*
X372039Y729821D01*
X372058Y729840D01*
Y731964D01*
X372144Y732050D01*
X373858D01*
X374013Y731895D01*
Y727965D01*
G37*
G36*
G01X413827Y711714D02*
X413536Y712005D01*
Y726199D01*
X413658Y726321D01*
X434451D01*
X434657Y726115D01*
Y715915D01*
X435946Y714626D01*
X436950D01*
X437098Y714478D01*
Y712562D01*
X436250Y711714D01*
X413827D01*
G37*
G36*
G01X440093Y714015D02*
Y710554D01*
X438342Y708803D01*
X436576D01*
X436405Y708974D01*
Y710415D01*
X438079Y712089D01*
X438121Y712131D01*
Y714179D01*
X438257Y714315D01*
X439793D01*
X440093Y714015D01*
G37*
G36*
G01X534518Y626514D02*
X512127D01*
X511836Y626805D01*
Y640999D01*
X511958Y641121D01*
X530851D01*
X531157Y640815D01*
Y631015D01*
X532746Y629426D01*
X535250D01*
X535391Y629285D01*
Y627387D01*
X534518Y626514D01*
G37*
G36*
G01X538393Y629333D02*
Y625073D01*
X537776Y624456D01*
X536923Y623603D01*
X534876D01*
X534705Y623774D01*
Y625215D01*
X536379Y626889D01*
X536406Y626916D01*
Y629381D01*
X536489Y629464D01*
X538262D01*
X538393Y629333D01*
G37*
G36*
G01X728121Y1355031D02*
X712273D01*
X711473Y1355831D01*
Y1366807D01*
X708568Y1369712D01*
X706568D01*
X706145Y1370135D01*
Y1371961D01*
X707185Y1373001D01*
X728673D01*
X728821Y1372853D01*
Y1355731D01*
X728121Y1355031D01*
G37*
G36*
G01X705029Y1369807D02*
X703547D01*
X703119Y1370235D01*
Y1374009D01*
X704824Y1375714D01*
X706570D01*
X706807Y1375477D01*
Y1374102D01*
X705133Y1372428D01*
Y1372035D01*
Y1369911D01*
X705029Y1369807D01*
G37*
G36*
G01X737811Y1369907D02*
X736646D01*
X736134D01*
X735901Y1370140D01*
Y1374095D01*
X737620Y1375814D01*
X739328D01*
X739589Y1375553D01*
Y1374202D01*
X737915Y1372528D01*
X737888Y1372501D01*
Y1369984D01*
X737811Y1369907D01*
G37*
G36*
G01X760903Y1355131D02*
X745055D01*
X744255Y1355931D01*
Y1366907D01*
X741350Y1369812D01*
X739350D01*
X738897Y1370265D01*
Y1372045D01*
X739953Y1373101D01*
X761455D01*
X761603Y1372953D01*
Y1355831D01*
X760903Y1355131D01*
G37*
G36*
G01X886782Y1058543D02*
Y1055312D01*
X886183Y1054713D01*
X873330D01*
X871976Y1056067D01*
Y1076315D01*
X872894Y1077233D01*
X885560D01*
X886247Y1076546D01*
Y1059078D01*
X886782Y1058543D01*
G37*
G36*
G01X922523Y1214316D02*
Y1223805D01*
Y1230164D01*
Y1237364D01*
Y1242096D01*
X921446Y1243173D01*
X875710D01*
X875251Y1242714D01*
Y1215478D01*
Y1214728D01*
X877949Y1212029D01*
X879279D01*
X920236D01*
X922523Y1214316D01*
G37*
G36*
G01X910630Y1152669D02*
Y1148586D01*
X912771Y1146445D01*
Y1146436D01*
X913487Y1145720D01*
Y1138745D01*
X918323Y1133909D01*
Y1092130D01*
X910496Y1084302D01*
Y1065978D01*
Y1064398D01*
X909129Y1063031D01*
X905067D01*
X892315D01*
X890295Y1065051D01*
Y1102957D01*
X891853Y1104515D01*
X892477D01*
X901350D01*
X905113Y1108278D01*
Y1135556D01*
X906248Y1136691D01*
Y1138528D01*
X907449Y1139730D01*
X909323Y1141604D01*
Y1159006D01*
X908553Y1159776D01*
Y1162154D01*
X908795Y1162396D01*
X910395D01*
X910630Y1162161D01*
Y1152669D01*
G37*
G36*
G01X914853Y1158412D02*
X912912Y1156471D01*
Y1149816D01*
X912809Y1149713D01*
X911823D01*
X911710Y1149826D01*
Y1162749D01*
X910998Y1163461D01*
X897096D01*
X896707Y1163072D01*
Y1162358D01*
X896507Y1162158D01*
X892753D01*
X890975Y1163936D01*
Y1181101D01*
X891798Y1181924D01*
X914085D01*
X915003D01*
X917553D01*
X918242Y1181234D01*
X918281Y1181195D01*
X919386Y1180090D01*
Y1162959D01*
X918281Y1161854D01*
X916611Y1160184D01*
X916427Y1160000D01*
X914853Y1158426D01*
Y1158412D01*
G37*
G36*
G01X894407Y1160958D02*
X899907D01*
X900107Y1160758D01*
Y1158858D01*
X899907Y1158658D01*
X894307D01*
X894107Y1158858D01*
Y1160658D01*
X894407Y1160958D01*
G37*
G36*
G01X907395Y1162396D02*
X905495D01*
X905295Y1162196D01*
Y1157796D01*
X905595Y1157496D01*
X907295D01*
X907543Y1157744D01*
Y1162248D01*
X907395Y1162396D01*
G37*
G36*
G01X904969Y1156196D02*
X907195D01*
X907595Y1155796D01*
Y1154896D01*
X907395Y1154696D01*
X904007D01*
X901507Y1157196D01*
Y1160958D01*
X901707Y1161158D01*
X903307D01*
X903607Y1160858D01*
X903707Y1160758D01*
Y1157458D01*
X904969Y1156196D01*
G37*
G36*
G01X1093567Y1354775D02*
X1093858Y1354484D01*
Y1340290D01*
X1093736Y1340168D01*
X1076019D01*
X1075789Y1340398D01*
Y1349305D01*
X1073347Y1351747D01*
X1073231Y1351863D01*
X1071206D01*
X1070444D01*
X1070315Y1351992D01*
Y1353978D01*
X1071112Y1354775D01*
X1093567D01*
G37*
G36*
G01X1069211Y1351779D02*
X1068046D01*
X1067434D01*
X1067301Y1351912D01*
Y1356216D01*
X1067918Y1356833D01*
X1068771Y1357686D01*
X1070747D01*
X1070945Y1357488D01*
Y1356030D01*
X1069315Y1354400D01*
Y1354007D01*
Y1351883D01*
X1069211Y1351779D01*
G37*
G36*
G01X1126167Y1354775D02*
X1126458Y1354484D01*
Y1340290D01*
X1126336Y1340168D01*
X1108619D01*
X1108389Y1340398D01*
Y1349305D01*
X1105947Y1351747D01*
X1105831Y1351863D01*
X1103806D01*
X1103044D01*
X1102915Y1351992D01*
Y1353979D01*
X1103711Y1354775D01*
X1126167D01*
G37*
G36*
G01X1101811Y1351779D02*
X1100646D01*
X1100034D01*
X1099901Y1351912D01*
Y1356216D01*
X1100518Y1356833D01*
X1101371Y1357686D01*
X1103418D01*
X1103589Y1357515D01*
Y1356074D01*
X1101915Y1354400D01*
Y1354007D01*
Y1351883D01*
X1101811Y1351779D01*
G37*
G36*
G01X1158867Y1354775D02*
X1159158Y1354484D01*
Y1340290D01*
X1159036Y1340168D01*
X1141319D01*
X1141089Y1340398D01*
Y1349305D01*
X1138647Y1351747D01*
X1138531Y1351863D01*
X1136506D01*
X1135744D01*
X1135615Y1351992D01*
Y1353958D01*
X1136432Y1354775D01*
X1158867D01*
G37*
G36*
G01X1134511Y1351779D02*
X1133346D01*
X1132734D01*
X1132601Y1351912D01*
Y1356216D01*
X1133218Y1356833D01*
X1134071Y1357686D01*
X1136118D01*
X1136289Y1357515D01*
Y1356074D01*
X1134615Y1354400D01*
Y1354007D01*
Y1351883D01*
X1134511Y1351779D01*
G37*
G36*
G01X1191767Y1354775D02*
X1192058Y1354484D01*
Y1340290D01*
X1191936Y1340168D01*
X1174219D01*
X1173989Y1340398D01*
Y1349305D01*
X1171547Y1351747D01*
X1171431Y1351863D01*
X1169406D01*
X1168644D01*
X1168555Y1351952D01*
Y1353978D01*
X1169352Y1354775D01*
X1191767D01*
G37*
G36*
G01X1167411Y1351779D02*
X1166246D01*
X1165634D01*
X1165501Y1351912D01*
Y1356216D01*
X1166118Y1356833D01*
X1166971Y1357686D01*
X1169018D01*
X1169189Y1357515D01*
Y1356074D01*
X1167515Y1354400D01*
Y1354007D01*
Y1351883D01*
X1167411Y1351779D01*
G37*
G36*
G01X1200211D02*
X1199046D01*
X1198434D01*
X1198301Y1351912D01*
Y1356216D01*
X1198918Y1356833D01*
X1199771Y1357686D01*
X1201818D01*
X1201989Y1357515D01*
Y1356074D01*
X1200315Y1354400D01*
Y1354007D01*
Y1351883D01*
X1200211Y1351779D01*
G37*
G36*
G01X1224567Y1354775D02*
X1224858Y1354484D01*
Y1340290D01*
X1224736Y1340168D01*
X1207019D01*
X1206789Y1340398D01*
Y1349305D01*
X1204347Y1351747D01*
X1204231Y1351863D01*
X1202206D01*
X1201444D01*
X1201335Y1351972D01*
Y1353978D01*
X1202132Y1354775D01*
X1224567D01*
G37*
G36*
G01X1277784Y1308544D02*
X1295454D01*
X1295745Y1308253D01*
Y1294157D01*
X1295525Y1293937D01*
X1277906D01*
X1277676Y1294167D01*
Y1303074D01*
Y1303313D01*
X1275249Y1305740D01*
X1272413D01*
X1272200Y1305953D01*
Y1307790D01*
X1272954Y1308544D01*
X1273312D01*
X1277784D01*
G37*
G36*
G01X1269188Y1305850D02*
Y1309821D01*
X1270822Y1311455D01*
X1272705D01*
X1272876Y1311284D01*
Y1309881D01*
X1271178Y1308183D01*
Y1305751D01*
X1271096Y1305669D01*
X1269369D01*
X1269188Y1305850D01*
G37*
G36*
G01X1302092Y1306085D02*
Y1309761D01*
X1303786Y1311455D01*
X1305446D01*
X1305780Y1311121D01*
Y1309843D01*
X1304082Y1308145D01*
Y1305890D01*
X1304006Y1305814D01*
X1302363D01*
X1302092Y1306085D01*
G37*
G36*
G01X1328358Y1308544D02*
X1328649Y1308253D01*
Y1294154D01*
X1328432Y1293937D01*
X1310810D01*
X1310580Y1294167D01*
Y1303074D01*
Y1303366D01*
X1308314Y1305632D01*
X1308022D01*
X1305997D01*
X1305235D01*
X1305092Y1305775D01*
Y1307700D01*
X1305936Y1308544D01*
X1328358D01*
G37*
G36*
G01X1361158Y1308744D02*
X1361449Y1308453D01*
Y1294370D01*
X1361216Y1294137D01*
X1343610D01*
X1343380Y1294367D01*
Y1303274D01*
X1340938Y1305716D01*
X1340822Y1305832D01*
X1338797D01*
X1338035D01*
X1337907Y1305960D01*
Y1307917D01*
X1338734Y1308744D01*
X1361158D01*
G37*
G36*
G01X1336802Y1305748D02*
X1335637D01*
X1335025D01*
X1334892Y1305881D01*
Y1310038D01*
X1336509Y1311655D01*
X1338328D01*
X1338580Y1311403D01*
Y1310043D01*
X1336906Y1308369D01*
Y1307976D01*
Y1305852D01*
X1336802Y1305748D01*
G37*
G36*
G01X1457997Y729714D02*
X1457706Y730005D01*
Y744199D01*
X1457828Y744321D01*
X1475545D01*
X1475775Y744091D01*
Y735184D01*
X1478217Y732742D01*
X1478333Y732626D01*
X1480896D01*
X1481157Y732365D01*
Y730565D01*
X1480306Y729714D01*
X1457997D01*
G37*
G36*
G01X1482353Y732710D02*
X1483518D01*
X1484130D01*
X1484263Y732577D01*
Y728273D01*
X1483646Y727656D01*
X1482793Y726803D01*
X1480746D01*
X1480575Y726974D01*
Y728415D01*
X1482249Y730089D01*
Y730482D01*
Y732606D01*
X1482353Y732710D01*
G37*
G36*
G01X1491079Y729714D02*
X1490788Y730005D01*
Y744199D01*
X1490910Y744321D01*
X1508627D01*
X1508857Y744091D01*
Y735184D01*
X1511299Y732742D01*
X1511415Y732626D01*
X1514028D01*
X1514257Y732397D01*
Y730497D01*
X1513474Y729714D01*
X1491079D01*
G37*
G36*
G01X1515435Y732710D02*
X1516600D01*
X1517212D01*
X1517345Y732577D01*
Y728273D01*
X1516728Y727656D01*
X1515875Y726803D01*
X1514047D01*
X1513657Y727193D01*
Y728415D01*
X1515331Y730089D01*
Y730482D01*
Y732606D01*
X1515435Y732710D01*
G37*
G36*
G01X1523879Y729714D02*
X1523588Y730005D01*
Y744199D01*
X1523710Y744321D01*
X1541427D01*
X1541657Y744091D01*
Y735184D01*
X1544099Y732742D01*
X1544215Y732626D01*
X1546828D01*
X1547057Y732397D01*
Y730497D01*
X1546274Y729714D01*
X1523879D01*
G37*
G36*
G01X1548235Y732710D02*
X1549400D01*
X1550012D01*
X1550145Y732577D01*
Y728273D01*
X1549528Y727656D01*
X1548675Y726803D01*
X1546628D01*
X1546457Y726974D01*
Y728415D01*
X1548131Y730089D01*
Y730482D01*
Y732606D01*
X1548235Y732710D01*
G37*
G36*
G01X1589779Y674005D02*
X1589488Y674296D01*
Y688490D01*
X1589610Y688612D01*
X1609042D01*
X1609257Y688397D01*
Y677775D01*
X1610115Y676917D01*
X1612805D01*
X1612957Y676765D01*
Y674765D01*
X1612197Y674005D01*
X1589779D01*
G37*
G36*
G01X1614135Y677001D02*
X1615300D01*
X1615912D01*
X1616045Y676868D01*
Y672564D01*
X1615428Y671947D01*
X1614575Y671094D01*
X1612528D01*
X1612357Y671265D01*
Y672706D01*
X1614031Y674380D01*
Y674773D01*
Y676897D01*
X1614135Y677001D01*
G37*
G36*
G01X1628126Y172008D02*
G02I-720J0D01*
G37*
G36*
G01X1622779Y655005D02*
X1622488Y655296D01*
Y669490D01*
X1622610Y669612D01*
X1641942D01*
X1642157Y669397D01*
Y658875D01*
X1643115Y657917D01*
X1645805D01*
X1645957Y657765D01*
Y655765D01*
X1645197Y655005D01*
X1622779D01*
G37*
G36*
G01X1647135Y658001D02*
X1648300D01*
X1648912D01*
X1649045Y657868D01*
Y653564D01*
X1648428Y652947D01*
X1647575Y652094D01*
X1645528D01*
X1645357Y652265D01*
Y653706D01*
X1647031Y655380D01*
Y655773D01*
Y657897D01*
X1647135Y658001D01*
G37*
G36*
G01X1659206Y1355120D02*
Y1366096D01*
X1656301Y1369001D01*
X1654301D01*
X1653882Y1369420D01*
Y1371269D01*
X1654731Y1372118D01*
X1676378D01*
Y1354844D01*
Y1354299D01*
X1675957Y1353878D01*
X1659597D01*
X1659206Y1354269D01*
Y1355120D01*
G37*
G36*
G01X1652762Y1369096D02*
X1651597D01*
X1650985D01*
X1650852Y1369229D01*
Y1373336D01*
X1652519Y1375003D01*
X1654198D01*
X1654540Y1374661D01*
Y1373391D01*
X1652866Y1371717D01*
Y1371324D01*
Y1369200D01*
X1652762Y1369096D01*
G37*
G36*
G01X1691988Y1355220D02*
Y1366196D01*
X1689083Y1369101D01*
X1687083D01*
X1686643Y1369541D01*
Y1371382D01*
X1687476Y1372215D01*
X1709152D01*
Y1354936D01*
Y1354273D01*
X1708967Y1354088D01*
X1692347D01*
X1691988Y1354447D01*
Y1355220D01*
G37*
G36*
G01X1683634Y1369532D02*
Y1373438D01*
X1685299Y1375103D01*
X1686973D01*
X1687211Y1374865D01*
Y1373380D01*
X1685624Y1371793D01*
Y1369534D01*
X1685458Y1369368D01*
X1683798D01*
X1683634Y1369532D01*
G37*
G36*
G01X1780256Y208367D02*
X1792522D01*
X1793090Y207799D01*
Y199964D01*
G02X1793032Y199824I-200J1D01*
G01X1793020Y199811D01*
G02X1792878Y199752I-142J141D01*
G01X1790325D01*
X1790280Y199763D01*
X1788804D01*
X1788530Y199489D01*
X1785160D01*
X1784909Y199740D01*
X1777170D01*
X1774810Y197380D01*
Y192997D01*
X1774390Y192577D01*
Y187525D01*
X1773874Y187009D01*
X1747507D01*
X1742008Y181510D01*
X1698370D01*
X1696160Y183720D01*
Y212546D01*
X1696172Y212558D01*
Y216222D01*
X1698390Y218440D01*
X1737500D01*
X1747121Y208819D01*
X1747573Y208367D01*
X1780256D01*
G37*
G36*
G01X1734988Y1557271D02*
X1736788D01*
X1736888D01*
X1736988Y1557171D01*
Y1557071D01*
Y1551271D01*
X1736888Y1551171D01*
X1734988D01*
X1734888Y1551271D01*
Y1557171D01*
X1734988Y1557271D01*
G37*
G36*
G01X1742988Y1551071D02*
X1738388D01*
X1738188D01*
X1737988Y1551271D01*
Y1553571D01*
X1738144Y1553727D01*
X1738544D01*
X1744001D01*
X1745458D01*
X1762520D01*
X1766146D01*
X1766718Y1553155D01*
Y1541318D01*
X1766232Y1540832D01*
X1746669D01*
X1745888Y1541613D01*
Y1548171D01*
Y1549071D01*
X1743888Y1551071D01*
X1742988D01*
G37*
G36*
G01X1760386Y57708D02*
G03I-720J0D01*
G37*
G36*
G01X1765086Y57508D02*
G03I-720J0D01*
G37*
G36*
G01X1778679Y1541372D02*
Y1550280D01*
X1777788Y1551171D01*
X1774288D01*
X1773988D01*
X1773788Y1551371D01*
Y1553471D01*
X1774044Y1553727D01*
X1774244D01*
X1779001D01*
X1779701D01*
X1796763D01*
X1799088D01*
X1799588Y1553227D01*
Y1542483D01*
X1797926Y1540821D01*
X1779230D01*
X1778679Y1541372D01*
G37*
G36*
G01X1772688Y1557271D02*
X1772788Y1557171D01*
Y1551271D01*
X1772688Y1551171D01*
X1770788D01*
X1770688Y1551271D01*
Y1557171D01*
X1770788Y1557271D01*
X1772688D01*
G37*
G36*
G01X1790350Y211192D02*
X1804910D01*
X1805630D01*
X1805840Y211402D01*
Y228502D01*
X1805060Y229282D01*
X1787440D01*
X1786160D01*
X1785890Y229012D01*
Y211692D01*
X1786329Y211253D01*
X1787349D01*
X1788739D01*
X1790289D01*
X1790350Y211192D01*
G37*
G36*
G01X1814729Y193362D02*
Y188764D01*
X1813744Y187779D01*
X1810894D01*
X1810588Y187473D01*
Y184373D01*
X1811262Y183699D01*
X1819174D01*
X1820400Y184925D01*
Y188538D01*
Y189470D01*
Y192923D01*
X1819703Y193620D01*
X1814987D01*
X1814729Y193362D01*
G37*
%LPC*%
G75*
G54D352*
X1731660Y208455D03*
X1701285D03*
%LPD*%
G75*
G54D100*
X147290Y481917D03*
Y505343D03*
X174070Y481377D03*
Y504803D03*
G54D101*
X152705Y680396D03*
Y673782D03*
X382797Y1580912D03*
Y1587526D03*
X454288Y1576826D03*
Y1583440D03*
X1188192Y579015D03*
Y585629D03*
X1726334Y667545D03*
Y660931D03*
G54D110*
X180780Y1509459D03*
X183142D03*
X185504D03*
X180780Y1540477D03*
X183142D03*
X185504D03*
X187866Y1509459D03*
X192591D03*
X197315D03*
X190228D03*
X194953D03*
X199677D03*
X187866Y1540477D03*
X192591D03*
X197315D03*
X190228D03*
X194953D03*
X199677D03*
X202039Y1509459D03*
X206764D03*
X211488D03*
X216213D03*
X213850D03*
X204402D03*
X209126D03*
X202039Y1540477D03*
X206764D03*
X211488D03*
X216213D03*
X213850D03*
X204402D03*
X209126D03*
X220937Y1509459D03*
X225661D03*
X230386D03*
X218575D03*
X223299D03*
X228024D03*
X220937Y1540477D03*
X225661D03*
X230386D03*
X218575D03*
X223299D03*
X228024D03*
X235110Y1509459D03*
X239835D03*
X244559D03*
X232748D03*
X237472D03*
X242197D03*
X235110Y1540477D03*
X239835D03*
X244559D03*
X232748D03*
X237472D03*
X242197D03*
X254008Y1509459D03*
X258732D03*
X249283D03*
X246921D03*
X251646D03*
X256370D03*
X254008Y1540477D03*
X258732D03*
X249283D03*
X246921D03*
X251646D03*
X256370D03*
X263457Y1509459D03*
X265819D03*
X261095D03*
Y1540477D03*
X263457D03*
X265819D03*
X308842Y1509459D03*
X311204D03*
X315928D03*
X313566D03*
X318290D03*
X308842Y1540477D03*
X311204D03*
X315928D03*
X313566D03*
X318290D03*
X320653Y1509459D03*
X325377D03*
X330101D03*
X334826D03*
X323015D03*
X327739D03*
X332464D03*
X320653Y1540477D03*
X325377D03*
X330101D03*
X334826D03*
X323015D03*
X327739D03*
X332464D03*
X339550Y1509459D03*
X344275D03*
X348999D03*
X341912D03*
X346637D03*
X337188D03*
X339550Y1540477D03*
X344275D03*
X348999D03*
X341912D03*
X346637D03*
X337188D03*
X353723Y1509459D03*
X358448D03*
X363172D03*
X351361D03*
X356086D03*
X360810D03*
X353723Y1540477D03*
X358448D03*
X363172D03*
X351361D03*
X356086D03*
X360810D03*
X367897Y1509459D03*
X372621D03*
X377345D03*
X365534D03*
X370259D03*
X374983D03*
X379708D03*
X367897Y1540477D03*
X372621D03*
X377345D03*
X365534D03*
X370259D03*
X374983D03*
X379708D03*
X391519Y1509459D03*
X393881D03*
X382070D03*
X386794D03*
X389157D03*
X384432D03*
X389157Y1540477D03*
X391519D03*
X393881D03*
X382070D03*
X386794D03*
X384432D03*
X444953Y1509459D03*
X447315D03*
X452039D03*
X449677D03*
X454401D03*
X444953Y1540477D03*
X447315D03*
X452039D03*
X449677D03*
X454401D03*
X456764Y1509459D03*
X461488D03*
X466212D03*
X459126D03*
X463850D03*
X468575D03*
X456764Y1540477D03*
X461488D03*
X466212D03*
X459126D03*
X463850D03*
X468575D03*
X470937Y1509459D03*
X475661D03*
X480386D03*
X478023D03*
X482748D03*
X473299D03*
X470937Y1540477D03*
X475661D03*
X480386D03*
X478023D03*
X482748D03*
X473299D03*
X485110Y1509459D03*
X489834D03*
X494559D03*
X499283D03*
X487472D03*
X492197D03*
X496921D03*
X485110Y1540477D03*
X489834D03*
X494559D03*
X499283D03*
X487472D03*
X492197D03*
X496921D03*
X504008Y1509459D03*
X508732D03*
X513456D03*
X501645D03*
X506370D03*
X511094D03*
X504008Y1540477D03*
X508732D03*
X513456D03*
X501645D03*
X506370D03*
X511094D03*
X527630Y1509459D03*
X518181D03*
X522905D03*
X525268D03*
X515819D03*
X520543D03*
X525268Y1540477D03*
X527630D03*
X518181D03*
X522905D03*
X515819D03*
X520543D03*
X529992Y1509459D03*
Y1540477D03*
X573015Y1509459D03*
Y1540477D03*
X575377Y1509459D03*
X580101D03*
X584826D03*
X577739D03*
X582463D03*
X587188D03*
X575377Y1540477D03*
X580101D03*
X584826D03*
X577739D03*
X582463D03*
X587188D03*
X589550Y1509459D03*
X594274D03*
X598999D03*
X603723D03*
X591912D03*
X596637D03*
X601361D03*
X589550Y1540477D03*
X594274D03*
X598999D03*
X603723D03*
X591912D03*
X596637D03*
X601361D03*
X608448Y1509459D03*
X613172D03*
X617896D03*
X606085D03*
X610810D03*
X615534D03*
X608448Y1540477D03*
X613172D03*
X617896D03*
X606085D03*
X610810D03*
X615534D03*
X622621Y1509459D03*
X627345D03*
X632070D03*
X620259D03*
X624983D03*
X629707D03*
X622621Y1540477D03*
X627345D03*
X632070D03*
X620259D03*
X624983D03*
X629707D03*
X646243Y1509459D03*
X636794D03*
X641518D03*
X634432D03*
X639156D03*
X643881D03*
X648605D03*
X646243Y1540477D03*
X636794D03*
X641518D03*
X634432D03*
X639156D03*
X643881D03*
X648605D03*
X655692Y1509459D03*
X658054D03*
X650967D03*
X653330D03*
Y1540477D03*
X655692D03*
X658054D03*
X650967D03*
X1188653Y1542459D03*
X1191015D03*
X1195739D03*
X1193377D03*
X1198101D03*
X1188653Y1573477D03*
X1191015D03*
X1195739D03*
X1193377D03*
X1198101D03*
X1200464Y1542459D03*
X1205188D03*
X1209912D03*
X1214637D03*
X1202826D03*
X1207550D03*
X1212275D03*
X1200464Y1573477D03*
X1205188D03*
X1209912D03*
X1214637D03*
X1202826D03*
X1207550D03*
X1212275D03*
X1219361Y1542459D03*
X1224086D03*
X1228810D03*
X1221723D03*
X1226448D03*
X1216999D03*
X1219361Y1573477D03*
X1224086D03*
X1228810D03*
X1221723D03*
X1226448D03*
X1216999D03*
X1233534Y1542459D03*
X1238259D03*
X1242983D03*
X1231172D03*
X1235897D03*
X1240621D03*
X1233534Y1573477D03*
X1238259D03*
X1242983D03*
X1231172D03*
X1235897D03*
X1240621D03*
X1247708Y1542459D03*
X1252432D03*
X1257156D03*
X1245345D03*
X1250070D03*
X1254794D03*
X1259519D03*
X1247708Y1573477D03*
X1252432D03*
X1257156D03*
X1245345D03*
X1250070D03*
X1254794D03*
X1259519D03*
X1271330Y1542459D03*
X1273692D03*
X1261881D03*
X1266605D03*
X1268968D03*
X1264243D03*
X1268968Y1573477D03*
X1271330D03*
X1273692D03*
X1261881D03*
X1266605D03*
X1264243D03*
X1316715Y1542459D03*
X1319077D03*
X1316715Y1573477D03*
X1319077D03*
X1323801Y1542459D03*
X1328526D03*
X1333250D03*
X1321439D03*
X1326163D03*
X1330888D03*
X1323801Y1573477D03*
X1328526D03*
X1333250D03*
X1321439D03*
X1326163D03*
X1330888D03*
X1337974Y1542459D03*
X1342699D03*
X1347423D03*
X1335612D03*
X1340337D03*
X1345061D03*
X1337974Y1573477D03*
X1342699D03*
X1347423D03*
X1335612D03*
X1340337D03*
X1345061D03*
X1352148Y1542459D03*
X1356872D03*
X1361596D03*
X1349785D03*
X1354510D03*
X1359234D03*
X1363959D03*
X1352148Y1573477D03*
X1356872D03*
X1361596D03*
X1349785D03*
X1354510D03*
X1359234D03*
X1363959D03*
X1366321Y1542459D03*
X1371045D03*
X1375770D03*
X1368683D03*
X1373407D03*
X1378132D03*
X1366321Y1573477D03*
X1371045D03*
X1375770D03*
X1368683D03*
X1373407D03*
X1378132D03*
X1389943Y1542459D03*
X1380494D03*
X1385218D03*
X1382856D03*
X1387581D03*
X1392305D03*
X1389943Y1573477D03*
X1380494D03*
X1385218D03*
X1382856D03*
X1387581D03*
X1392305D03*
X1399392Y1542459D03*
X1401754D03*
X1394667D03*
X1397030D03*
Y1573477D03*
X1399392D03*
X1401754D03*
X1394667D03*
X1452827Y1542459D03*
Y1573477D03*
X1455189Y1542459D03*
X1459913D03*
X1464638D03*
X1457551D03*
X1462275D03*
X1467000D03*
X1455189Y1573477D03*
X1459913D03*
X1464638D03*
X1457551D03*
X1462275D03*
X1467000D03*
X1469362Y1542459D03*
X1474086D03*
X1478811D03*
X1471724D03*
X1476449D03*
X1481173D03*
X1469362Y1573477D03*
X1474086D03*
X1478811D03*
X1471724D03*
X1476449D03*
X1481173D03*
X1483535Y1542459D03*
X1488260D03*
X1492984D03*
X1497708D03*
X1485897D03*
X1490622D03*
X1495346D03*
X1483535Y1573477D03*
X1488260D03*
X1492984D03*
X1497708D03*
X1485897D03*
X1490622D03*
X1495346D03*
X1502433Y1542459D03*
X1507157D03*
X1511882D03*
X1500071D03*
X1504795D03*
X1509519D03*
X1502433Y1573477D03*
X1507157D03*
X1511882D03*
X1500071D03*
X1504795D03*
X1509519D03*
X1526055Y1542459D03*
X1516606D03*
X1521330D03*
X1514244D03*
X1518968D03*
X1523693D03*
X1526055Y1573477D03*
X1516606D03*
X1521330D03*
X1514244D03*
X1518968D03*
X1523693D03*
X1535504Y1542459D03*
X1537866D03*
X1530779D03*
X1533142D03*
X1528417D03*
X1533142Y1573477D03*
X1535504D03*
X1537866D03*
X1530779D03*
X1528417D03*
X1580889Y1542459D03*
X1583251D03*
X1585613D03*
X1580889Y1573477D03*
X1583251D03*
X1585613D03*
X1587975Y1542459D03*
X1592700D03*
X1597424D03*
X1602148D03*
X1590337D03*
X1595062D03*
X1599786D03*
X1587975Y1573477D03*
X1592700D03*
X1597424D03*
X1602148D03*
X1590337D03*
X1595062D03*
X1599786D03*
X1606873Y1542459D03*
X1611597D03*
X1616322D03*
X1613959D03*
X1604511D03*
X1609235D03*
X1606873Y1573477D03*
X1611597D03*
X1616322D03*
X1613959D03*
X1604511D03*
X1609235D03*
X1621046Y1542459D03*
X1625770D03*
X1630495D03*
X1618684D03*
X1623408D03*
X1628133D03*
X1621046Y1573477D03*
X1625770D03*
X1630495D03*
X1618684D03*
X1623408D03*
X1628133D03*
X1635219Y1542459D03*
X1639944D03*
X1644668D03*
X1632857D03*
X1637581D03*
X1642306D03*
X1647030D03*
X1635219Y1573477D03*
X1639944D03*
X1644668D03*
X1632857D03*
X1637581D03*
X1642306D03*
X1647030D03*
X1654117Y1542459D03*
X1658841D03*
X1649392D03*
X1661204D03*
X1651755D03*
X1656479D03*
X1661204Y1573477D03*
X1654117D03*
X1658841D03*
X1649392D03*
X1651755D03*
X1656479D03*
X1663566Y1542459D03*
X1665928D03*
X1663566Y1573477D03*
X1665928D03*
G54D200*
X512969Y130014D03*
X511394D03*
Y160328D03*
X512969D03*
X528717Y130014D03*
X527142D03*
X525568D03*
X523993D03*
X522418D03*
X520843D03*
X519268D03*
X517694D03*
X516119D03*
X514544D03*
X520843Y160328D03*
X522418D03*
X523993D03*
X525568D03*
X527142D03*
X528717D03*
X514544D03*
X516119D03*
X517694D03*
X519268D03*
X533442Y130014D03*
X531867D03*
X530292D03*
Y160328D03*
X531867D03*
X533442D03*
G54D201*
X522418Y145171D03*
G54D210*
X573782Y373868D03*
X565908D03*
X573782Y378986D03*
Y376427D03*
X565908D03*
Y378986D03*
X573782Y387227D03*
Y384668D03*
X565908D03*
Y387227D03*
X573782Y389786D03*
X565908D03*
X573782Y403717D03*
Y401158D03*
Y398599D03*
X565908D03*
Y401158D03*
Y403717D03*
X601908Y373868D03*
Y384668D03*
Y387227D03*
Y376427D03*
Y378986D03*
Y389786D03*
X609782Y373868D03*
Y387227D03*
Y384668D03*
Y378986D03*
Y376427D03*
Y389786D03*
G54D102*
X150185Y680042D03*
X155225D03*
X150185Y674136D03*
X155225D03*
X380277Y1581266D03*
Y1587172D03*
X385317Y1581266D03*
Y1587172D03*
X451768Y1577180D03*
Y1583086D03*
X456808Y1577180D03*
Y1583086D03*
X1185672Y579369D03*
Y585275D03*
X1190712Y579369D03*
Y585275D03*
X1723814Y667191D03*
X1728854D03*
X1723814Y661285D03*
X1728854D03*
G54D111*
X179457Y1515083D03*
Y1517445D03*
Y1519807D03*
Y1522169D03*
Y1526894D03*
Y1531618D03*
Y1533980D03*
Y1524532D03*
Y1529256D03*
Y1536343D03*
X265173Y1517445D03*
Y1515083D03*
Y1519807D03*
Y1522169D03*
Y1526894D03*
Y1529256D03*
Y1531618D03*
Y1533980D03*
Y1536343D03*
Y1524532D03*
X307519Y1515083D03*
Y1517445D03*
Y1519807D03*
Y1522169D03*
Y1526894D03*
Y1531618D03*
Y1533980D03*
Y1524532D03*
Y1529256D03*
Y1536343D03*
X393235Y1517445D03*
Y1515083D03*
Y1519807D03*
Y1522169D03*
Y1526894D03*
Y1529256D03*
Y1531618D03*
Y1533980D03*
Y1536343D03*
Y1524532D03*
X443630Y1515083D03*
Y1517445D03*
Y1519807D03*
Y1522169D03*
Y1526894D03*
Y1531618D03*
Y1533980D03*
Y1524532D03*
Y1529256D03*
Y1536343D03*
X529346Y1517445D03*
Y1515083D03*
Y1519807D03*
Y1522169D03*
Y1526894D03*
Y1529256D03*
Y1531618D03*
Y1533980D03*
Y1536343D03*
Y1524532D03*
X571692Y1515083D03*
Y1517445D03*
Y1519807D03*
Y1522169D03*
Y1526894D03*
Y1531618D03*
Y1533980D03*
Y1524532D03*
Y1529256D03*
Y1536343D03*
X657408Y1517445D03*
Y1515083D03*
Y1519807D03*
Y1522169D03*
Y1526894D03*
Y1529256D03*
Y1531618D03*
Y1533980D03*
Y1536343D03*
Y1524532D03*
X1187330Y1548083D03*
Y1550445D03*
Y1559894D03*
Y1564618D03*
Y1552807D03*
Y1555169D03*
Y1566980D03*
Y1557532D03*
Y1562256D03*
Y1569343D03*
X1273046Y1550445D03*
Y1548083D03*
Y1552807D03*
Y1555169D03*
Y1559894D03*
Y1562256D03*
Y1564618D03*
Y1566980D03*
Y1557532D03*
Y1569343D03*
X1315392Y1548083D03*
Y1550445D03*
Y1559894D03*
Y1564618D03*
Y1552807D03*
Y1555169D03*
Y1566980D03*
Y1557532D03*
Y1562256D03*
Y1569343D03*
X1401108Y1550445D03*
Y1548083D03*
Y1552807D03*
Y1555169D03*
Y1559894D03*
Y1562256D03*
Y1564618D03*
Y1566980D03*
Y1557532D03*
Y1569343D03*
X1451504Y1548083D03*
Y1550445D03*
Y1559894D03*
Y1564618D03*
Y1552807D03*
Y1555169D03*
Y1566980D03*
Y1557532D03*
Y1562256D03*
Y1569343D03*
X1537220Y1550445D03*
Y1548083D03*
Y1552807D03*
Y1555169D03*
Y1559894D03*
Y1562256D03*
Y1564618D03*
Y1566980D03*
Y1557532D03*
Y1569343D03*
X1579566Y1548083D03*
Y1550445D03*
Y1559894D03*
Y1564618D03*
Y1552807D03*
Y1555169D03*
Y1566980D03*
Y1557532D03*
Y1562256D03*
Y1569343D03*
X1665282Y1550445D03*
Y1548083D03*
Y1552807D03*
Y1555169D03*
Y1559894D03*
Y1562256D03*
Y1564618D03*
Y1566980D03*
Y1557532D03*
Y1569343D03*
G54D120*
X230905Y1644448D03*
Y1658621D03*
Y1672795D03*
Y1686968D03*
Y1701141D03*
Y1715314D03*
Y1729488D03*
X246653Y1644448D03*
X238779Y1648385D03*
X246653Y1658621D03*
X238779Y1662558D03*
X246653Y1672795D03*
X238779Y1676732D03*
X246653Y1686968D03*
X238779Y1690905D03*
X246653Y1701141D03*
X238779Y1705078D03*
X246653Y1715314D03*
X238779Y1719251D03*
X246653Y1729488D03*
X238779Y1733425D03*
X254527Y1648385D03*
Y1662558D03*
Y1676732D03*
Y1690905D03*
Y1705078D03*
Y1719251D03*
Y1733425D03*
X262401Y1644448D03*
X270275Y1648385D03*
X262401Y1658621D03*
X270275Y1662558D03*
X262401Y1672795D03*
X270275Y1676732D03*
X262401Y1686968D03*
X270275Y1690905D03*
X262401Y1701141D03*
X270275Y1705078D03*
X262401Y1715314D03*
X270275Y1719251D03*
X262401Y1729488D03*
X270275Y1733425D03*
X278149Y1644448D03*
X286023Y1648385D03*
X278149Y1658621D03*
X286023Y1662558D03*
X278149Y1672795D03*
X286023Y1676732D03*
X278149Y1686968D03*
X286023Y1690905D03*
X278149Y1701141D03*
X286023Y1705078D03*
X278149Y1715314D03*
X286023Y1719251D03*
X278149Y1729488D03*
X286023Y1733425D03*
X297835Y1672795D03*
X305709Y1676732D03*
X297835Y1686968D03*
X305709Y1690905D03*
X297835Y1701141D03*
X305709Y1705078D03*
X297835Y1715314D03*
X305709Y1719251D03*
X297835Y1729488D03*
X305709Y1733425D03*
X313583Y1672795D03*
X321457Y1676732D03*
X313583Y1686968D03*
X321457Y1690905D03*
X313583Y1701141D03*
X321457Y1705078D03*
X313583Y1715314D03*
X321457Y1719251D03*
X313583Y1729488D03*
X321457Y1733425D03*
X329331Y1672795D03*
Y1686968D03*
Y1701141D03*
Y1715314D03*
Y1729488D03*
X345079Y1672795D03*
X337205Y1676732D03*
X345079Y1686968D03*
X337205Y1690905D03*
X345079Y1701141D03*
X337205Y1705078D03*
X345079Y1715314D03*
X337205Y1719251D03*
X345079Y1729488D03*
X337205Y1733425D03*
X352953Y1676732D03*
Y1690905D03*
Y1705078D03*
Y1719251D03*
Y1733425D03*
X495078Y1672795D03*
Y1686968D03*
Y1701141D03*
Y1715314D03*
Y1729488D03*
X510826Y1672795D03*
X502952Y1676732D03*
X510826Y1686968D03*
X502952Y1690905D03*
X510826Y1701141D03*
X502952Y1705078D03*
X510826Y1715314D03*
X502952Y1719251D03*
X510826Y1729488D03*
X502952Y1733425D03*
X526574Y1672795D03*
X518700Y1676732D03*
X526574Y1686968D03*
X518700Y1690905D03*
X526574Y1701141D03*
X518700Y1705078D03*
X526574Y1715314D03*
X518700Y1719251D03*
X526574Y1729488D03*
X518700Y1733425D03*
X542322Y1672795D03*
X534448Y1676732D03*
X542322Y1686968D03*
X534448Y1690905D03*
X542322Y1701141D03*
X534448Y1705078D03*
X542322Y1715314D03*
X534448Y1719251D03*
X542322Y1729488D03*
X534448Y1733425D03*
X550196Y1676732D03*
Y1690905D03*
Y1705078D03*
Y1719251D03*
Y1733425D03*
X562008Y1672795D03*
X569882Y1676732D03*
X562008Y1686968D03*
X569882Y1690905D03*
X562008Y1701141D03*
X569882Y1705078D03*
X562008Y1715314D03*
X569882Y1719251D03*
X562008Y1729488D03*
X569882Y1733425D03*
X577756Y1672795D03*
X585630Y1676732D03*
X577756Y1686968D03*
X585630Y1690905D03*
X577756Y1701141D03*
X585630Y1705078D03*
X577756Y1715314D03*
X585630Y1719251D03*
X577756Y1729488D03*
X585630Y1733425D03*
X593504Y1672795D03*
X601378Y1676732D03*
X593504Y1686968D03*
X601378Y1690905D03*
X593504Y1701141D03*
X601378Y1705078D03*
X593504Y1715314D03*
X601378Y1719251D03*
X593504Y1729488D03*
X601378Y1733425D03*
X609252Y1672795D03*
X617126Y1676732D03*
X609252Y1686968D03*
X617126Y1690905D03*
X609252Y1701141D03*
X617126Y1705078D03*
X609252Y1715314D03*
X617126Y1719251D03*
X609252Y1729488D03*
X617126Y1733425D03*
X1238778Y1672795D03*
Y1686968D03*
Y1701141D03*
Y1715314D03*
Y1729488D03*
X1254526Y1672795D03*
X1246652Y1676732D03*
X1254526Y1686968D03*
X1246652Y1690905D03*
X1254526Y1701141D03*
X1246652Y1705078D03*
X1254526Y1715314D03*
X1246652Y1719251D03*
X1254526Y1729488D03*
X1246652Y1733425D03*
X1270274Y1672795D03*
X1262400Y1676732D03*
X1270274Y1686968D03*
X1262400Y1690905D03*
X1270274Y1701141D03*
X1262400Y1705078D03*
X1270274Y1715314D03*
X1262400Y1719251D03*
X1270274Y1729488D03*
X1262400Y1733425D03*
X1286022Y1672795D03*
X1278148Y1676732D03*
X1286022Y1686968D03*
X1278148Y1690905D03*
X1286022Y1701141D03*
X1278148Y1705078D03*
X1286022Y1715314D03*
X1278148Y1719251D03*
X1286022Y1729488D03*
X1278148Y1733425D03*
X1305708Y1672795D03*
Y1686968D03*
X1293896Y1676732D03*
X1305708Y1701141D03*
X1293896Y1690905D03*
X1305708Y1715314D03*
X1293896Y1705078D03*
X1305708Y1729488D03*
X1293896Y1719251D03*
Y1733425D03*
X1313582Y1676732D03*
Y1690905D03*
Y1705078D03*
Y1719251D03*
Y1733425D03*
X1321456Y1672795D03*
X1329330Y1676732D03*
X1321456Y1686968D03*
X1329330Y1690905D03*
X1321456Y1701141D03*
X1329330Y1705078D03*
X1321456Y1715314D03*
X1329330Y1719251D03*
X1321456Y1729488D03*
X1329330Y1733425D03*
X1337204Y1672795D03*
X1345078Y1676732D03*
X1337204Y1686968D03*
X1345078Y1690905D03*
X1337204Y1701141D03*
X1345078Y1705078D03*
X1337204Y1715314D03*
X1345078Y1719251D03*
X1337204Y1729488D03*
X1345078Y1733425D03*
X1352952Y1672795D03*
X1360826Y1676732D03*
X1352952Y1686968D03*
X1360826Y1690905D03*
X1352952Y1701141D03*
X1360826Y1705078D03*
X1352952Y1715314D03*
X1360826Y1719251D03*
X1352952Y1729488D03*
X1360826Y1733425D03*
X1502952Y1672795D03*
X1510826Y1676732D03*
X1502952Y1686968D03*
X1510826Y1690905D03*
X1502952Y1701141D03*
X1510826Y1705078D03*
X1502952Y1715314D03*
X1510826Y1719251D03*
X1502952Y1729488D03*
X1510826Y1733425D03*
X1518700Y1672795D03*
X1526574Y1676732D03*
X1518700Y1686968D03*
X1526574Y1690905D03*
X1518700Y1701141D03*
X1526574Y1705078D03*
X1518700Y1715314D03*
X1526574Y1719251D03*
X1518700Y1729488D03*
X1526574Y1733425D03*
X1534448Y1672795D03*
X1542322Y1676732D03*
X1534448Y1686968D03*
X1542322Y1690905D03*
X1534448Y1701141D03*
X1542322Y1705078D03*
X1534448Y1715314D03*
X1542322Y1719251D03*
X1534448Y1729488D03*
X1542322Y1733425D03*
X1550196Y1672795D03*
X1558070Y1676732D03*
X1550196Y1686968D03*
X1558070Y1690905D03*
X1550196Y1701141D03*
X1558070Y1705078D03*
X1550196Y1715314D03*
X1558070Y1719251D03*
X1550196Y1729488D03*
X1558070Y1733425D03*
X1569882Y1672795D03*
Y1686968D03*
Y1701141D03*
Y1715314D03*
Y1729488D03*
X1585630Y1672795D03*
X1577756Y1676732D03*
X1585630Y1686968D03*
X1577756Y1690905D03*
X1585630Y1701141D03*
X1577756Y1705078D03*
X1585630Y1715314D03*
X1577756Y1719251D03*
X1585630Y1729488D03*
X1577756Y1733425D03*
X1601378Y1672795D03*
X1593504Y1676732D03*
X1601378Y1686968D03*
X1593504Y1690905D03*
X1601378Y1701141D03*
X1593504Y1705078D03*
X1601378Y1715314D03*
X1593504Y1719251D03*
X1601378Y1729488D03*
X1593504Y1733425D03*
X1617126Y1672795D03*
X1609252Y1676732D03*
X1617126Y1686968D03*
X1609252Y1690905D03*
X1617126Y1701141D03*
X1609252Y1705078D03*
X1617126Y1715314D03*
X1609252Y1719251D03*
X1617126Y1729488D03*
X1609252Y1733425D03*
X1625000Y1676732D03*
Y1690905D03*
Y1705078D03*
Y1719251D03*
Y1733425D03*
G54D300*
X1249152Y60384D03*
X1431175Y87432D03*
G54D211*
X576672Y228055D03*
G54D301*
X1259835Y127553D03*
Y130053D03*
Y132553D03*
Y135053D03*
Y137553D03*
Y140053D03*
Y142553D03*
Y145053D03*
X1280741Y135053D03*
Y132553D03*
Y130053D03*
Y127553D03*
Y145053D03*
Y142553D03*
Y140053D03*
Y137553D03*
G54D310*
X1658169Y414202D03*
G54D220*
X662740Y370677D03*
X659000D03*
X655260D03*
Y380323D03*
X662740D03*
X1360629Y106559D03*
Y116205D03*
X1364369D03*
X1368109Y106559D03*
Y116205D03*
G54D103*
X150185Y678073D03*
X155225D03*
X150185Y676105D03*
X155225D03*
X380277Y1583235D03*
Y1585203D03*
X385317Y1583235D03*
Y1585203D03*
X451768Y1581117D03*
Y1579149D03*
X456808Y1581117D03*
Y1579149D03*
X1185672Y583306D03*
Y581338D03*
X1190712Y583306D03*
Y581338D03*
X1723814Y665222D03*
X1728854D03*
X1723814Y663254D03*
X1728854D03*
G54D130*
X275630Y109804D03*
X708786Y113929D03*
X1750751Y110928D03*
G54D121*
X230905Y1649173D03*
Y1653897D03*
Y1663346D03*
Y1668070D03*
Y1677519D03*
Y1682244D03*
Y1691692D03*
Y1696417D03*
Y1705866D03*
Y1710590D03*
Y1720039D03*
Y1724763D03*
X238779Y1643661D03*
X246653Y1649173D03*
Y1653897D03*
X238779Y1653110D03*
Y1657834D03*
X246653Y1663346D03*
Y1668070D03*
X238779Y1667283D03*
Y1672007D03*
X246653Y1677519D03*
Y1682244D03*
X238779Y1681456D03*
Y1686180D03*
X246653Y1691692D03*
Y1696417D03*
X238779Y1695629D03*
Y1700354D03*
X246653Y1705866D03*
Y1710590D03*
X238779Y1709803D03*
Y1714527D03*
X246653Y1720039D03*
Y1724763D03*
X238779Y1723976D03*
Y1728700D03*
X246653Y1734212D03*
X254527Y1643661D03*
Y1653110D03*
Y1657834D03*
Y1667283D03*
Y1672007D03*
Y1681456D03*
Y1686180D03*
Y1695629D03*
Y1700354D03*
Y1709803D03*
Y1714527D03*
Y1723976D03*
Y1728700D03*
X270275Y1643661D03*
X262401Y1649173D03*
X270275Y1653110D03*
X262401Y1653897D03*
X270275Y1657834D03*
X262401Y1663346D03*
X270275Y1667283D03*
X262401Y1668070D03*
X270275Y1672007D03*
X262401Y1677519D03*
X270275Y1681456D03*
X262401Y1682244D03*
X270275Y1686180D03*
X262401Y1691692D03*
X270275Y1695629D03*
X262401Y1696417D03*
X270275Y1700354D03*
X262401Y1705866D03*
X270275Y1709803D03*
X262401Y1710590D03*
X270275Y1714527D03*
X262401Y1720039D03*
X270275Y1723976D03*
X262401Y1724763D03*
X270275Y1728700D03*
X262401Y1734212D03*
X286023Y1643661D03*
X278149Y1649173D03*
X286023Y1653110D03*
X278149Y1653897D03*
X286023Y1657834D03*
X278149Y1663346D03*
X286023Y1667283D03*
X278149Y1668070D03*
X286023Y1672007D03*
X278149Y1677519D03*
X286023Y1681456D03*
X278149Y1682244D03*
X286023Y1686180D03*
X278149Y1691692D03*
X286023Y1695629D03*
X278149Y1696417D03*
X286023Y1700354D03*
X278149Y1705866D03*
X286023Y1709803D03*
X278149Y1710590D03*
X286023Y1714527D03*
X278149Y1720039D03*
X286023Y1723976D03*
X278149Y1724763D03*
X286023Y1728700D03*
X278149Y1734212D03*
X305709Y1672007D03*
X297835Y1677519D03*
X305709Y1681456D03*
X297835Y1682244D03*
X305709Y1686180D03*
X297835Y1691692D03*
X305709Y1695629D03*
X297835Y1696417D03*
X305709Y1700354D03*
X297835Y1705866D03*
X305709Y1709803D03*
X297835Y1710590D03*
X305709Y1714527D03*
X297835Y1720039D03*
X305709Y1723976D03*
X297835Y1724763D03*
X305709Y1728700D03*
X321457Y1672007D03*
X313583Y1677519D03*
X321457Y1681456D03*
X313583Y1682244D03*
X321457Y1686180D03*
X313583Y1691692D03*
X321457Y1695629D03*
X313583Y1696417D03*
X321457Y1700354D03*
X313583Y1705866D03*
X321457Y1709803D03*
X313583Y1710590D03*
X321457Y1714527D03*
X313583Y1720039D03*
X321457Y1723976D03*
X313583Y1724763D03*
X321457Y1728700D03*
X313583Y1734212D03*
X329331Y1677519D03*
Y1682244D03*
Y1691692D03*
Y1696417D03*
Y1705866D03*
Y1710590D03*
Y1720039D03*
Y1724763D03*
Y1734212D03*
X337205Y1672007D03*
X345079Y1677519D03*
Y1682244D03*
X337205Y1681456D03*
Y1686180D03*
X345079Y1691692D03*
Y1696417D03*
X337205Y1695629D03*
Y1700354D03*
X345079Y1705866D03*
Y1710590D03*
X337205Y1709803D03*
Y1714527D03*
X345079Y1720039D03*
Y1724763D03*
X337205Y1723976D03*
Y1728700D03*
X345079Y1734212D03*
X352953Y1672007D03*
Y1681456D03*
Y1686180D03*
Y1695629D03*
Y1700354D03*
Y1709803D03*
Y1714527D03*
Y1723976D03*
Y1728700D03*
X495078Y1677519D03*
Y1682244D03*
Y1691692D03*
Y1696417D03*
Y1705866D03*
Y1710590D03*
Y1720039D03*
Y1724763D03*
X502952Y1672007D03*
X510826Y1677519D03*
Y1682244D03*
X502952Y1681456D03*
Y1686180D03*
X510826Y1691692D03*
Y1696417D03*
X502952Y1695629D03*
Y1700354D03*
X510826Y1705866D03*
Y1710590D03*
X502952Y1709803D03*
Y1714527D03*
X510826Y1720039D03*
Y1724763D03*
X502952Y1723976D03*
Y1728700D03*
X510826Y1734212D03*
X518700Y1672007D03*
Y1681456D03*
Y1686180D03*
X526574Y1677519D03*
Y1682244D03*
X518700Y1695629D03*
Y1700354D03*
X526574Y1691692D03*
Y1696417D03*
X518700Y1709803D03*
Y1714527D03*
X526574Y1705866D03*
Y1710590D03*
X518700Y1723976D03*
Y1728700D03*
X526574Y1720039D03*
Y1724763D03*
Y1734212D03*
X534448Y1672007D03*
X542322Y1677519D03*
Y1682244D03*
X534448Y1681456D03*
Y1686180D03*
X542322Y1691692D03*
Y1696417D03*
X534448Y1695629D03*
Y1700354D03*
X542322Y1705866D03*
Y1710590D03*
X534448Y1709803D03*
Y1714527D03*
X542322Y1720039D03*
Y1724763D03*
X534448Y1723976D03*
Y1728700D03*
X542322Y1734212D03*
X550196Y1672007D03*
Y1681456D03*
Y1686180D03*
Y1695629D03*
Y1700354D03*
Y1709803D03*
Y1714527D03*
Y1723976D03*
Y1728700D03*
X569882Y1672007D03*
X562008Y1677519D03*
X569882Y1681456D03*
X562008Y1682244D03*
X569882Y1686180D03*
X562008Y1691692D03*
X569882Y1695629D03*
X562008Y1696417D03*
X569882Y1700354D03*
X562008Y1705866D03*
X569882Y1709803D03*
X562008Y1710590D03*
X569882Y1714527D03*
X562008Y1720039D03*
X569882Y1723976D03*
X562008Y1724763D03*
X569882Y1728700D03*
X585630Y1672007D03*
X577756Y1677519D03*
X585630Y1681456D03*
X577756Y1682244D03*
X585630Y1686180D03*
X577756Y1691692D03*
X585630Y1695629D03*
X577756Y1696417D03*
X585630Y1700354D03*
X577756Y1705866D03*
X585630Y1709803D03*
X577756Y1710590D03*
X585630Y1714527D03*
X577756Y1720039D03*
X585630Y1723976D03*
X577756Y1724763D03*
X585630Y1728700D03*
X577756Y1734212D03*
X601378Y1672007D03*
X593504Y1677519D03*
X601378Y1681456D03*
X593504Y1682244D03*
X601378Y1686180D03*
X593504Y1691692D03*
X601378Y1695629D03*
X593504Y1696417D03*
X601378Y1700354D03*
X593504Y1705866D03*
X601378Y1709803D03*
X593504Y1710590D03*
X601378Y1714527D03*
X593504Y1720039D03*
X601378Y1723976D03*
X593504Y1724763D03*
X601378Y1728700D03*
X593504Y1734212D03*
X617126Y1672007D03*
X609252Y1677519D03*
X617126Y1681456D03*
X609252Y1682244D03*
X617126Y1686180D03*
X609252Y1691692D03*
X617126Y1695629D03*
X609252Y1696417D03*
X617126Y1700354D03*
X609252Y1705866D03*
X617126Y1709803D03*
X609252Y1710590D03*
X617126Y1714527D03*
X609252Y1720039D03*
X617126Y1723976D03*
X609252Y1724763D03*
X617126Y1728700D03*
X609252Y1734212D03*
X1238778Y1677519D03*
Y1682244D03*
Y1691692D03*
Y1696417D03*
Y1705866D03*
Y1710590D03*
Y1720039D03*
Y1724763D03*
X1246652Y1672007D03*
X1254526Y1677519D03*
Y1682244D03*
X1246652Y1681456D03*
Y1686180D03*
X1254526Y1691692D03*
Y1696417D03*
X1246652Y1695629D03*
Y1700354D03*
X1254526Y1705866D03*
Y1710590D03*
X1246652Y1709803D03*
Y1714527D03*
X1254526Y1720039D03*
Y1724763D03*
X1246652Y1723976D03*
Y1728700D03*
X1254526Y1734212D03*
X1262400Y1672007D03*
Y1681456D03*
Y1686180D03*
X1270274Y1677519D03*
Y1682244D03*
X1262400Y1695629D03*
Y1700354D03*
X1270274Y1691692D03*
Y1696417D03*
X1262400Y1709803D03*
Y1714527D03*
X1270274Y1705866D03*
Y1710590D03*
X1262400Y1723976D03*
Y1728700D03*
X1270274Y1720039D03*
Y1724763D03*
Y1734212D03*
X1278148Y1672007D03*
X1286022Y1677519D03*
Y1682244D03*
X1278148Y1681456D03*
Y1686180D03*
X1286022Y1691692D03*
Y1696417D03*
X1278148Y1695629D03*
Y1700354D03*
X1286022Y1705866D03*
Y1710590D03*
X1278148Y1709803D03*
Y1714527D03*
X1286022Y1720039D03*
Y1724763D03*
X1278148Y1723976D03*
Y1728700D03*
X1286022Y1734212D03*
X1293896Y1672007D03*
Y1681456D03*
Y1686180D03*
Y1695629D03*
Y1700354D03*
Y1709803D03*
Y1714527D03*
Y1723976D03*
Y1728700D03*
X1313582Y1672007D03*
X1305708Y1677519D03*
X1313582Y1681456D03*
X1305708Y1682244D03*
X1313582Y1686180D03*
X1305708Y1691692D03*
X1313582Y1695629D03*
X1305708Y1696417D03*
X1313582Y1700354D03*
X1305708Y1705866D03*
X1313582Y1709803D03*
X1305708Y1710590D03*
X1313582Y1714527D03*
X1305708Y1720039D03*
X1313582Y1723976D03*
X1305708Y1724763D03*
X1313582Y1728700D03*
X1329330Y1672007D03*
X1321456Y1677519D03*
X1329330Y1681456D03*
X1321456Y1682244D03*
X1329330Y1686180D03*
X1321456Y1691692D03*
X1329330Y1695629D03*
X1321456Y1696417D03*
X1329330Y1700354D03*
X1321456Y1705866D03*
X1329330Y1709803D03*
X1321456Y1710590D03*
X1329330Y1714527D03*
X1321456Y1720039D03*
X1329330Y1723976D03*
X1321456Y1724763D03*
X1329330Y1728700D03*
X1321456Y1734212D03*
X1345078Y1672007D03*
X1337204Y1677519D03*
X1345078Y1681456D03*
X1337204Y1682244D03*
X1345078Y1686180D03*
X1337204Y1691692D03*
X1345078Y1695629D03*
X1337204Y1696417D03*
X1345078Y1700354D03*
X1337204Y1705866D03*
X1345078Y1709803D03*
X1337204Y1710590D03*
X1345078Y1714527D03*
X1337204Y1720039D03*
X1345078Y1723976D03*
X1337204Y1724763D03*
X1345078Y1728700D03*
X1337204Y1734212D03*
X1360826Y1672007D03*
X1352952Y1677519D03*
X1360826Y1681456D03*
X1352952Y1682244D03*
X1360826Y1686180D03*
X1352952Y1691692D03*
X1360826Y1695629D03*
X1352952Y1696417D03*
X1360826Y1700354D03*
X1352952Y1705866D03*
X1360826Y1709803D03*
X1352952Y1710590D03*
X1360826Y1714527D03*
X1352952Y1720039D03*
X1360826Y1723976D03*
X1352952Y1724763D03*
X1360826Y1728700D03*
X1352952Y1734212D03*
X1510826Y1672007D03*
X1502952Y1677519D03*
X1510826Y1681456D03*
X1502952Y1682244D03*
X1510826Y1686180D03*
X1502952Y1691692D03*
X1510826Y1695629D03*
X1502952Y1696417D03*
X1510826Y1700354D03*
X1502952Y1705866D03*
X1510826Y1709803D03*
X1502952Y1710590D03*
X1510826Y1714527D03*
X1502952Y1720039D03*
X1510826Y1723976D03*
X1502952Y1724763D03*
X1510826Y1728700D03*
X1526574Y1672007D03*
X1518700Y1677519D03*
X1526574Y1681456D03*
X1518700Y1682244D03*
X1526574Y1686180D03*
X1518700Y1691692D03*
X1526574Y1695629D03*
X1518700Y1696417D03*
X1526574Y1700354D03*
X1518700Y1705866D03*
X1526574Y1709803D03*
X1518700Y1710590D03*
X1526574Y1714527D03*
X1518700Y1720039D03*
X1526574Y1723976D03*
X1518700Y1724763D03*
X1526574Y1728700D03*
X1518700Y1734212D03*
X1542322Y1672007D03*
X1534448Y1677519D03*
X1542322Y1681456D03*
X1534448Y1682244D03*
X1542322Y1686180D03*
X1534448Y1691692D03*
X1542322Y1695629D03*
X1534448Y1696417D03*
X1542322Y1700354D03*
X1534448Y1705866D03*
X1542322Y1709803D03*
X1534448Y1710590D03*
X1542322Y1714527D03*
X1534448Y1720039D03*
X1542322Y1723976D03*
X1534448Y1724763D03*
X1542322Y1728700D03*
X1534448Y1734212D03*
X1558070Y1672007D03*
X1550196Y1677519D03*
X1558070Y1681456D03*
X1550196Y1682244D03*
X1558070Y1686180D03*
X1550196Y1691692D03*
X1558070Y1695629D03*
X1550196Y1696417D03*
X1558070Y1700354D03*
X1550196Y1705866D03*
X1558070Y1709803D03*
X1550196Y1710590D03*
X1558070Y1714527D03*
X1550196Y1720039D03*
X1558070Y1723976D03*
X1550196Y1724763D03*
X1558070Y1728700D03*
X1550196Y1734212D03*
X1569882Y1677519D03*
Y1682244D03*
Y1691692D03*
Y1696417D03*
Y1705866D03*
Y1710590D03*
Y1720039D03*
Y1724763D03*
X1577756Y1672007D03*
X1585630Y1677519D03*
Y1682244D03*
X1577756Y1681456D03*
Y1686180D03*
X1585630Y1691692D03*
Y1696417D03*
X1577756Y1695629D03*
Y1700354D03*
X1585630Y1705866D03*
Y1710590D03*
X1577756Y1709803D03*
Y1714527D03*
X1585630Y1720039D03*
Y1724763D03*
X1577756Y1723976D03*
Y1728700D03*
X1585630Y1734212D03*
X1593504Y1672007D03*
Y1681456D03*
Y1686180D03*
X1601378Y1677519D03*
Y1682244D03*
X1593504Y1695629D03*
Y1700354D03*
X1601378Y1691692D03*
Y1696417D03*
X1593504Y1709803D03*
Y1714527D03*
X1601378Y1705866D03*
Y1710590D03*
X1593504Y1723976D03*
Y1728700D03*
X1601378Y1720039D03*
Y1724763D03*
Y1734212D03*
X1609252Y1672007D03*
X1617126Y1677519D03*
Y1682244D03*
X1609252Y1681456D03*
Y1686180D03*
X1617126Y1691692D03*
Y1696417D03*
X1609252Y1695629D03*
Y1700354D03*
X1617126Y1705866D03*
Y1710590D03*
X1609252Y1709803D03*
Y1714527D03*
X1617126Y1720039D03*
Y1724763D03*
X1609252Y1723976D03*
Y1728700D03*
X1617126Y1734212D03*
X1625000Y1672007D03*
Y1681456D03*
Y1686180D03*
Y1695629D03*
Y1700354D03*
Y1709803D03*
Y1714527D03*
Y1723976D03*
Y1728700D03*
G54D112*
G01X19230Y1446459D02*
Y1409103D01*
X32417Y1395916D01*
X90992D01*
X94713Y1392195D01*
Y1385912D01*
G01X28562Y517025D02*
X31237D01*
G01X35352Y1663587D02*
Y1668587D01*
G01D02*
X32927D01*
G01X51114Y363337D02*
Y360862D01*
G01X48626Y552365D02*
Y549835D01*
G01X50631Y1537096D02*
X48957D01*
X48157Y1536296D01*
G01X42150Y1553655D02*
X47790Y1559295D01*
X48758D01*
G01X46150Y1553655D02*
X47590D01*
X48907Y1554972D01*
G01X38058Y1594396D02*
Y1591405D01*
G01X43633Y1606896D02*
X42208D01*
X41208Y1607896D01*
G01Y1617396D02*
Y1619896D01*
G01X54075Y303500D02*
X56620D01*
G01X59322Y363337D02*
Y360702D01*
G01X63429Y363337D02*
Y360702D01*
G01X58365Y552365D02*
Y549835D01*
G01X53299Y552365D02*
Y549870D01*
G01X61133Y1639571D02*
Y1639598D01*
X59343Y1641388D01*
X58633D01*
G01X56133Y1639571D02*
Y1640038D01*
X54449Y1641722D01*
G01X59427Y1646812D02*
Y1644410D01*
G01X64427Y1646812D02*
Y1643496D01*
G01X55427Y1646812D02*
Y1644819D01*
X56815Y1643431D01*
G01X77326Y145191D02*
X79726D01*
G01X69800Y268223D02*
X72462D01*
G01X67575Y290000D02*
Y287500D01*
G01X67681Y363337D02*
Y360702D01*
G01X76378Y1409080D02*
X72378D01*
G01X76378D02*
Y1406622D01*
G01X79740Y1418669D02*
X81409Y1417000D01*
X84000D01*
G01Y1421500D02*
X81863D01*
X79740Y1419377D01*
Y1418669D01*
G01X76575Y1434000D02*
X79055D01*
G01X76575D02*
Y1438722D01*
X77416Y1439563D01*
X80740D01*
G01X81771Y1549369D02*
Y1550848D01*
X82974Y1552051D01*
G01X76806Y1593265D02*
Y1596332D01*
G01X68133Y1590321D02*
Y1587896D01*
G01X81006Y1593265D02*
Y1596332D01*
G01X78406Y1604632D02*
Y1604219D01*
X80400Y1602225D01*
G01X73427Y1646812D02*
Y1644410D01*
G01X68427Y1646812D02*
Y1644410D01*
G01X77427Y1646812D02*
Y1644410D01*
G01X84949Y382219D02*
X87520D01*
G01X84949Y391391D02*
X87520D01*
G01X84949Y395865D02*
X87520D01*
G01X90601Y1385864D02*
X85736Y1390729D01*
Y1391597D01*
G01X94713Y1385912D02*
X97546D01*
G01X86925Y1417000D02*
X84000D01*
G01X86925Y1412500D02*
X84000D01*
G01X86925Y1408000D02*
X84000D01*
G01X86925Y1421500D02*
X84000D01*
G01X95925Y1430500D02*
X93000D01*
G01X95925Y1426000D02*
Y1430500D01*
G01Y1435500D02*
X93000D01*
G01X95925Y1440000D02*
X93000D01*
G01X90075Y1435500D02*
X93000D01*
G01X83796Y1533746D02*
X86374D01*
G01Y1537596D02*
X84111D01*
X83811Y1537296D01*
G01X85621Y1549369D02*
Y1551969D01*
G01X82208Y1611896D02*
X84833D01*
G01X82208Y1616396D02*
Y1611896D01*
G01Y1620896D02*
Y1616396D01*
G01Y1620896D02*
Y1625396D01*
G01X85345Y1702511D02*
X82945D01*
G01X95342Y1713741D02*
Y1716241D01*
G01D02*
X98645D01*
X100842Y1718438D01*
X102583D01*
G01X82500Y1720331D02*
X85182D01*
G01X101679Y158191D02*
Y160690D01*
X101675Y160694D01*
G01X101679Y151191D02*
Y153691D01*
G01X109040Y1385562D02*
X111355D01*
X111630Y1385287D01*
G01X101995Y1385743D02*
Y1388247D01*
G01X99075Y1430500D02*
X103022D01*
X103748Y1431226D01*
G01X99075Y1430500D02*
Y1431725D01*
X97800Y1433000D01*
G01X110378Y1670313D02*
X112778D01*
G01X110378Y1674313D02*
X112778D01*
G01X123811Y524366D02*
X118407D01*
G01X112353Y1646612D02*
Y1649012D01*
G01X126428Y1661087D02*
Y1658587D01*
G01X123353Y1695941D02*
Y1693541D01*
G01X117575Y1712450D02*
X120052D01*
G01X129493Y1709346D02*
X125058D01*
X122217Y1706505D01*
X120107D01*
G01X140360Y427155D02*
Y430160D01*
G01X130492Y1382305D02*
Y1384789D01*
G01X134595Y1385743D02*
X133147D01*
X132150Y1386740D01*
G01X141640Y1385562D02*
X143955D01*
X144230Y1385287D01*
G01X133120Y1452233D02*
Y1454751D01*
G01X137120Y1452233D02*
Y1454751D01*
G01X141028Y1452187D02*
Y1454705D01*
G01X132353Y1646612D02*
Y1649012D01*
G01X136353Y1646612D02*
Y1649012D01*
G01X127353Y1696062D02*
Y1693662D01*
G01X139893Y1705166D02*
X142293D01*
G01X129493Y1711846D02*
Y1709346D01*
G01X150318Y230828D02*
Y233536D01*
G01X144610Y427155D02*
Y429560D01*
G01X148075Y1429500D02*
X150900D01*
G01X148075Y1425500D02*
X150900D01*
G01X148075Y1433500D02*
X150900D01*
G01X143500Y1442425D02*
X143478Y1440000D01*
G01X147000Y1442425D02*
X146978Y1440000D01*
G01X148075Y1437500D02*
X150235D01*
X151082Y1436653D01*
G01X151000Y1442425D02*
X153213D01*
X154443Y1441195D01*
G01X145028Y1452187D02*
Y1454705D01*
G01X149028Y1452187D02*
Y1453986D01*
X148340Y1454674D01*
G01X152353Y1646612D02*
Y1649012D01*
G01X143778Y1685087D02*
Y1682587D01*
G01X147253Y1693662D02*
Y1696343D01*
G01X155353Y1690512D02*
Y1687843D01*
G01X149900Y1712791D02*
X147277D01*
G01X154740Y1707425D02*
X152815Y1705500D01*
G01X158740Y1707425D02*
X156825Y1705510D01*
G01X155740Y1726500D02*
Y1729726D01*
G01X155260Y1718500D02*
X157860D01*
G01X142842Y1722241D02*
X145267D01*
G01X149900Y1722941D02*
X152496D01*
G01X171435Y400560D02*
X173960D01*
G01X171425Y395040D02*
X174320D01*
G01X163192Y1382305D02*
Y1384789D01*
G01X167295Y1385743D02*
X165847D01*
X164850Y1386740D01*
G01X159427Y1690512D02*
Y1687843D01*
G01X167500Y1715425D02*
Y1712864D01*
G01Y1718575D02*
Y1719940D01*
X166467Y1720973D01*
G01X162740Y1718500D02*
X167425D01*
X167500Y1718575D01*
G01X178169Y147260D02*
X182548D01*
G01X183890Y390585D02*
Y388180D01*
G01X174525Y416600D02*
X172120D01*
G01X174525Y412350D02*
X172120D01*
G01X174340Y1385562D02*
X176655D01*
X176930Y1385287D01*
G01X171925Y1711000D02*
Y1708428D01*
G01X181760Y1707313D02*
X180941D01*
X179444Y1708810D01*
G01X171925Y1715000D02*
Y1717984D01*
G01X185760Y1707313D02*
Y1707157D01*
X184007Y1705404D01*
X183813D01*
G01X171925Y1725000D02*
Y1727581D01*
G01X181760Y1718000D02*
X184340D01*
G01X181760Y1728951D02*
Y1731351D01*
G01X171925Y1721000D02*
Y1717984D01*
G01X185760Y1728951D02*
Y1731666D01*
G01X193925Y149000D02*
X192496D01*
X191264Y147768D01*
G01X194425Y156500D02*
Y154766D01*
X193610Y153951D01*
G01X189410Y390585D02*
Y388180D01*
G01X196092Y1382305D02*
Y1384789D01*
G01X200195Y1385743D02*
X198747D01*
X197750Y1386740D01*
G01X190270Y1554420D02*
X188254Y1552404D01*
Y1550797D01*
G01X197703Y1554067D02*
Y1550897D01*
G01X192978Y1553738D02*
Y1550797D01*
G01X197670Y1554100D02*
X197703Y1554067D01*
G01X193010Y1553770D02*
X192978Y1553738D01*
G01X197853Y1586110D02*
Y1588289D01*
X199448Y1589884D01*
G01X197853Y1586110D02*
X196118D01*
X192344Y1589884D01*
G01X188486Y1658766D02*
Y1658391D01*
X190242Y1656635D01*
G01X194000Y1714925D02*
Y1712362D01*
G01X198760Y1715000D02*
X201531D01*
G01X198925Y1707000D02*
Y1705227D01*
X199547Y1704605D01*
G01X197704Y1723000D02*
X195150D01*
G01X194000Y1718075D02*
Y1720551D01*
G01X189240Y1718000D02*
X193925D01*
X194000Y1718075D01*
G01X202776Y148760D02*
X206760D01*
G01X217925Y156500D02*
X215501D01*
X215241Y156240D01*
X212224D01*
G01X207240Y1385562D02*
X209555D01*
X209830Y1385287D01*
G01X213648Y1419187D02*
Y1416262D01*
G01X211876Y1553484D02*
Y1550897D01*
G01X207152Y1553632D02*
Y1550897D01*
G01X202427Y1553957D02*
Y1550697D01*
G01X211360Y1554000D02*
X211876Y1553484D01*
G01X207490Y1553970D02*
X207152Y1553632D01*
G01X202500Y1554030D02*
X202427Y1553957D01*
G01X204768Y1586134D02*
Y1589520D01*
X204404Y1589884D01*
G01X204768Y1586134D02*
X207758D01*
X211508Y1589884D01*
G01X211000Y1711925D02*
Y1709091D01*
X211103Y1708988D01*
G01X211000Y1715075D02*
Y1717675D01*
G01X206240Y1715000D02*
X210925D01*
X211000Y1715075D01*
G01X221075Y156500D02*
Y159075D01*
X222000Y160000D01*
G01X221051Y153167D02*
X218794D01*
X217925Y154036D01*
Y156500D01*
G01X228892Y1382305D02*
Y1384789D01*
G01X232995Y1385743D02*
X231547D01*
X230550Y1386740D01*
G01X235697Y44370D02*
Y39755D01*
G01X240708Y207651D02*
X242959D01*
X246250Y204360D01*
G01X235861Y711602D02*
X237585D01*
X238156Y712173D01*
X239843D01*
G01D02*
Y709715D01*
G01X240040Y1385562D02*
X242355D01*
X242630Y1385287D01*
G01X235628Y1589884D02*
Y1586151D01*
G01X240584Y1589884D02*
Y1586463D01*
G01X254756Y156727D02*
X257249D01*
X257252Y156730D01*
G01X254095Y209235D02*
X255270Y210410D01*
Y211895D01*
G01Y215045D02*
X252746D01*
X252660Y215131D01*
X250156D01*
G01X261925Y221500D02*
X258439Y218014D01*
Y214000D01*
G01X255270Y215045D02*
X255994D01*
X257039Y214000D01*
X258439D01*
G01X251202Y640909D02*
X253442D01*
X254671Y642138D01*
G01X262016Y644555D02*
X261741Y644830D01*
X259426D01*
G01X247688Y1589884D02*
Y1586419D01*
G01X252644Y1589884D02*
Y1586343D01*
G01X259748Y1589884D02*
Y1586409D01*
G01X276925Y207000D02*
X274000D01*
X273500Y207500D01*
G01X271500Y220441D02*
X267500D01*
G01X275500Y234075D02*
X279500D01*
G01X275500Y230925D02*
Y227499D01*
X277440Y225559D01*
X278500D01*
G01X278425Y230925D02*
X275500D01*
G01X262466Y595078D02*
X265100D01*
G01X267844Y611172D02*
Y608621D01*
X267601Y608378D01*
G01X269061Y644374D02*
X271149D01*
X271571Y644796D01*
G01X272955Y656155D02*
Y658558D01*
G01Y663505D02*
Y661099D01*
G01X273640Y1339416D02*
X275955D01*
X276230Y1339141D01*
G01X266595Y1339597D02*
X264507D01*
X264085Y1339175D01*
G01X273597Y1522995D02*
X274555Y1523953D01*
X276637D01*
G01X264704Y1589884D02*
Y1586313D01*
G01X293000Y222575D02*
X290000D01*
G01X285260Y237224D02*
Y234000D01*
G01X279499Y1522995D02*
X278541Y1523953D01*
X276637D01*
G01X292747Y1585722D02*
Y1585961D01*
X288824Y1589884D01*
G01X296478Y149203D02*
Y151703D01*
G01Y156203D02*
Y158702D01*
X296474Y158706D01*
G01X293000Y219425D02*
Y216500D01*
G01X292740Y227776D02*
Y225000D01*
X293000Y224740D01*
Y222575D01*
G01X302500Y250425D02*
X310547D01*
X313500Y247472D01*
G01X292705Y582879D02*
Y580275D01*
G01X297815Y582879D02*
Y580384D01*
G01X301791Y678615D02*
X303879D01*
X304301Y679037D01*
G01X294746Y678796D02*
X292431D01*
X292156Y679071D01*
G01X305685Y695340D02*
Y697746D01*
G01Y690396D02*
Y692799D01*
G01X295388Y1336131D02*
Y1338615D01*
G01X299491Y1339569D02*
X298043D01*
X297046Y1340566D01*
G01X295928Y1589884D02*
Y1588903D01*
X292747Y1585722D01*
G01X299938Y1585884D02*
Y1588938D01*
X300884Y1589884D01*
G01X299938Y1585884D02*
X303988D01*
X307988Y1589884D01*
G01X310425Y241000D02*
Y243925D01*
G01X317240Y256528D02*
Y252970D01*
G01X327597Y241000D02*
X313575D01*
G01D02*
X313500Y241075D01*
Y247472D01*
G01X308925Y263000D02*
Y260075D01*
G01X306536Y1339388D02*
X308851D01*
X309126Y1339113D01*
G01X325617Y81168D02*
Y76938D01*
G01X327597Y241000D02*
X329219Y239378D01*
G01X326177Y270260D02*
X331000D01*
G01X327516Y698946D02*
X325201D01*
X324926Y699221D01*
G01X334561Y698765D02*
X336015D01*
X337030Y697750D01*
G01X328292Y1336074D02*
Y1338558D01*
G01X332395Y1339512D02*
X330947D01*
X329950Y1340509D01*
G01X352340Y215325D02*
X349216D01*
X348107Y216434D01*
Y220420D01*
G01X342075Y285000D02*
Y287925D01*
G01X336000Y284000D02*
X337000Y285000D01*
X338925D01*
G01D02*
Y279425D01*
X337240Y277740D01*
X335823D01*
G01X342000Y280575D02*
X344034Y282609D01*
G01X345582Y586415D02*
X343182D01*
G01X338664Y702203D02*
Y699660D01*
G01X338455Y715490D02*
Y717896D01*
G01Y710546D02*
Y712949D01*
G01X339440Y1339331D02*
X341755D01*
X342030Y1339056D01*
G01X363621Y130165D02*
Y127665D01*
G01X357319Y130005D02*
X363461D01*
X363621Y130165D01*
G01X352358Y211407D02*
Y215307D01*
X352340Y215325D01*
G01X353582Y555215D02*
X353263Y554896D01*
X351018D01*
G01X353582Y566415D02*
X351678D01*
X351157Y566936D01*
G01X353582Y570415D02*
X351157D01*
G01X360576Y698678D02*
X358261D01*
X357986Y698953D01*
G01X361092Y1336274D02*
Y1338758D01*
G01X365195Y1339712D02*
X363747D01*
X362750Y1340709D01*
G01X379070Y149077D02*
X379090Y149097D01*
Y151241D01*
X380667Y152818D01*
X384155D01*
G01X384375Y147365D02*
X382663Y149077D01*
X379070D01*
G01X370888Y158028D02*
Y155250D01*
G01X372677Y303760D02*
X367902D01*
G01X367621Y698497D02*
X369075D01*
X370090Y697482D01*
G01X371724Y701935D02*
Y699450D01*
G01X371515Y715222D02*
Y717628D01*
G01Y712681D02*
Y710278D01*
G01X372240Y1339531D02*
X374555D01*
X374830Y1339256D01*
G01X374337Y1387697D02*
X377190D01*
G01X390859Y123809D02*
X391600Y123068D01*
Y121178D01*
G01X395048Y123603D02*
Y121178D01*
G01X386703Y123762D02*
X390812D01*
X390859Y123809D01*
G01X386418Y142937D02*
X386118Y142637D01*
X380447D01*
G01X386418Y142937D02*
Y145322D01*
X384375Y147365D01*
G01X392721Y138980D02*
X386350D01*
G01X394575Y311500D02*
Y313845D01*
X396237Y315507D01*
G01X391425Y311500D02*
X391165Y311240D01*
X382323D01*
G01X395053Y318125D02*
X391425Y314497D01*
Y311500D01*
G01X393376Y469122D02*
X391617D01*
X389784Y470955D01*
Y476070D01*
G01X393616Y698746D02*
X391301D01*
X391026Y699021D01*
G01X397777Y1359043D02*
X395689D01*
X395267Y1358621D01*
G01X394824Y1664695D02*
Y1667120D01*
G01X389824Y1664695D02*
Y1667120D01*
G01X384824Y1664695D02*
Y1666476D01*
X385502Y1667154D01*
G01X384824Y1661545D02*
X382115D01*
G01X387324Y1678070D02*
Y1680495D01*
G01X392324Y1678070D02*
Y1680495D01*
G01X410701Y99148D02*
X409410Y97857D01*
Y81460D01*
X411797Y79073D01*
X417617D01*
G01X406243Y102501D02*
Y100076D01*
G01X405566Y144300D02*
X403141D01*
G01X400632D02*
X403141D01*
G01X405566Y148300D02*
X403141D01*
G01X405368Y152278D02*
X408603D01*
G01X405368Y157034D02*
Y152278D01*
G01X407299Y217646D02*
Y221340D01*
X409099Y223140D01*
X411610D01*
G01X404575Y304000D02*
X410000D01*
G01X399657Y546915D02*
X402946Y550204D01*
Y551915D01*
G01X414402Y544690D02*
Y559297D01*
X411219Y562480D01*
X404011D01*
X402946Y561415D01*
G01X404771Y696213D02*
Y698670D01*
G01X400661Y698565D02*
X401880Y697346D01*
Y696220D01*
G01X404555Y715290D02*
Y717696D01*
G01Y710346D02*
Y712749D01*
G01X404822Y1358862D02*
X407137D01*
X407412Y1358587D01*
G01X401659Y1522995D02*
X402617Y1523953D01*
X404699D01*
G01X407561Y1522995D02*
X406603Y1523953D01*
X404699D01*
G01X405331Y1548928D02*
Y1550847D01*
X406086Y1551602D01*
Y1552840D01*
G01X402983Y1552879D02*
X406047D01*
X406086Y1552840D01*
G01X400379Y1590275D02*
Y1595565D01*
X400905Y1596091D01*
G01X408925Y1641000D02*
X406075D01*
G01X399000Y1627288D02*
X397822Y1628466D01*
Y1629615D01*
G01X408925Y1637000D02*
Y1634233D01*
X409552Y1633606D01*
G01X411500Y1653500D02*
X409075D01*
G01Y1649500D02*
X410350D01*
X411448Y1650598D01*
G01X399824Y1664695D02*
Y1667120D01*
G01X409000Y1669740D02*
Y1667025D01*
G01X417000Y1664925D02*
X410372D01*
X409000Y1663553D01*
Y1662260D01*
G01X405000Y1680575D02*
Y1683500D01*
G01X397324Y1678070D02*
Y1680495D01*
G01X409000Y1680575D02*
Y1683500D01*
G01X417617Y79073D02*
X417987Y78703D01*
X424493D01*
X425555Y79765D01*
Y82014D01*
G01X417617Y79073D02*
X414963Y81727D01*
Y83352D01*
G01X413126Y99148D02*
X410701D01*
G01X421655Y92014D02*
X425555D01*
G01X423376Y99148D02*
Y96664D01*
G01X425555Y92014D02*
Y95097D01*
X423988Y96664D01*
X423376D01*
G01X415299Y217646D02*
Y220701D01*
X412860Y223140D01*
X411610D01*
G01X415140Y254165D02*
X412715D01*
G01X430520Y248768D02*
X424532D01*
X423730Y249570D01*
G01X415140Y250165D02*
X413715D01*
X412715Y251165D01*
G01X415140Y262165D02*
X412715D01*
G01X415140Y270165D02*
X412715D01*
G01X415140Y258165D02*
X412715D01*
G01X415140Y266165D02*
X412715D01*
G01X426616Y680946D02*
X424301D01*
X424026Y681221D01*
G01X425374Y1590275D02*
Y1590793D01*
X423837Y1592330D01*
X422007D01*
G01X413925Y1653500D02*
X411500D01*
G01X417000Y1668075D02*
X420000D01*
G01X417000Y1664925D02*
X420000D01*
G01X413925Y1657500D02*
X411500D01*
G01X417000Y1680575D02*
Y1683500D01*
G01X413000Y1680575D02*
Y1683500D01*
G01X429673Y77125D02*
X430500Y76298D01*
Y72900D01*
G01X433673Y77125D02*
Y73960D01*
G01X425555Y92014D02*
Y82014D01*
G01X429685Y91082D02*
Y88657D01*
G01X433685Y91082D02*
X429685D01*
G01X442673Y84125D02*
X438673D01*
G01Y77125D02*
X441182D01*
G01X477997Y163700D02*
Y170673D01*
X473940Y174730D01*
X440857D01*
X437997Y171870D01*
Y170701D01*
G01X433997D02*
Y173127D01*
X439290Y178420D01*
X476380D01*
X481997Y172803D01*
Y163700D01*
G01X439500Y486425D02*
Y484000D01*
G01X429784Y506947D02*
X431731Y505000D01*
X444500D01*
X447000Y502500D01*
X467000D01*
X468500Y501000D01*
Y493075D01*
G01X437555Y699896D02*
Y697490D01*
G01Y692546D02*
Y694949D01*
G01X428500Y1637075D02*
Y1637323D01*
X431000Y1639823D01*
Y1640500D01*
G01X445267Y82124D02*
X443266Y84125D01*
X442673D01*
G01X450992Y263768D02*
X449330Y265430D01*
Y270911D01*
G01X452480D02*
Y273420D01*
G01X449330Y270911D02*
Y274480D01*
X447840Y275970D01*
G01X443500Y486425D02*
X460425D01*
X462528Y488528D01*
Y493500D01*
G01X453472Y497240D02*
X449760D01*
G01X441575Y1604200D02*
X444128D01*
G01X441575Y1600200D02*
X444128D01*
G01X449760Y1637559D02*
X452500D01*
G01X453085Y1647008D02*
Y1648561D01*
X454099Y1649575D01*
G01X447576Y1647557D02*
Y1648424D01*
X446000Y1650000D01*
G01X443594Y1647602D02*
X446000Y1650000D01*
G01X465803Y70016D02*
X468228D01*
G01X462653D02*
Y72525D01*
G01X468500Y489925D02*
X465925D01*
G01X468500Y493075D02*
X468075Y493500D01*
X462528D01*
G01X459016Y656346D02*
X456701D01*
X456426Y656621D01*
G01X466061Y656165D02*
X466957D01*
X467854Y657062D01*
X469046D01*
G01X457240Y1632441D02*
Y1629500D01*
G01X470441Y1643260D02*
X468350Y1645351D01*
G01X461000Y1647075D02*
Y1650000D01*
G01X464925Y1655500D02*
X462500D01*
G01X465000Y1650575D02*
X466575D01*
X467500Y1651500D01*
G01X457000Y1647075D02*
Y1650000D01*
G01X468075Y1672000D02*
X468501D01*
X470463Y1670038D01*
G01X464925Y1659500D02*
Y1662500D01*
G01X468075Y1676000D02*
X468575D01*
X470500Y1674075D01*
G01X470309Y1684738D02*
Y1682308D01*
X469925Y1681924D01*
Y1680000D01*
G01D02*
X469000D01*
X467500Y1678500D01*
G01X465425Y1701000D02*
X462500D01*
G01X465425Y1697000D02*
X462500D01*
G01X468500Y1711425D02*
Y1708500D01*
G01X469975Y1720053D02*
Y1716050D01*
X468500Y1714575D01*
G01D02*
X466000D01*
G01X467416Y1727533D02*
Y1724808D01*
G01X462500Y1733500D02*
X465425D01*
G01X476700Y105574D02*
Y110574D01*
G01X487107Y285154D02*
X484562D01*
X483823Y285893D01*
G01X469955Y667946D02*
Y670349D01*
G01Y672890D02*
Y675296D01*
G01X475559Y1650740D02*
Y1655484D01*
X475575Y1655500D01*
G01D02*
X478500D01*
G01X472425Y1672000D02*
X470463Y1670038D01*
G01X475575Y1659500D02*
X477538Y1661463D01*
G01X473075Y1680000D02*
X476000D01*
G01X472425Y1676000D02*
X470500Y1674075D01*
G01X475575Y1701000D02*
X478500D01*
G01X475575Y1697000D02*
X478500D01*
G01X475575Y1714500D02*
X478500D01*
G01X475575Y1710500D02*
X478500D01*
G01X469975Y1727533D02*
Y1724808D01*
G01X478500Y1733500D02*
X475575D01*
G01X498314Y118493D02*
X498913Y119092D01*
X500836D01*
G01X493072Y171625D02*
X495323D01*
X498900Y168048D01*
Y161474D01*
X496943Y159517D01*
X495212Y158800D01*
X494200D01*
G01X495500Y161386D02*
Y164800D01*
X493072Y167228D01*
Y167625D01*
G01X492685Y160994D02*
Y160995D01*
X492246Y162055D01*
X490601Y163700D01*
X489997D01*
G01X497657Y185516D02*
X495232D01*
G01X488260Y422665D02*
Y418980D01*
G01X501500Y419425D02*
X498500D01*
G01X498661Y629665D02*
X500749D01*
X501171Y630087D01*
G01X491616Y629846D02*
X489301D01*
X489026Y630121D01*
G01X505932Y185516D02*
X503507D01*
G01X501500Y429575D02*
Y433000D01*
G01X512000Y429425D02*
Y426500D01*
X513500Y425000D01*
X526000D01*
X529000Y422000D01*
X544118D01*
X547529Y425411D01*
G01X502555Y641446D02*
Y643849D01*
G01Y648796D02*
Y646390D01*
G01X511861Y1589884D02*
Y1586419D01*
G01X504757Y1589884D02*
Y1586463D01*
G01X499801Y1589884D02*
Y1586151D01*
G01X522088Y207435D02*
X519579D01*
G01X522088Y204285D02*
X528658D01*
X532222Y207849D01*
G01X518500Y429425D02*
X522500D01*
G01D02*
X529075D01*
X532000Y426500D01*
G01X519185Y442000D02*
X521119D01*
X522831Y443712D01*
G01X524916Y595746D02*
X522601D01*
X522326Y596021D01*
G01X523921Y1589884D02*
Y1586409D01*
G01X516817Y1589884D02*
Y1586343D01*
G01X528877Y1589884D02*
Y1586313D01*
G01X543131Y123255D02*
X545686Y120700D01*
X546400D01*
G01X539575Y445500D02*
X544500Y440575D01*
Y440045D01*
X544844Y439701D01*
G01X543170Y434737D02*
X541263Y436644D01*
Y439237D01*
X536425Y444075D01*
Y445500D01*
G01D02*
X536185Y445740D01*
X529815D01*
G01X536425Y445500D02*
Y448925D01*
X544000Y456500D01*
X547999D01*
X549075Y457576D01*
Y459000D01*
G01X545925D02*
Y461075D01*
X543500Y463500D01*
G01X531961Y595565D02*
X534049D01*
X534471Y595987D01*
G01X535855Y609749D02*
Y607346D01*
G01X540106Y657325D02*
Y659725D01*
G01X537770Y1522995D02*
X538728Y1523953D01*
X540810D01*
G01X543672Y1522995D02*
X542714Y1523953D01*
X540810D01*
G01X554411Y152742D02*
X556811D01*
G01X554411Y156667D02*
X559484D01*
G01X548260Y444165D02*
Y441048D01*
X548856Y440452D01*
G01X550425Y451000D02*
Y448575D01*
X552510Y446490D01*
G01X549075Y459000D02*
X549315Y458760D01*
X555185D01*
G01X569925Y475500D02*
Y475630D01*
X564700Y480855D01*
X559620D01*
X558379Y482096D01*
G01X552400Y1585652D02*
X552273D01*
X548041Y1589884D01*
G01X552400Y1585652D02*
Y1589287D01*
X552997Y1589884D01*
G01X559348Y1585724D02*
Y1589131D01*
X560101Y1589884D01*
G01X566460Y160644D02*
X563951D01*
G01X574107Y294154D02*
X571562D01*
X570823Y294893D01*
G01X563575Y451000D02*
Y448425D01*
G01X565815Y462500D02*
X569104D01*
X569464Y462140D01*
G01X569925Y471500D02*
Y475500D01*
G01X567297Y487551D02*
X575348Y479500D01*
X576925D01*
G01X559348Y1585724D02*
X560897D01*
X565057Y1589884D01*
G01X582193Y83098D02*
X584402D01*
X585000Y82500D01*
G01X583628Y164356D02*
X581203D01*
G01X583628Y169415D02*
X581203D01*
G01X590948Y208991D02*
X588244D01*
G01X590235Y404287D02*
X587710D01*
G01X586500Y457925D02*
X583505D01*
G01X575075Y462000D02*
Y466000D01*
G01Y454500D02*
Y451263D01*
G01Y466000D02*
X577801D01*
G01X587500Y470308D02*
Y468581D01*
X586500Y467581D01*
Y467575D01*
G01X576925Y479500D02*
Y482425D01*
X580500Y486000D01*
X584276D01*
G01X603344Y149640D02*
X605853D01*
G01X595260Y160644D02*
Y163155D01*
X593975Y164440D01*
G01X603344Y153640D02*
X604844Y152140D01*
X605853D01*
G01X599776Y417760D02*
X602925Y414611D01*
Y412000D01*
G01D02*
X599884D01*
G01X590631Y454242D02*
Y458382D01*
X590552Y458461D01*
G01X596575Y449500D02*
X598496Y451421D01*
G01X605818Y260010D02*
X604718Y258910D01*
Y257562D01*
G01X608968Y260010D02*
Y258662D01*
X607868Y257562D01*
G01X609016Y274272D02*
Y260058D01*
X608968Y260010D01*
G01X606075Y412000D02*
X608931D01*
X610935Y409996D01*
G01X618575Y418000D02*
Y416123D01*
X617998Y415546D01*
G01X609224Y425240D02*
X608879Y425585D01*
X605796D01*
G01X615075Y440000D02*
Y443000D01*
G01X608169Y447260D02*
X612969D01*
G01X611925Y440000D02*
Y437000D01*
G01X604494Y439689D02*
X608690D01*
X609001Y440000D01*
X611925D01*
G01X616654Y1382864D02*
X619263D01*
G01X619202Y1386732D02*
X617115D01*
X616615Y1386232D01*
G01X619238Y1375082D02*
X616629D01*
G01X632240Y416441D02*
X634184D01*
X635200Y415425D01*
G01X624760Y421559D02*
Y424569D01*
G01X631075Y427000D02*
Y429888D01*
G01X619500Y438925D02*
X622174D01*
G01X634244Y510613D02*
X631510D01*
G01X619263Y1382864D02*
Y1378964D01*
G01X638000Y415425D02*
X635200D01*
G01X638000Y425575D02*
X640459D01*
X641490Y424544D01*
X643401D01*
X644673Y425816D01*
G01X646984Y507479D02*
X647022Y507441D01*
X648066D01*
X649771Y505736D01*
G01X639504Y512597D02*
X636614D01*
G01X643563Y1389972D02*
Y1392581D01*
G01X647445Y1389996D02*
Y1392605D01*
G01X639284Y1678805D02*
Y1683049D01*
G01X638878Y1709734D02*
Y1714439D01*
X637794Y1715523D01*
Y1718395D01*
G01Y1721545D02*
X635210D01*
G01X637794Y1718395D02*
X635210D01*
G01X641825Y1733000D02*
Y1730516D01*
G01Y1728000D02*
Y1730516D01*
G01Y1717138D02*
Y1718724D01*
X640865Y1719684D01*
G01D02*
X641825Y1720644D01*
Y1722138D01*
G01X662740Y370677D02*
Y375240D01*
G01X649500Y376425D02*
Y373500D01*
G01Y379575D02*
Y382500D01*
G01X652425Y390000D02*
Y385924D01*
G01X649500Y376425D02*
X652926D01*
X655260Y378759D01*
Y380323D01*
G01X650075Y418500D02*
Y422500D01*
G01D02*
X654248D01*
G01X663382Y516260D02*
X659398D01*
G01X656000Y521075D02*
X659425D01*
G01X658829Y1367283D02*
X658811Y1367301D01*
Y1371199D01*
G01X661685Y1367283D02*
X658829D01*
G01X658777Y1375061D02*
X660633D01*
X661713Y1373981D01*
G01X658743Y1378931D02*
X658777Y1378897D01*
Y1375061D01*
G01X655702Y1388498D02*
Y1391107D01*
G01X659559Y1388440D02*
Y1391027D01*
G01X651877Y1388465D02*
Y1391074D01*
G01X662971Y1679019D02*
Y1686822D01*
X665212Y1689063D01*
G01X656800Y1691225D02*
X658491Y1689534D01*
Y1688965D01*
G01X651975Y1728000D02*
X654508D01*
G01X651975Y1722138D02*
X657137D01*
X657173Y1722174D01*
G01X651975Y1717138D02*
X653436D01*
X654527Y1718229D01*
G01X664653Y1717056D02*
X662129D01*
X661845Y1717340D01*
G01X651975Y1733000D02*
X657009D01*
X657173Y1732836D01*
G01X673618Y520000D02*
X676499D01*
X677424Y520925D01*
X679500D01*
G01X668575Y529500D02*
X671500D01*
G01X668575Y533500D02*
X679269D01*
X683083Y529686D01*
Y521583D01*
X683000Y521500D01*
G01X677730Y1635842D02*
X677429D01*
X673982Y1639289D01*
G01X677718Y1639704D02*
Y1643904D01*
G01X677730Y1647842D02*
X674486D01*
G01X677718Y1643904D02*
X675408D01*
X674908Y1644404D01*
Y1644481D01*
G01X671631Y1690786D02*
X670296Y1692121D01*
X666392D01*
X665212Y1690941D01*
Y1689063D01*
G01X665575Y1712084D02*
X667248D01*
X668058Y1712894D01*
Y1720092D01*
G01X673113Y1729686D02*
Y1727261D01*
G01Y1719024D02*
Y1716599D01*
G01X693367Y363329D02*
X694184Y364146D01*
X694870D01*
X694873Y364149D01*
X696105D01*
G01X689440Y363329D02*
Y362687D01*
X691484Y360643D01*
G01X679500Y520925D02*
X682425D01*
X683000Y521500D01*
G01X679500Y524075D02*
Y526834D01*
G01X697261Y1640773D02*
X693150D01*
G01X696030Y1627702D02*
X694482D01*
X693451Y1628733D01*
G01X689781Y1645891D02*
X688364D01*
X686825Y1647430D01*
G01X696764Y1678474D02*
X695133D01*
X691560Y1682047D01*
G01X696105Y364149D02*
X698014D01*
X698017Y364146D01*
X698703D01*
X699520Y363329D01*
G01X703520D02*
X707462D01*
X707545Y363246D01*
G01X697731Y1395113D02*
Y1397513D01*
G01X701925Y1596500D02*
Y1592633D01*
X702035Y1592523D01*
G01X701925Y1596500D02*
X699500D01*
G01D02*
X698500Y1595500D01*
Y1594075D01*
G01X701925Y1604500D02*
X699000D01*
G01X701925Y1608500D02*
X699500D01*
G01X703799Y1627618D02*
X706424D01*
X706681Y1627361D01*
G01X699799Y1627618D02*
X697610D01*
X697526Y1627702D01*
X696030D01*
G01X705688Y1650517D02*
X709361D01*
X713771Y1654927D01*
G01X706623Y1663001D02*
X703473D01*
G01X696764Y1681996D02*
Y1683453D01*
X698003Y1684692D01*
G01X717021Y220862D02*
X716021Y221862D01*
X713296D01*
G01X716596Y1403571D02*
X718911D01*
X719186Y1403296D01*
G01X709551Y1403752D02*
Y1406578D01*
G01X719152Y1630656D02*
X721137D01*
X722104Y1629689D01*
Y1626253D01*
G01X731500Y393287D02*
X727500D01*
G01D02*
Y390862D01*
G01X737468Y1690278D02*
X737935D01*
X741326Y1686887D01*
G01X732434Y1688248D02*
Y1690660D01*
G01X728454Y1688079D02*
Y1690491D01*
G01X737468Y1690278D02*
Y1692133D01*
X738550Y1693215D01*
G01X748820Y137864D02*
X751221D01*
G01X748425Y175500D02*
X748125Y175200D01*
Y170618D01*
G01X748441Y212760D02*
X745712D01*
G01X738230Y1400414D02*
Y1402898D01*
G01X749378Y1403671D02*
X751693D01*
X751968Y1403396D01*
G01X742333Y1403852D02*
X740885D01*
X739888Y1404849D01*
G01X751770Y1628208D02*
X749261D01*
G01X740205Y1643326D02*
X743039D01*
G01X754030Y1656008D02*
X751521D01*
G01X754030Y1659158D02*
X751521D01*
G01X752187Y1685419D02*
Y1682994D01*
G01Y1678069D02*
X754839D01*
G01X753559Y220240D02*
X756083D01*
G01X761000Y215575D02*
Y224830D01*
X757629Y228201D01*
G01Y239295D02*
Y228201D01*
G01X762913Y1510474D02*
X758163D01*
G01X761510Y1641559D02*
Y1638434D01*
G01X757770Y1628208D02*
X755261D01*
G01X762030Y1666158D02*
Y1668583D01*
G01X758030Y1666158D02*
Y1668583D01*
G01X757557Y1687769D02*
Y1684444D01*
G01X767381Y1673316D02*
Y1676594D01*
G01X774728Y153728D02*
X772270D01*
G01X771925Y364000D02*
X769000D01*
G01X778925Y371000D02*
X776500D01*
G01X773181Y415197D02*
X773205D01*
X773352Y415344D01*
X776077D01*
G01X791341Y281822D02*
X797183D01*
G01D02*
X797594Y282233D01*
G01X787905Y377452D02*
X792488D01*
G01X797551Y384932D02*
X803625D01*
X805484Y386791D01*
G01X798425Y392500D02*
Y393520D01*
X796021Y395924D01*
G01X789425Y407500D02*
X787000D01*
G01X866549Y748027D02*
Y712158D01*
X839781Y647534D01*
X822692Y630445D01*
Y628252D01*
X811537Y617097D01*
X789135D01*
G01X795421Y1328662D02*
Y1331257D01*
G01X798724Y366000D02*
X803500D01*
G01X808634Y386791D02*
X810686D01*
X811569Y387674D01*
G01X805491Y381020D02*
X802660D01*
G01X805484Y386791D02*
X804519Y387756D01*
X802462D01*
G01X811224Y399500D02*
Y395974D01*
G01X810224Y409500D02*
X808552D01*
X807564Y408512D01*
Y403805D01*
G01X809575Y504000D02*
X812500D01*
G01X809575Y508000D02*
X812819D01*
X817281Y503538D01*
X825748D01*
X828259Y501027D01*
G01X808425Y534500D02*
X805940D01*
G01X808133Y541448D02*
X802920Y546661D01*
Y566824D01*
X807663Y571567D01*
X816467D01*
X825200Y580300D01*
G01X815575Y392500D02*
Y393921D01*
X816991Y395337D01*
G01X823986Y423099D02*
X826339D01*
X826665Y423425D01*
G01X824500Y511575D02*
Y514500D01*
G01X817441Y520760D02*
Y517941D01*
G01X822559Y528240D02*
Y530876D01*
G01X825200Y580300D02*
X834750Y570750D01*
Y569297D01*
G01X842596Y58448D02*
X842597D01*
Y54740D01*
X841421Y53564D01*
X833284D01*
X831387Y55461D01*
Y58632D01*
G01X828601Y61752D02*
Y60731D01*
X830700Y58632D01*
X831387D01*
G01X841742Y105951D02*
X840337Y107356D01*
X834616D01*
G01D02*
Y110117D01*
X839361Y114862D01*
G01X845500Y390441D02*
X841862D01*
G01X835925Y393000D02*
X833097D01*
G01X830075Y409500D02*
X833000D01*
G01X836983Y435552D02*
X836065Y434634D01*
X834430D01*
G01X836983Y439552D02*
X834379D01*
X834106Y439279D01*
G01X836983Y459578D02*
X834251D01*
G01X836983Y455578D02*
X834251D01*
G01X835425Y475000D02*
Y477890D01*
G01X844760Y476724D02*
X843036Y475000D01*
X838575D01*
G01D02*
Y477554D01*
G01X831000Y511575D02*
Y514516D01*
X831798Y515314D01*
G01X843856Y87711D02*
Y89096D01*
X844936Y90176D01*
G01X851575Y381000D02*
X854552D01*
G01X852625Y401280D02*
X849750D01*
G01X861416Y402450D02*
X856945D01*
X855775Y401280D01*
G01X858925Y395500D02*
X856571D01*
X856512Y395559D01*
X852500D01*
G01X858925Y398537D02*
X856993D01*
X855775Y399755D01*
Y401280D01*
G01X852240Y467276D02*
Y470946D01*
G01X871145Y166362D02*
Y163862D01*
G01X862075Y395500D02*
Y398537D01*
G01X858925Y395500D02*
Y398537D01*
G01X872020Y413300D02*
Y411120D01*
X870864Y409964D01*
Y409930D01*
G01X874295Y166362D02*
Y163862D01*
G01Y176862D02*
X876696D01*
G01X874295Y171362D02*
X876696D01*
G01X881140Y183169D02*
X878328D01*
G01X881150Y187449D02*
X878221D01*
G01X877925Y301500D02*
X875447D01*
G01X889057Y1056033D02*
Y1053133D01*
G01X913386Y195925D02*
X909298D01*
G01X909161Y203012D02*
X913386D01*
G01Y210098D02*
X909320D01*
G01X913386Y217185D02*
X909320D01*
G01Y224271D02*
X909321Y224272D01*
X913386D01*
G01Y231358D02*
X909320D01*
G01X902376Y597449D02*
Y594657D01*
G01X905526Y597449D02*
Y594657D01*
G01X916889Y597073D02*
X905902D01*
X905526Y597449D01*
G01X903556Y611358D02*
Y614062D01*
G01X906706Y611358D02*
Y614062D01*
G01X916889Y611573D02*
X906921D01*
X906706Y611358D01*
G01X906473Y1161169D02*
Y1158574D01*
G01X912500Y1310000D02*
X912971Y1309529D01*
X919128D01*
X921989Y1312390D01*
X928110D01*
X933500Y1307000D01*
X942424D01*
X944883Y1304541D01*
X945872D01*
G01X931496Y210098D02*
X935497D01*
G01X931496Y224272D02*
X935497D01*
G01X931496Y217185D02*
X935497D01*
G01X931496Y231358D02*
X935497D01*
G01X931455Y604751D02*
X926983D01*
G01X931455Y619251D02*
X927127D01*
G01X931455Y633751D02*
X935483D01*
X935783Y634051D01*
G01X941073Y1137843D02*
X938507D01*
G01X953498Y1161169D02*
Y1158574D01*
G01X989227Y378999D02*
Y389311D01*
G01X988481Y516014D02*
X986056D01*
G01X977150Y1055484D02*
Y1052684D01*
G01X1005169Y293075D02*
X1010571D01*
X1012410Y291236D01*
X1015334D01*
G01X1000759Y451675D02*
X998359D01*
G01X1000759Y462675D02*
X998359D01*
G01X1000759Y457175D02*
X998359D01*
G01X1000759Y468175D02*
X998359D01*
G01X1000759Y473675D02*
X998359D01*
G01X1000759Y479175D02*
X998359D01*
G01X1000759Y484675D02*
X998359D01*
G01X1000759Y494175D02*
Y490175D01*
G01Y494175D02*
Y499675D01*
G01D02*
X998326D01*
G01X1008631Y510304D02*
X1006206D01*
G01X1007011Y541924D02*
X1004527D01*
G01X1007011Y553224D02*
X1004527D01*
G01X1001557Y1646205D02*
X999932Y1644580D01*
G01X1042527Y1646205D02*
X1001557D01*
G01X1015334Y291236D02*
X1017835D01*
G01X1011189Y493655D02*
X1008789D01*
G01X1011781Y510304D02*
X1014206D01*
G01X1020202Y538201D02*
X1022686D01*
G01X1020202Y541351D02*
X1017868D01*
X1017718Y541201D01*
G01X1012925Y558000D02*
Y560500D01*
G01X1040045Y391362D02*
X1030525D01*
G01X1021425Y402000D02*
Y404925D01*
G01X1040425Y411704D02*
X1034855D01*
G01X1034838Y538201D02*
X1032354D01*
G01X1034838Y541351D02*
X1035260Y540929D01*
X1036057D01*
X1037301Y539685D01*
G01X1021425Y566000D02*
Y568614D01*
G01X1031575Y566000D02*
Y567925D01*
X1031000Y568500D01*
G01X1040626Y668441D02*
Y730293D01*
X1038332Y732587D01*
Y745663D01*
X1035026Y748969D01*
Y756009D01*
G01X1043670Y406586D02*
X1040891D01*
G01X1046820D02*
X1049573D01*
G01X1040425Y414263D02*
X1045042D01*
X1046735Y412570D01*
Y406671D01*
X1046820Y406586D01*
G01X1051083Y483394D02*
X1053603D01*
X1055905Y485696D01*
Y490037D01*
G01X1042829Y521074D02*
X1045254D01*
G01X1042829Y516014D02*
X1045254D01*
G01X1042829Y534074D02*
X1045254D01*
G01X1042829Y526074D02*
X1045254D01*
G01X1044829Y549574D02*
X1047335D01*
G01X1044829Y544574D02*
X1045716D01*
X1047200Y543090D01*
G01X1039000Y557425D02*
Y555000D01*
G01X1050866Y1656096D02*
Y1659548D01*
G01X1042395Y1652082D02*
Y1646337D01*
X1042527Y1646205D01*
G01X1062642Y444859D02*
X1063282Y445499D01*
X1065671D01*
G01X1065721Y457959D02*
X1062741D01*
G01X1059055Y490037D02*
Y492537D01*
G01X1055905D02*
Y490037D01*
G01X1066363Y1388025D02*
Y1385625D01*
G01X1062405Y1385593D02*
Y1421752D01*
X1060426Y1423731D01*
Y1431526D01*
X1058143Y1433809D01*
G01X1063751Y1651069D02*
Y1653834D01*
G01X1064221Y1659995D02*
Y1662726D01*
G01X1075526Y427539D02*
X1073925D01*
X1072673Y428791D01*
G01X1071470Y475525D02*
X1068869D01*
G01X1077869Y467000D02*
X1080640D01*
G01X1077869Y471500D02*
X1080574D01*
G01X1083363Y472105D02*
X1081179D01*
X1080574Y471500D01*
G01X1068839Y479655D02*
X1071239D01*
G01X1080420Y487782D02*
X1077785D01*
G01X1080416Y482772D02*
X1079406Y483782D01*
X1077785D01*
G01X1080778Y1385543D02*
X1083093D01*
X1083368Y1385268D01*
G01X1073733Y1385724D02*
Y1388198D01*
G01X1068094Y1651070D02*
Y1654099D01*
G01X1068221Y1659995D02*
Y1662778D01*
G01X1090363Y440605D02*
X1087963D01*
G01X1090363Y446105D02*
X1087963D01*
G01X1090363Y462605D02*
X1087963D01*
G01X1090363Y457105D02*
X1087963D01*
G01X1090363Y451605D02*
X1088445D01*
X1087940Y452110D01*
G01X1090363Y468105D02*
X1087963D01*
G01X1090363Y489641D02*
X1087963D01*
G01X1090363Y484605D02*
X1087963D01*
G01X1092948Y479430D02*
X1095444D01*
X1095448Y479426D01*
G01X1090363Y494641D02*
X1087963D01*
G01X1091539Y1691229D02*
X1089030D01*
G01X1095489Y1696029D02*
X1092980D01*
G01X1095489Y1699179D02*
X1092980D01*
G01X1094514Y1715841D02*
X1092030D01*
G01X1094514Y1725991D02*
X1092030D01*
G01X1098873Y484391D02*
X1096473D01*
G01X1098873Y489391D02*
X1096473D01*
G01X1106333Y1385724D02*
X1104885D01*
X1103888Y1386721D01*
G01X1102230Y1382286D02*
Y1384770D01*
G01X1108747Y1528805D02*
Y1528638D01*
X1106700Y1526591D01*
G01X1109558Y1544511D02*
X1112823D01*
X1113887Y1543447D01*
G01X1098925Y1639000D02*
X1096500D01*
G01X1096469Y1643468D02*
X1097437Y1642500D01*
X1098925D01*
G01X1109000Y1668575D02*
Y1671107D01*
G01X1105000Y1679575D02*
Y1682132D01*
G01X1102639Y1696029D02*
X1105148D01*
G01X1098514Y1715841D02*
X1100998D01*
G01X1098514Y1725991D02*
X1100998D01*
G01X1113378Y1385543D02*
X1115693D01*
X1115968Y1385268D01*
G01X1114617Y1526318D02*
Y1528805D01*
G01X1115027Y1596326D02*
Y1598788D01*
G01X1115394Y1622752D02*
Y1620306D01*
G01X1116000Y1668575D02*
Y1671029D01*
G01X1112500Y1668575D02*
Y1671107D01*
G01X1120303Y1679510D02*
Y1682055D01*
G01X1119361Y1716159D02*
Y1713734D01*
G01X1139033Y1385724D02*
X1137585D01*
X1136588Y1386721D01*
G01X1134930Y1382286D02*
Y1384770D01*
G01X1133070Y1579453D02*
X1137523D01*
G01X1132168Y1623390D02*
Y1620860D01*
G01X1136097Y1623393D02*
X1137518D01*
X1138752Y1624627D01*
G01X1140117Y1668727D02*
Y1671421D01*
G01X1132209Y1672033D02*
Y1672870D01*
X1130345Y1674734D01*
X1128889D01*
G01X1150118Y207344D02*
Y206835D01*
X1152118Y204835D01*
G01X1150118Y212344D02*
Y211835D01*
X1152118Y209835D01*
G01X1140662Y483394D02*
X1143582D01*
X1144663Y484475D01*
Y489819D01*
G01X1146078Y1385543D02*
X1148393D01*
X1148668Y1385268D01*
G01X1144118Y1445987D02*
Y1449628D01*
G01X1153542Y1589453D02*
X1149278D01*
G01X1144107Y1668641D02*
Y1671118D01*
G01X1162086Y73939D02*
Y70131D01*
X1164031Y68186D01*
X1169352D01*
G01X1162086Y76509D02*
Y73939D01*
G01X1171933Y1385724D02*
X1170485D01*
X1169488Y1386721D01*
G01X1167830Y1382286D02*
Y1384770D01*
G01X1160163Y1441260D02*
Y1445627D01*
G01X1163350Y1454234D02*
X1166350D01*
G01X1169187Y1682631D02*
Y1687117D01*
G01X1184194Y57015D02*
X1181762D01*
G01X1181782Y52815D02*
Y56995D01*
X1181762Y57015D01*
G01Y61515D02*
X1184194D01*
G01X1172781Y447841D02*
X1175181D01*
G01X1172781Y442341D02*
X1175181D01*
G01X1172781Y458841D02*
X1175181D01*
G01X1172781Y464341D02*
X1175181D01*
G01X1172781Y469841D02*
X1175181D01*
G01X1178978Y1385543D02*
X1181293D01*
X1181568Y1385268D01*
G01X1187925Y1401000D02*
X1185000D01*
G01X1187925Y1396500D02*
X1185000D01*
G01X1187925Y1410000D02*
X1184100D01*
G01X1187925Y1405500D02*
X1185000D01*
G01X1181025Y1433000D02*
X1178400D01*
G01X1188025Y1428500D02*
X1184900D01*
G01X1179187Y1662159D02*
Y1666429D01*
G01X1196187Y100875D02*
X1200518D01*
G01X1202437Y185187D02*
X1200012D01*
G01X1188352Y432202D02*
X1185952D01*
G01X1188352Y440202D02*
X1185952D01*
G01X1188352Y448202D02*
X1185952D01*
G01X1188352Y444202D02*
X1185952D01*
G01X1188352Y436202D02*
X1185952D01*
G01X1188352Y452202D02*
X1185952D01*
G01X1199852Y460202D02*
X1195767D01*
G01X1199912Y465272D02*
X1195767D01*
G01X1196925Y1419000D02*
X1195000D01*
X1194000Y1418000D01*
G01X1196925Y1414500D02*
Y1419000D01*
G01Y1433000D02*
X1194000D01*
G01X1196925Y1428500D02*
X1194000D01*
G01X1198800Y1421500D02*
X1200075Y1420225D01*
Y1419000D01*
G01X1204204Y1419721D02*
X1202056D01*
X1201335Y1419000D01*
X1200075D01*
G01X1187925Y1437500D02*
Y1440400D01*
G01X1198250Y1587440D02*
X1196127Y1585317D01*
Y1583797D01*
G01X1205758Y1619274D02*
X1203827D01*
X1200217Y1622884D01*
G01X1190334Y1666276D02*
X1192903D01*
G01X1189780Y1673050D02*
Y1671477D01*
X1190616Y1670641D01*
G01X1199612Y1697850D02*
Y1700334D01*
G01X1189462Y1693850D02*
Y1691366D01*
G01X1185676Y1695080D02*
Y1697249D01*
G01X1199612Y1693850D02*
Y1691366D01*
G01X1189462Y1697850D02*
Y1700334D01*
G01X1189407Y1715093D02*
Y1717518D01*
G01X1213156Y94846D02*
X1215581D01*
G01X1205182Y431875D02*
X1201157D01*
G01X1214339Y582886D02*
X1235000Y603547D01*
Y672345D01*
X1269000Y706345D01*
Y762075D01*
X1266075Y765000D01*
G01X1211778Y1385543D02*
X1214093D01*
X1214368Y1385268D01*
G01X1200690Y1382088D02*
Y1384572D01*
G01X1204733Y1385724D02*
X1203285D01*
X1202288Y1386721D01*
G01X1200820Y1587210D02*
X1200851Y1587179D01*
G01X1205710Y1587070D02*
X1205576Y1586936D01*
G01X1210300Y1583697D02*
Y1587030D01*
G01X1215090Y1587240D02*
X1215025Y1587175D01*
G01X1200851Y1587179D02*
Y1583797D01*
G01X1205576Y1586936D02*
Y1583897D01*
G01X1215025Y1587175D02*
Y1583897D01*
G01X1205758Y1619274D02*
Y1621321D01*
X1207321Y1622884D01*
G01X1212608Y1619274D02*
Y1622553D01*
X1212277Y1622884D01*
G01X1212608Y1619274D02*
X1215771D01*
X1219381Y1622884D01*
G01X1207954Y1677919D02*
Y1680419D01*
G01X1205122Y1673059D02*
X1202697D01*
G01X1204804Y1693859D02*
Y1691375D01*
G01X1214954Y1697859D02*
Y1700343D01*
G01Y1693859D02*
Y1691375D01*
G01X1204804Y1697859D02*
Y1700343D01*
G01X1214254Y1706861D02*
X1215840D01*
X1216875Y1705826D01*
G01X1210254Y1706861D02*
X1207770D01*
G01X1210254Y1717011D02*
X1207770D01*
G01X1210254Y1731011D02*
X1207770D01*
G01X1214254Y1720861D02*
X1216738D01*
G01X1214254Y1731011D02*
X1216738D01*
G01X1210254Y1720861D02*
X1207770D01*
G01X1214254Y1717011D02*
X1216738D01*
G01X1203052Y1731803D02*
X1204675D01*
X1205638Y1732766D01*
G01X1236879Y447255D02*
X1226034D01*
X1225654Y446875D01*
G01X1228372Y688501D02*
X1251740Y711869D01*
Y763623D01*
X1253117Y765000D01*
X1255925D01*
G01X1219749Y1583897D02*
Y1586801D01*
G01X1240029Y431255D02*
X1242429D01*
G01X1240029Y443255D02*
X1242429D01*
G01X1240029Y447255D02*
X1242429D01*
G01X1240029Y435255D02*
X1242429D01*
G01X1236879Y449755D02*
Y447255D01*
G01X1238338Y470376D02*
X1241374D01*
X1243647Y468103D01*
X1245703D01*
X1245752Y468152D01*
G01X1240240Y1339578D02*
X1242724D01*
G01X1244934Y1422362D02*
Y1418504D01*
X1244892Y1418462D01*
G01X1245000Y1430075D02*
X1242500D01*
G01X1244892Y1418462D02*
X1246269Y1417085D01*
X1252315D01*
G01X1241000Y1444075D02*
X1238675D01*
X1237100Y1442500D01*
G01X1245000Y1444075D02*
X1241000D01*
G01X1245000Y1437075D02*
X1242500D01*
G01X1243501Y1622884D02*
Y1619151D01*
G01X1245752Y468152D02*
Y470733D01*
G01X1249769Y1339397D02*
X1252084D01*
X1252359Y1339122D01*
G01X1252859Y1419925D02*
X1253062D01*
X1254905Y1418082D01*
Y1417026D01*
G01X1256859Y1419925D02*
X1257594Y1419190D01*
Y1417000D01*
G01X1248575Y1414500D02*
X1250399D01*
X1251399Y1413500D01*
X1253100D01*
G01X1245000Y1430075D02*
X1249000D01*
G01X1252859Y1419925D02*
X1248859D01*
G01X1256224Y1430075D02*
X1253000D01*
G01X1245000Y1437075D02*
X1249000D01*
G01X1253000D02*
X1255525D01*
X1256600Y1436000D01*
Y1434500D01*
G01X1248457Y1622884D02*
Y1619463D01*
G01X1255561Y1622884D02*
Y1619419D01*
G01X1265774Y395125D02*
X1268174D01*
G01X1262092Y454372D02*
X1265227D01*
G01X1262022Y459182D02*
Y454442D01*
X1262092Y454372D01*
G01X1262022Y459182D02*
Y497679D01*
X1301642Y537299D01*
G01X1292297Y657206D02*
X1274657Y674846D01*
Y760933D01*
X1273677Y761913D01*
G01X1275620Y1339550D02*
X1274172D01*
X1273175Y1340547D01*
G01X1271517Y1336112D02*
Y1338596D01*
G01X1272577Y1622884D02*
Y1619313D01*
G01X1260517Y1622884D02*
Y1619343D01*
G01X1267621Y1622884D02*
Y1619409D01*
G01X1301900Y660699D02*
X1288677Y673922D01*
Y758913D01*
G01X1282665Y1339369D02*
X1284980D01*
X1285255Y1339094D01*
G01X1281470Y1555995D02*
X1282428Y1556953D01*
X1284510D01*
G01X1287372Y1555995D02*
X1286414Y1556953D01*
X1284510D01*
G01X1301705Y82866D02*
X1303594D01*
X1304705Y81755D01*
Y79807D01*
G01X1290127Y401125D02*
Y403625D01*
G01Y410635D02*
Y408125D01*
G01X1301642Y537299D02*
X1304067D01*
G01X1297157Y541634D02*
X1297032D01*
X1295532Y540134D01*
Y539513D01*
G01X1304421Y1336055D02*
Y1338539D01*
G01X1295960Y1618665D02*
X1291741Y1622884D01*
G01X1295960Y1618665D02*
Y1622147D01*
X1296697Y1622884D01*
G01X1295960Y1618652D02*
Y1618665D01*
G01X1302908Y1618664D02*
Y1621991D01*
X1303801Y1622884D01*
G01X1302908Y1618664D02*
X1304537D01*
X1308757Y1622884D01*
G01X1309185Y77748D02*
Y74748D01*
G01X1316266Y567148D02*
Y564514D01*
G01X1315569Y1339312D02*
X1317884D01*
X1318159Y1339037D01*
G01X1308524Y1339493D02*
X1307076D01*
X1306079Y1340490D01*
G01X1329585Y561806D02*
X1332324D01*
X1332360Y561770D01*
G01X1348369Y1339512D02*
X1350684D01*
X1350959Y1339237D01*
G01X1341324Y1339693D02*
X1339876D01*
X1338879Y1340690D01*
G01X1337221Y1336255D02*
Y1338739D01*
G01X1372568Y613889D02*
X1370253D01*
X1369978Y614164D01*
G01X1369981Y1355715D02*
Y1356711D01*
X1368922Y1357770D01*
Y1359024D01*
G01X1373906D02*
X1371422D01*
G01X1379613Y613708D02*
X1381701D01*
X1382123Y614130D01*
G01X1383507Y625489D02*
Y627892D01*
G01Y630433D02*
Y632839D01*
G01X1380951Y1358843D02*
X1383266D01*
X1383541Y1358568D01*
G01X1392068Y1670391D02*
Y1667907D01*
G01X1381918Y1670391D02*
Y1667907D01*
G01X1392068Y1674391D02*
Y1676875D01*
G01X1381918Y1674391D02*
Y1676875D01*
G01X1391750Y1695238D02*
Y1697747D01*
G01X1384470Y1712038D02*
X1382045D01*
G01X1384470Y1708038D02*
X1382045D01*
G01X1384470Y1704038D02*
X1382045D01*
G01X1387620Y1712038D02*
X1390045D01*
G01X1387029Y1728318D02*
X1384604D01*
G01X1387620Y1723918D02*
Y1721418D01*
G01X1385061Y1723918D02*
Y1721418D01*
G01X1382229Y1733118D02*
X1379804D01*
G01X1399832Y642765D02*
X1402392D01*
X1402452Y642825D01*
G01X1405268Y646789D02*
X1402953D01*
X1402678Y647064D01*
G01X1398058Y1622167D02*
Y1619683D01*
G01X1408208Y1622167D02*
Y1621305D01*
X1409660Y1619853D01*
G01X1398058Y1626167D02*
Y1628651D01*
G01X1408208Y1626167D02*
Y1628651D01*
G01X1407890Y1646967D02*
X1410315D01*
G01X1418249Y244450D02*
X1414619D01*
G01X1414823Y647030D02*
X1414401Y646608D01*
X1412313D01*
G01X1416207Y663333D02*
Y665739D01*
G01Y658389D02*
Y660792D01*
G01X1409532Y1555995D02*
X1410490Y1556953D01*
X1412572D01*
G01X1415434Y1555995D02*
X1414476Y1556953D01*
X1412572D01*
G01X1425569Y1601663D02*
X1422914D01*
G01X1423722Y1609904D02*
Y1608616D01*
X1421232Y1606126D01*
G01X1415623Y1602234D02*
X1412467D01*
G01X1421392Y1621706D02*
X1423052Y1623366D01*
X1423722D01*
G01Y1619504D02*
Y1616780D01*
G01D02*
Y1613966D01*
G01X1419622Y1613342D02*
Y1616000D01*
G01X1413622Y1640917D02*
Y1643497D01*
X1413199Y1643920D01*
G01X1413622Y1637767D02*
X1411113D01*
G01X1421890Y1646967D02*
X1424315D01*
G01X1437868Y679369D02*
X1435553D01*
X1435278Y679644D01*
G01X1433832Y675765D02*
X1435757D01*
X1436257Y676265D01*
G01X1433049Y1596545D02*
X1435584D01*
G01X1432734Y1609966D02*
X1430244D01*
G01X1432734Y1613904D02*
X1430075D01*
G01X1432922Y1623504D02*
X1430319D01*
G01X1432922Y1619566D02*
Y1618303D01*
X1434316Y1616909D01*
G01X1431631Y1640469D02*
Y1641591D01*
X1433327Y1643287D01*
G01X1426513Y1632989D02*
Y1634373D01*
X1425390Y1635496D01*
G01X1431961Y1647087D02*
X1433911Y1649037D01*
G01X1441741Y596291D02*
X1439232D01*
G01X1447423Y679610D02*
X1447001Y679188D01*
X1444913D01*
G01X1448807Y695913D02*
Y698319D01*
G01Y690969D02*
Y693372D01*
G01X1450500Y1617425D02*
Y1614500D01*
G01X1442579Y1670878D02*
Y1673303D01*
G01X1447579Y1670878D02*
Y1673303D01*
G01X1452579Y1670878D02*
Y1673303D01*
G01X1442579Y1667728D02*
X1440244D01*
X1440027Y1667945D01*
G01X1442579Y1667728D02*
Y1665478D01*
X1440579Y1663478D01*
Y1661203D01*
G01X1445079Y1684253D02*
Y1686678D01*
G01X1449070Y1684297D02*
Y1686722D01*
G01X1445079Y1686678D02*
X1449026D01*
X1449070Y1686722D01*
G01X1466682Y544977D02*
X1463647D01*
G01X1466682Y560977D02*
X1464257D01*
G01X1466682Y556977D02*
X1464778D01*
X1464257Y557498D01*
G01X1458682Y576977D02*
X1456282D01*
G01X1465332Y695265D02*
X1467257D01*
X1468257Y696265D01*
G01X1470786Y698946D02*
X1468471D01*
X1468196Y699221D01*
G01X1457579Y1670878D02*
Y1672593D01*
X1456852Y1673320D01*
G01X1461702Y1670963D02*
Y1673302D01*
X1459294Y1675710D01*
X1457940D01*
G01X1513832Y563977D02*
X1515286D01*
X1516348Y565039D01*
Y582870D01*
X1508492Y590726D01*
X1489440D01*
X1488306Y591860D01*
X1473352D01*
X1471467Y589975D01*
Y581891D01*
G01X1477831Y698765D02*
X1479285D01*
X1480300Y697750D01*
G01X1481934Y702203D02*
Y699670D01*
G01X1481725Y715490D02*
Y717896D01*
G01Y710546D02*
Y712949D01*
G01X1503868Y698946D02*
X1501553D01*
X1501278Y699221D01*
G01X1510913Y698765D02*
X1512367D01*
X1513382Y697750D01*
G01X1507675Y1622884D02*
Y1619151D01*
G01X1512631Y1622884D02*
Y1619463D01*
G01X1513832Y543977D02*
X1519423D01*
X1519930Y543470D01*
G01X1513832Y547977D02*
X1516257D01*
G01X1513832Y551977D02*
X1516336D01*
G01X1515016Y702203D02*
Y699670D01*
G01X1514807Y715490D02*
Y717896D01*
G01Y710546D02*
Y712949D01*
G01X1519735Y1622884D02*
Y1619419D01*
G01X1524691Y1622884D02*
Y1619343D01*
G01X1542089Y288816D02*
X1544489D01*
G01X1536668Y698946D02*
X1534353D01*
X1534078Y699221D01*
G01X1536751Y1622884D02*
Y1619313D01*
G01X1531795Y1622884D02*
Y1619409D01*
G01X1543713Y698765D02*
X1544257D01*
X1545757Y700265D01*
Y700597D01*
X1546257Y701097D01*
G01X1547607Y715490D02*
Y717896D01*
G01Y710546D02*
Y712949D01*
G01X1560157Y1265938D02*
Y1266958D01*
X1558020Y1269095D01*
X1557559D01*
G01X1561913Y1273445D02*
X1558309D01*
X1558077Y1273213D01*
G01X1551546Y1555995D02*
X1550588Y1556953D01*
X1548684D01*
G01X1545644Y1555995D02*
X1546602Y1556953D01*
X1548684D01*
G01X1560074Y1618725D02*
X1555915Y1622884D01*
G01X1566442Y294816D02*
Y297316D01*
G01X1569798Y677006D02*
X1567483D01*
X1567208Y677281D01*
G01X1560074Y1618725D02*
Y1622087D01*
X1560871Y1622884D01*
G01X1560074Y1618242D02*
Y1618725D01*
G01X1566978Y1618364D02*
Y1621887D01*
X1567975Y1622884D01*
G01X1566978Y1618364D02*
X1568411D01*
X1572931Y1622884D01*
G01X1576843Y676825D02*
Y674425D01*
G01X1580737Y695956D02*
Y693550D01*
G01X1579177Y1265363D02*
Y1267117D01*
X1580320Y1268260D01*
X1585133D01*
X1586713Y1269840D01*
Y1271796D01*
X1586835Y1271918D01*
G01X1602568Y643237D02*
X1600253D01*
X1599978Y643512D01*
G01X1588832Y1269083D02*
X1588893D01*
X1591177Y1266799D01*
Y1265363D01*
G01X1610373Y554664D02*
X1610436Y554727D01*
Y559092D01*
G01X1613713Y561591D02*
X1611340D01*
X1610436Y560687D01*
Y559092D01*
G01D02*
X1609107D01*
X1607369Y560830D01*
Y561330D01*
G01X1609613Y643056D02*
Y641633D01*
X1608640Y640660D01*
G01X1613507Y657240D02*
Y654837D01*
G01Y659781D02*
Y662187D01*
G01X1622391Y566803D02*
Y564169D01*
G01X1638334Y561362D02*
X1638225Y561253D01*
X1635697D01*
G01X1645123Y624478D02*
X1645763Y625118D01*
Y627206D01*
G01X1635568Y624237D02*
X1633253D01*
X1632978Y624512D01*
G01X1646507Y638240D02*
Y635837D01*
G01X1662000Y217925D02*
X1663310Y216615D01*
Y215488D01*
G01X1661101Y1675927D02*
Y1671631D01*
G01X1651101Y1696399D02*
Y1700478D01*
G01X1654513Y1708609D02*
X1656997D01*
G01X1658189Y1704237D02*
X1660541D01*
G01X1650513Y1708609D02*
X1648029D01*
G01X1654513Y1723759D02*
X1656997D01*
G01X1650513Y1718759D02*
X1648029D01*
G01X1650513Y1723759D02*
X1648029D01*
G01X1654513Y1718759D02*
X1656997D01*
G01X1650513Y1733909D02*
X1648029D01*
G01X1654513D02*
X1656997D01*
G01X1662465Y1441749D02*
Y1444358D01*
G01X1679816Y1666228D02*
X1679325D01*
X1676971Y1668582D01*
G01X1675360Y1708927D02*
X1672500D01*
G01X1675360Y1723677D02*
Y1721252D01*
G01X1684790Y409290D02*
Y399762D01*
X1686660Y397892D01*
X1712390D01*
X1714444Y399946D01*
Y404220D01*
X1715044Y404820D01*
Y406970D01*
G01X1690066Y1403141D02*
X1688618D01*
X1687621Y1404138D01*
G01X1685963Y1399703D02*
Y1402187D01*
G01X1688243Y1666227D02*
Y1663802D01*
G01X1684733Y1696427D02*
Y1698952D01*
G01X1691952Y1698947D02*
Y1696422D01*
G01X1687883Y1696427D02*
Y1699152D01*
G01X1689513Y1708609D02*
X1691997D01*
G01X1685513D02*
X1683029D01*
G01X1685513Y1718759D02*
X1683782D01*
X1682724Y1717701D01*
G01X1689513Y1718759D02*
X1690998D01*
X1692218Y1717539D01*
G01X1692415Y1666165D02*
Y1663740D01*
G01X1695102Y1696422D02*
Y1698947D01*
G01X1710106Y44370D02*
Y48978D01*
G01Y39768D02*
Y44370D01*
G01X1722500Y368787D02*
X1721075D01*
X1719200Y370662D01*
Y371162D01*
G01X1715044Y406970D02*
X1715052Y406962D01*
X1718931D01*
G01X1726202Y1599168D02*
X1725638D01*
X1723606Y1597136D01*
Y1590548D01*
X1719673Y1586615D01*
X1712870D01*
G01X1710360Y1708927D02*
Y1706502D01*
G01X1724633Y1705115D02*
X1721912D01*
G01X1727325Y373337D02*
X1725500Y375162D01*
Y377787D01*
G01X1726425Y368787D02*
X1722500D01*
G01X1725500Y377787D02*
X1728300D01*
G01X1735351Y1569832D02*
X1735651Y1570132D01*
X1737914D01*
G01X1726888Y1658965D02*
Y1663465D01*
G01Y1672465D02*
Y1667965D01*
G01D02*
Y1663465D01*
G01Y1676965D02*
X1724323D01*
G01X1724263Y1672465D02*
X1726888D01*
G01X1735463Y1692040D02*
Y1694465D01*
G01X1725423Y1690231D02*
Y1692656D01*
G01X1724633Y1715265D02*
X1722149D01*
G01X1728633Y1705115D02*
X1731117D01*
G01X1728633Y1715265D02*
X1731117D01*
G01X1728633Y1720265D02*
X1731117D01*
G01X1724633Y1730415D02*
X1722149D01*
G01X1728633D02*
X1731117D01*
G01X1724633Y1720265D02*
X1722149D01*
G01X1747963Y1644790D02*
Y1641965D01*
G01X1750380Y1710233D02*
Y1707468D01*
G01X1749480Y1720583D02*
Y1718158D01*
G01X1754162Y364048D02*
X1756800D01*
G01X1754162Y368048D02*
X1756800D01*
G01X1752963Y1644790D02*
Y1643465D01*
X1754763Y1641665D01*
G01X1767795Y372452D02*
X1770280D01*
G01X1773657Y1566782D02*
X1771079D01*
G01X1771094Y1570332D02*
X1771394Y1570632D01*
X1773657D01*
G01X1769054Y1582405D02*
Y1585705D01*
G01X1772904Y1582405D02*
Y1585005D01*
G01X1771038Y1689965D02*
Y1692956D01*
G01X1789811Y180569D02*
Y178083D01*
G01X1793444Y180569D02*
X1797011D01*
G01X1793444D02*
Y178083D01*
G01X1784724Y403932D02*
X1782324D01*
G01X1784724Y410432D02*
X1782324D01*
G01X1784724Y418932D02*
X1782324D01*
G01X1784724Y425432D02*
X1782324D01*
G01X1804111Y180569D02*
Y178083D01*
G01X1807711Y180569D02*
Y178083D01*
G01X1805659Y408056D02*
X1805783Y407932D01*
X1816224D01*
G01X1805648Y421334D02*
X1815626D01*
X1815724Y421432D01*
G01X1817157Y371329D02*
X1816999Y371171D01*
X1812549D01*
G01X1817157Y371329D02*
Y373829D01*
G01X1816994Y395552D02*
Y398052D01*
G01X1813109Y390411D02*
X1815697D01*
X1816994Y391708D01*
Y395552D01*
G01X1816224Y407932D02*
Y410432D01*
G01X1815724Y421432D02*
Y423932D01*
G01X1825874Y427432D02*
Y424948D01*
G01X1825867Y431678D02*
X1828483D01*
X184530Y1514243D03*
X186105Y1516970D03*
X184530Y1527880D03*
X186105Y1530608D03*
X189254Y1514243D03*
X193979D03*
X198703D03*
X187680Y1519698D03*
X192404D03*
X197128D03*
X190829Y1516970D03*
X195554D03*
X200278D03*
X189254Y1536063D03*
X193979D03*
X198703D03*
X187680Y1533336D03*
X192404D03*
X197128D03*
X190829Y1530608D03*
X195554D03*
X200278D03*
X203428Y1514243D03*
X208152D03*
X212876D03*
X216026Y1519698D03*
X201853D03*
X206577D03*
X211302D03*
X214451Y1516970D03*
X205002D03*
X209727D03*
X203428Y1536063D03*
X208152D03*
X212876D03*
X216026Y1533336D03*
X201853D03*
X206577D03*
X211302D03*
X214451Y1530608D03*
X205002D03*
X209727D03*
X217601Y1514243D03*
X222325D03*
X227050D03*
X220750Y1519698D03*
X225475D03*
X230199D03*
X219176Y1516970D03*
X223900D03*
X228624D03*
X217601Y1536063D03*
X222325D03*
X227050D03*
X220750Y1533336D03*
X225475D03*
X230199D03*
X219176Y1530608D03*
X223900D03*
X228624D03*
X231774Y1514243D03*
X236498D03*
X241223D03*
X245947D03*
X234924Y1519698D03*
X239648D03*
X244372D03*
X233349Y1516970D03*
X238073D03*
X242798D03*
X231774Y1536063D03*
X236498D03*
X241223D03*
X245947D03*
X234924Y1533336D03*
X239648D03*
X244372D03*
X233349Y1530608D03*
X238073D03*
X242798D03*
X255396Y1514243D03*
X250672D03*
X249097Y1519698D03*
X253821D03*
X258546D03*
X247522Y1516970D03*
X252247D03*
X256971D03*
X255396Y1536063D03*
X260121D03*
X250672D03*
X249097Y1533336D03*
X253821D03*
X258546D03*
X247522Y1530608D03*
X252247D03*
X256971D03*
X312592Y1514243D03*
X317316D03*
X315742Y1519698D03*
X320466D03*
X314167Y1516970D03*
X318891D03*
X312592Y1527880D03*
X317316Y1536063D03*
X315742Y1533336D03*
X320466D03*
X314167Y1530608D03*
X318891D03*
X322041Y1514243D03*
X326765D03*
X331490D03*
X325190Y1519698D03*
X329915D03*
X334639D03*
X323616Y1516970D03*
X328340D03*
X333064D03*
X322041Y1536063D03*
X326765D03*
X331490D03*
X325190Y1533336D03*
X329915D03*
X334639D03*
X323616Y1530608D03*
X328340D03*
X333064D03*
X336214Y1514243D03*
X340938D03*
X345663D03*
X350387D03*
X344088Y1519698D03*
X348812D03*
X339364D03*
X342513Y1516970D03*
X347238D03*
X337789D03*
X336214Y1536063D03*
X340938D03*
X345663D03*
X350387D03*
X344088Y1533336D03*
X348812D03*
X339364D03*
X342513Y1530608D03*
X347238D03*
X337789D03*
X355112Y1514243D03*
X359836D03*
X364560D03*
X353537Y1519698D03*
X358261D03*
X362986D03*
X351962Y1516970D03*
X356686D03*
X361411D03*
X355112Y1536063D03*
X359836D03*
X364560D03*
X353537Y1533336D03*
X358261D03*
X362986D03*
X351962Y1530608D03*
X356686D03*
X361411D03*
X369285Y1514243D03*
X374009D03*
X378734D03*
X367710Y1519698D03*
X372434D03*
X377159D03*
X366135Y1516970D03*
X370860D03*
X375584D03*
X380309D03*
X369285Y1536063D03*
X374009D03*
X378734D03*
X367710Y1533336D03*
X372434D03*
X377159D03*
X366135Y1530608D03*
X370860D03*
X375584D03*
X380309D03*
X383458Y1514243D03*
X381883Y1519698D03*
X386608D03*
X385033Y1516970D03*
X383458Y1536063D03*
X388183D03*
X381883Y1533336D03*
X386608D03*
X385033Y1530608D03*
X448703Y1514243D03*
X453427D03*
X451853Y1519698D03*
X450278Y1516970D03*
X455002D03*
X448703Y1527880D03*
X453427Y1536063D03*
X451853Y1533336D03*
X450278Y1530608D03*
X455002D03*
X458152Y1514243D03*
X462876D03*
X467601D03*
X456577Y1519698D03*
X461301D03*
X466026D03*
X459727Y1516970D03*
X464451D03*
X469175D03*
X458152Y1536063D03*
X462876D03*
X467601D03*
X456577Y1533336D03*
X461301D03*
X466026D03*
X459727Y1530608D03*
X464451D03*
X469175D03*
X472325Y1514243D03*
X477049D03*
X481774D03*
X480199Y1519698D03*
X470750D03*
X475475D03*
X478624Y1516970D03*
X483349D03*
X473900D03*
X472325Y1536063D03*
X477049D03*
X481774D03*
X480199Y1533336D03*
X470750D03*
X475475D03*
X478624Y1530608D03*
X483349D03*
X473900D03*
X486498Y1514243D03*
X491223D03*
X495947D03*
X484923Y1519698D03*
X489648D03*
X494372D03*
X499097D03*
X488073Y1516970D03*
X492797D03*
X497522D03*
X486498Y1536063D03*
X491223D03*
X495947D03*
X484923Y1533336D03*
X489648D03*
X494372D03*
X499097D03*
X488073Y1530608D03*
X492797D03*
X497522D03*
X500671Y1514243D03*
X505396D03*
X510120D03*
X503821Y1519698D03*
X508545D03*
X513270D03*
X502246Y1516970D03*
X506971D03*
X511695D03*
X500671Y1536063D03*
X505396D03*
X510120D03*
X503821Y1533336D03*
X508545D03*
X513270D03*
X502246Y1530608D03*
X506971D03*
X511695D03*
X519569Y1514243D03*
X514845D03*
X517994Y1519698D03*
X522719D03*
X516420Y1516970D03*
X521144D03*
X519569Y1536063D03*
X524294D03*
X514845D03*
X517994Y1533336D03*
X522719D03*
X516420Y1530608D03*
X521144D03*
X576765Y1514243D03*
X581489D03*
X586214D03*
X579915Y1519698D03*
X584639D03*
X578340Y1516970D03*
X583064D03*
X587789D03*
X576765Y1527880D03*
X581489Y1536063D03*
X586214D03*
X579915Y1533336D03*
X584639D03*
X578340Y1530608D03*
X583064D03*
X587789D03*
X590938Y1514243D03*
X595663D03*
X600387D03*
X589363Y1519698D03*
X594088D03*
X598812D03*
X603537D03*
X592513Y1516970D03*
X597237D03*
X601962D03*
X590938Y1536063D03*
X595663D03*
X600387D03*
X589363Y1533336D03*
X594088D03*
X598812D03*
X603537D03*
X592513Y1530608D03*
X597237D03*
X601962D03*
X605111Y1514243D03*
X609836D03*
X614560D03*
X608261Y1519698D03*
X612985D03*
X617710D03*
X606686Y1516970D03*
X611411D03*
X616135D03*
X605111Y1536063D03*
X609836D03*
X614560D03*
X608261Y1533336D03*
X612985D03*
X617710D03*
X606686Y1530608D03*
X611411D03*
X616135D03*
X619285Y1514243D03*
X624009D03*
X628733D03*
X633458D03*
X622434Y1519698D03*
X627159D03*
X631883D03*
X620859Y1516970D03*
X625584D03*
X630308D03*
X619285Y1536063D03*
X624009D03*
X628733D03*
X633458D03*
X622434Y1533336D03*
X627159D03*
X631883D03*
X620859Y1530608D03*
X625584D03*
X630308D03*
X647631Y1514243D03*
X638182D03*
X642907D03*
X636607Y1519698D03*
X641332D03*
X646056D03*
X635033Y1516970D03*
X639757D03*
X644482D03*
X647631Y1536063D03*
X638182D03*
X642907D03*
X636607Y1533336D03*
X641332D03*
X646056D03*
X635033Y1530608D03*
X639757D03*
X644482D03*
X650781Y1519698D03*
X649206Y1516970D03*
X652356Y1536063D03*
X650781Y1533336D03*
X649206Y1530608D03*
X1192403Y1547243D03*
X1197127D03*
X1193978Y1549970D03*
X1198702D03*
X1192403Y1560880D03*
X1195553Y1566336D03*
X1200277D03*
X1193978Y1563608D03*
X1198702D03*
X1195553Y1552698D03*
X1200277D03*
X1197127Y1569063D03*
X1201852Y1547243D03*
X1206576D03*
X1211301D03*
X1203427Y1549970D03*
X1208151D03*
X1212875D03*
X1205001Y1566336D03*
X1209726D03*
X1214450D03*
X1203427Y1563608D03*
X1208151D03*
X1212875D03*
X1205001Y1552698D03*
X1209726D03*
X1214450D03*
X1201852Y1569063D03*
X1206576D03*
X1211301D03*
X1216025Y1547243D03*
X1220749D03*
X1225474D03*
X1230198D03*
X1222324Y1549970D03*
X1227049D03*
X1217600D03*
X1223899Y1566336D03*
X1228623D03*
X1219175D03*
X1222324Y1563608D03*
X1227049D03*
X1217600D03*
X1223899Y1552698D03*
X1228623D03*
X1219175D03*
X1216025Y1569063D03*
X1220749D03*
X1225474D03*
X1230198D03*
X1234923Y1547243D03*
X1239647D03*
X1244371D03*
X1231773Y1549970D03*
X1236497D03*
X1241222D03*
X1233348Y1566336D03*
X1238072D03*
X1242797D03*
X1231773Y1563608D03*
X1236497D03*
X1241222D03*
X1233348Y1552698D03*
X1238072D03*
X1242797D03*
X1234923Y1569063D03*
X1239647D03*
X1244371D03*
X1249096Y1547243D03*
X1253820D03*
X1258545D03*
X1245946Y1549970D03*
X1250671D03*
X1255395D03*
X1247521Y1566336D03*
X1252245D03*
X1256970D03*
X1245946Y1563608D03*
X1250671D03*
X1255395D03*
X1247521Y1552698D03*
X1252245D03*
X1256970D03*
X1249096Y1569063D03*
X1253820D03*
X1258545D03*
X1263269Y1547243D03*
X1260120Y1549970D03*
X1264844D03*
X1261694Y1566336D03*
X1266419D03*
X1260120Y1563608D03*
X1264844D03*
X1261694Y1552698D03*
X1266419D03*
X1263269Y1569063D03*
X1267994D03*
X1320465Y1547243D03*
X1325189D03*
X1329914D03*
X1322040Y1549970D03*
X1326764D03*
X1331489D03*
X1320465Y1560880D03*
X1323615Y1566336D03*
X1328339D03*
X1333063D03*
X1322040Y1563608D03*
X1326764D03*
X1331489D03*
X1323615Y1552698D03*
X1328339D03*
X1333063D03*
X1325189Y1569063D03*
X1329914D03*
X1334638Y1547243D03*
X1339363D03*
X1344087D03*
X1348811D03*
X1336213Y1549970D03*
X1340937D03*
X1345662D03*
X1337788Y1566336D03*
X1342512D03*
X1347237D03*
X1336213Y1563608D03*
X1340937D03*
X1345662D03*
X1337788Y1552698D03*
X1342512D03*
X1347237D03*
X1334638Y1569063D03*
X1339363D03*
X1344087D03*
X1348811D03*
X1353536Y1547243D03*
X1358260D03*
X1362985D03*
X1350386Y1549970D03*
X1355111D03*
X1359835D03*
X1351961Y1566336D03*
X1356685D03*
X1361410D03*
X1350386Y1563608D03*
X1355111D03*
X1359835D03*
X1351961Y1552698D03*
X1356685D03*
X1361410D03*
X1353536Y1569063D03*
X1358260D03*
X1362985D03*
X1367709Y1547243D03*
X1372433D03*
X1377158D03*
X1364559Y1549970D03*
X1369284D03*
X1374008D03*
X1378733D03*
X1366134Y1566336D03*
X1370859D03*
X1375583D03*
X1364559Y1563608D03*
X1369284D03*
X1374008D03*
X1378733D03*
X1366134Y1552698D03*
X1370859D03*
X1375583D03*
X1367709Y1569063D03*
X1372433D03*
X1377158D03*
X1391331Y1547243D03*
X1381882D03*
X1386607D03*
X1383457Y1549970D03*
X1388182D03*
X1392906D03*
X1380307Y1566336D03*
X1385032D03*
X1389756D03*
X1383457Y1563608D03*
X1388182D03*
X1392906D03*
X1380307Y1552698D03*
X1385032D03*
X1389756D03*
X1391331Y1569063D03*
X1381882D03*
X1386607D03*
X1394481Y1566336D03*
Y1552698D03*
X1396056Y1569063D03*
X1456577Y1547243D03*
X1461301D03*
X1466026D03*
X1458152Y1549970D03*
X1462876D03*
X1467601D03*
X1456577Y1560880D03*
X1459727Y1566336D03*
X1464451D03*
X1458152Y1563608D03*
X1462876D03*
X1467601D03*
X1459727Y1552698D03*
X1464451D03*
X1461301Y1569063D03*
X1466026D03*
X1470750Y1547243D03*
X1475475D03*
X1480199D03*
X1472325Y1549970D03*
X1477049D03*
X1481774D03*
X1469175Y1566336D03*
X1473900D03*
X1478624D03*
X1483349D03*
X1472325Y1563608D03*
X1477049D03*
X1481774D03*
X1469175Y1552698D03*
X1473900D03*
X1478624D03*
X1483349D03*
X1470750Y1569063D03*
X1475475D03*
X1480199D03*
X1484923Y1547243D03*
X1489648D03*
X1494372D03*
X1486498Y1549970D03*
X1491223D03*
X1495947D03*
X1488073Y1566336D03*
X1492797D03*
X1497522D03*
X1486498Y1563608D03*
X1491223D03*
X1495947D03*
X1488073Y1552698D03*
X1492797D03*
X1497522D03*
X1484923Y1569063D03*
X1489648D03*
X1494372D03*
X1499097Y1547243D03*
X1503821D03*
X1508545D03*
X1513270D03*
X1500671Y1549970D03*
X1505396D03*
X1510120D03*
X1502246Y1566336D03*
X1506971D03*
X1511695D03*
X1500671Y1563608D03*
X1505396D03*
X1510120D03*
X1502246Y1552698D03*
X1506971D03*
X1511695D03*
X1499097Y1569063D03*
X1503821D03*
X1508545D03*
X1513270D03*
X1527443Y1547243D03*
X1517994D03*
X1522719D03*
X1514845Y1549970D03*
X1519569D03*
X1524294D03*
X1516419Y1566336D03*
X1521144D03*
X1525868D03*
X1514845Y1563608D03*
X1519569D03*
X1524294D03*
X1516419Y1552698D03*
X1521144D03*
X1525868D03*
X1527443Y1569063D03*
X1517994D03*
X1522719D03*
X1529018Y1549970D03*
X1530593Y1566336D03*
X1529018Y1563608D03*
X1530593Y1552698D03*
X1532168Y1569063D03*
X1584639Y1547243D03*
X1586214Y1549970D03*
X1584639Y1560880D03*
X1587789Y1566336D03*
X1586214Y1563608D03*
X1587789Y1552698D03*
X1589363Y1547243D03*
X1594088D03*
X1598812D03*
X1590938Y1549970D03*
X1595663D03*
X1600387D03*
X1592513Y1566336D03*
X1597237D03*
X1601962D03*
X1590938Y1563608D03*
X1595663D03*
X1600387D03*
X1592513Y1552698D03*
X1597237D03*
X1601962D03*
X1589363Y1569063D03*
X1594088D03*
X1598812D03*
X1603537Y1547243D03*
X1608261D03*
X1612985D03*
X1617710D03*
X1614560Y1549970D03*
X1605111D03*
X1609836D03*
X1616135Y1566336D03*
X1606686D03*
X1611411D03*
X1614560Y1563608D03*
X1605111D03*
X1609836D03*
X1616135Y1552698D03*
X1606686D03*
X1611411D03*
X1603537Y1569063D03*
X1608261D03*
X1612985D03*
X1617710D03*
X1622434Y1547243D03*
X1627159D03*
X1631883D03*
X1619285Y1549970D03*
X1624009D03*
X1628733D03*
X1620859Y1566336D03*
X1625584D03*
X1630308D03*
X1619285Y1563608D03*
X1624009D03*
X1628733D03*
X1620859Y1552698D03*
X1625584D03*
X1630308D03*
X1622434Y1569063D03*
X1627159D03*
X1631883D03*
X1636607Y1547243D03*
X1641332D03*
X1646056D03*
X1633458Y1549970D03*
X1638182D03*
X1642907D03*
X1647631D03*
X1635033Y1566336D03*
X1639757D03*
X1644481D03*
X1633458Y1563608D03*
X1638182D03*
X1642907D03*
X1647631D03*
X1635033Y1552698D03*
X1639757D03*
X1644481D03*
X1636607Y1569063D03*
X1641332D03*
X1646056D03*
X1655505Y1547243D03*
X1650781D03*
X1652356Y1549970D03*
X1657080D03*
X1649206Y1566336D03*
X1653930D03*
X1658655D03*
X1652356Y1563608D03*
X1657080D03*
X1649206Y1552698D03*
X1653930D03*
X1658655D03*
X1655505Y1569063D03*
X1660230D03*
X1650781D03*
G54D202*
X509820Y129423D03*
Y160919D03*
X535016Y129423D03*
Y160919D03*
G54D10*
G01X50696Y1547444D02*
X49807D01*
X48324Y1545961D01*
G01X134902Y679290D02*
Y675290D01*
G01Y679290D02*
X131960D01*
G01X169441Y680799D02*
Y684799D01*
G01D02*
X172500D01*
G01X179575Y676500D02*
Y672500D01*
G01X182500D02*
X179575D01*
G01X316066Y66815D02*
X328016D01*
X329953Y68752D01*
Y93806D01*
X327953Y95806D01*
X320128D01*
X320174Y95852D01*
G01X649922Y545610D02*
X648746Y546786D01*
X560906D01*
X522563Y508443D01*
X437938D01*
X432481Y513900D01*
X380100D01*
X378200Y512000D01*
X344967D01*
X314780Y542187D01*
Y545716D01*
G01X363236Y1199632D02*
X360358Y1196754D01*
Y1184058D01*
X350643Y1174343D01*
X347107D01*
G01X367931Y1196981D02*
X365887D01*
X363236Y1199632D01*
G01X517009Y856494D02*
X514705D01*
X460710Y802499D01*
X377760D01*
X376671Y803588D01*
G01X370316Y1204673D02*
X370816Y1204173D01*
Y1198030D01*
X369767Y1196981D01*
X367931D01*
G01X376271Y1207488D02*
X372332D01*
X370316Y1205472D01*
Y1204673D01*
G01X392153Y216695D02*
X389705D01*
X384600Y221800D01*
G01X384824Y1655020D02*
Y1661545D01*
G01X399824Y1634154D02*
X400623Y1633355D01*
Y1629772D01*
G01X412771Y531063D02*
Y524820D01*
G01X568451Y1264943D02*
X568156Y1264648D01*
Y1263008D01*
X561189Y1256041D01*
X516617D01*
X443764Y1183188D01*
Y1179395D01*
G01X456128Y70016D02*
X462653D01*
G01X484754Y223377D02*
X487442D01*
G01X522088Y204285D02*
X515715D01*
X515410Y204590D01*
G01X504351Y213285D02*
Y215901D01*
G01X539503Y595341D02*
X538067Y593905D01*
Y592652D01*
G01X566460Y157494D02*
X563951D01*
G01X572297D02*
X566460D01*
G01X573911Y217771D02*
X571427D01*
G01X568451Y1264943D02*
X568840D01*
X570775Y1263008D01*
G01X586394Y93248D02*
Y95948D01*
G01X588500Y812093D02*
X589567D01*
X592572Y809088D01*
G01X595260Y157494D02*
X596980D01*
X598552Y159066D01*
G01X589423Y157494D02*
X595260D01*
G01X592572Y809088D02*
X593274Y809790D01*
X597972D01*
X600674Y807088D01*
Y805449D01*
X600672D01*
X597911Y802688D01*
G01X600337Y800649D02*
X598298Y802688D01*
X597911D01*
G01X609402Y788678D02*
Y789809D01*
X613261Y793668D01*
Y796288D01*
X608900Y800649D01*
X600337D01*
G01X596821Y802688D02*
X597911D01*
G01X615571Y788448D02*
X614121Y786998D01*
X611221D01*
X609541Y788678D01*
X609402D01*
G01X613948Y1641600D02*
Y1650254D01*
X626744Y1663050D01*
Y1671294D01*
X632056Y1676606D01*
X634892D01*
X637051Y1674447D01*
Y1671632D01*
X640178Y1668505D01*
X643074D01*
G01X685786Y680936D02*
X686095Y681245D01*
Y685280D01*
X667101Y704274D01*
Y736071D01*
G01X705660Y606060D02*
X711539D01*
X711907Y606428D01*
G01X698645Y621686D02*
X702645D01*
G01D02*
X706387D01*
G01X701661Y1395143D02*
X701689Y1395171D01*
Y1399545D01*
G01X720500Y553437D02*
Y555862D01*
G01Y543437D02*
Y546211D01*
G01X711907Y606428D02*
X715037D01*
G01X720787Y630756D02*
Y627907D01*
G01X716721Y630692D02*
Y627907D01*
G01X718129Y664242D02*
Y666725D01*
G01X722129Y664242D02*
Y666725D01*
G01X757125Y119172D02*
X760958D01*
X764534Y115596D01*
Y89688D01*
X761528Y86682D01*
X750240D01*
G01X756500Y543437D02*
Y545862D01*
G01X754030Y1651007D02*
Y1656008D01*
G01X806358Y455344D02*
X802752D01*
G01X841872Y535110D02*
X845094D01*
G01X864065Y515961D02*
X860658D01*
G01X876923Y1242345D02*
X874232D01*
X872101Y1240214D01*
Y1167654D01*
X888813Y1150942D01*
Y1145208D01*
X889368Y1144653D01*
G01X877059Y264232D02*
X889199D01*
X890844Y265877D01*
Y286155D01*
X883652Y293347D01*
X881018D01*
G01X901842Y936863D02*
X906479Y941500D01*
X919500D01*
G01X893368Y1144653D02*
X889368D01*
G01X916881Y570706D02*
X911747D01*
X910565Y571888D01*
Y578877D01*
X909747Y579695D01*
G01X929599Y570703D02*
Y576501D01*
X930406Y577308D01*
G01X919500Y941500D02*
Y937581D01*
X921958Y935123D01*
X928991D01*
X931865Y937997D01*
Y940865D01*
X932500Y941500D01*
G01X944520Y185052D02*
Y182094D01*
G01X940393Y1144653D02*
X936393D01*
G01Y1148087D02*
Y1144653D01*
G01X1081005Y1425458D02*
Y1395919D01*
X1078379Y1393293D01*
X1071631D01*
X1066363Y1388025D01*
G01X1071656Y369792D02*
Y366726D01*
G01X1110936Y1654416D02*
X1113490Y1651862D01*
G01X1110936Y1654416D02*
X1105000Y1660352D01*
Y1676425D01*
G01D02*
X1108675D01*
X1110000Y1675100D01*
G01X1120595Y1658967D02*
X1120303Y1659259D01*
Y1670114D01*
G01D02*
Y1676360D01*
G01D02*
X1116502D01*
X1115217Y1675075D01*
G01X1197381Y133866D02*
X1156378D01*
G01X1169017Y584622D02*
Y580662D01*
X1168957Y580602D01*
G01D02*
X1166131D01*
G01X1166026Y669006D02*
X1170608D01*
X1231397Y729795D01*
Y769667D01*
G01X1195862Y61515D02*
Y57115D01*
X1195962Y57015D01*
G01X1197381Y133866D02*
X1202181D01*
G01X1211531D02*
X1208431D01*
G01X1205331D02*
X1208431D01*
G01X1205331Y128748D02*
X1208431D01*
G01D02*
X1211531D01*
G01X1205900Y582443D02*
X1213896D01*
X1214339Y582886D01*
G01X1202687Y587443D02*
Y582443D01*
G01D02*
X1205900D01*
G01X1238094Y277848D02*
Y280573D01*
G01X1246094Y277848D02*
Y280573D01*
G01X1262310Y1428303D02*
X1266996Y1423617D01*
G01X1295000Y655200D02*
Y658552D01*
X1277677Y675875D01*
Y761913D01*
G01X1309600Y667700D02*
X1300677Y676623D01*
Y758913D01*
G01X1312506Y94027D02*
X1308291D01*
X1306449Y92185D01*
G01X1405811Y1430021D02*
X1445231Y1390601D01*
Y1290713D01*
X1434932Y1280414D01*
Y1261421D01*
X1404202Y1230691D01*
X1354052D01*
X1337847Y1214486D01*
Y1205361D01*
X1336679Y1202541D01*
Y1193676D01*
X1342507Y1187848D01*
G01X1355641Y1210674D02*
X1360240Y1215273D01*
X1401050D01*
X1446336Y1260559D01*
Y1276755D01*
X1511190Y1341609D01*
X1562937D01*
G01X1368109Y106559D02*
Y100509D01*
G01X1459896Y58413D02*
X1456820D01*
X1454820Y60413D01*
G01X1464830Y59054D02*
X1464189Y58413D01*
X1459896D01*
G01X1455579Y1640337D02*
Y1636114D01*
G01X1474177Y816872D02*
Y819933D01*
X1475592Y821348D01*
X1486304D01*
X1488227Y819425D01*
Y817074D01*
X1487923Y816770D01*
G01X1513644Y216400D02*
X1513749Y216505D01*
X1517708D01*
G01X1522094Y225250D02*
X1536407D01*
X1537450Y226293D01*
G01X1527392Y238017D02*
X1522094D01*
G01Y231250D02*
X1533160D01*
G01X1564202Y209250D02*
X1556359D01*
X1554360Y207251D01*
G01X1597481Y271991D02*
X1578477Y290995D01*
Y367340D01*
X1546149Y399668D01*
Y541169D01*
G01X1547099Y1266271D02*
Y1262351D01*
X1547062Y1262314D01*
G01D02*
X1547626Y1261750D01*
Y1259032D01*
X1547062Y1258468D01*
G01X1556178Y1265938D02*
X1560157D01*
G01X1564202Y254250D02*
X1572502D01*
G01X1571516Y319099D02*
Y308570D01*
X1566442Y303496D01*
Y301816D01*
G01X1599028Y225250D02*
X1602270Y228492D01*
Y229530D01*
G01X1590878Y229250D02*
X1591418Y229790D01*
X1596462D01*
G01X1600918Y521688D02*
X1612812Y509794D01*
X1668314D01*
X1681601Y523081D01*
Y578967D01*
X1686044Y589694D01*
Y648338D01*
X1699944Y662238D01*
X1709759D01*
G01X1673403Y199997D02*
X1637516Y164110D01*
X1631200D01*
G01X1642240Y396028D02*
Y399603D01*
G01X1654147Y618923D02*
Y616523D01*
G01X1667635Y210191D02*
X1664335D01*
G01X1684677Y1440258D02*
X1687347D01*
X1687357Y1440268D01*
G01X1709759Y662238D02*
Y666238D01*
G01D02*
Y670221D01*
G01X1742652Y668216D02*
X1745484D01*
G01X1742652Y664216D02*
X1744696D01*
X1745484Y665004D01*
Y668216D01*
G01X1792895Y683536D02*
X1774806D01*
X1759486Y668216D01*
X1745484D01*
G01X1748127Y1311598D02*
X1755287Y1304438D01*
X1760904D01*
X1762008Y1303981D01*
X1771571Y1294418D01*
X1786267D01*
X1799014Y1281671D01*
X1811526D01*
G01X1781911Y68352D02*
X1792095D01*
X1794086Y70343D01*
Y94319D01*
X1791478Y96927D01*
X1785253D01*
X3001Y61178D03*
Y127178D03*
Y149178D03*
Y171178D03*
Y193178D03*
Y215178D03*
Y237178D03*
Y259178D03*
Y281178D03*
Y303178D03*
X21569Y49379D03*
X11782Y167036D03*
X18691Y167208D03*
X22409Y230021D03*
X19684Y237154D03*
X17292Y290137D03*
X10875Y323721D03*
Y345721D03*
Y367721D03*
Y389721D03*
X21345Y387760D03*
X21309Y395712D03*
X10875Y411721D03*
Y433721D03*
Y455721D03*
Y477721D03*
Y499721D03*
Y521721D03*
X20587Y523970D03*
X16342Y516951D03*
X16512Y533155D03*
X10875Y543721D03*
Y565721D03*
Y587721D03*
Y609721D03*
Y653721D03*
Y675721D03*
Y697721D03*
Y719721D03*
Y741721D03*
Y763721D03*
Y785721D03*
Y807721D03*
Y829721D03*
Y851721D03*
Y873721D03*
Y895721D03*
Y917721D03*
Y939721D03*
Y961721D03*
Y983721D03*
Y1005721D03*
Y1027721D03*
Y1049721D03*
Y1071721D03*
Y1093721D03*
Y1115721D03*
Y1137721D03*
Y1159721D03*
Y1181721D03*
Y1203721D03*
Y1225721D03*
Y1247721D03*
Y1269721D03*
Y1291721D03*
Y1445721D03*
X19230Y1446459D03*
X10875Y1467721D03*
Y1489721D03*
Y1511721D03*
Y1533721D03*
Y1555721D03*
Y1577721D03*
X18960Y1598181D03*
X34281Y277798D03*
Y282916D03*
X35689Y301357D03*
Y298207D03*
X34281Y312916D03*
Y307798D03*
X36500Y323500D03*
X35740Y363337D03*
X33686Y383944D03*
X27309Y383926D03*
X39320Y392269D03*
X29962Y401000D03*
X36524Y398013D03*
X26771Y398811D03*
X30680Y438142D03*
X33184Y523285D03*
X28562Y517025D03*
X39967Y526709D03*
X36402Y528675D03*
X30562Y533055D03*
X33257Y540370D03*
X26887Y541805D03*
X35952Y551605D03*
X35852Y673010D03*
Y664480D03*
Y686410D03*
Y683910D03*
Y675510D03*
Y697322D03*
Y694822D03*
Y705728D03*
X35010Y1289485D03*
X35040Y1292433D03*
X35080Y1298360D03*
X35040Y1295380D03*
X34584Y1307744D03*
Y1310244D03*
Y1312744D03*
Y1315244D03*
X33822Y1462075D03*
Y1459075D03*
Y1456075D03*
X36822D03*
Y1459075D03*
Y1462075D03*
X33822Y1465075D03*
X36822D03*
X33822Y1477075D03*
Y1486075D03*
Y1483075D03*
Y1480075D03*
X27205Y1501630D03*
Y1498230D03*
X37671Y1515214D03*
X34704Y1515235D03*
X38058Y1591405D03*
X35133Y1603396D03*
X35167Y1610521D03*
Y1598896D03*
X28592Y1617961D03*
X35233Y1623196D03*
X35167Y1626896D03*
X28592Y1639961D03*
X35167Y1629405D03*
X28592Y1661961D03*
X32927Y1668587D03*
X28592Y1683961D03*
X43569Y49379D03*
X45423Y197224D03*
Y212224D03*
Y202224D03*
Y207224D03*
X44600Y280357D03*
X42449Y282916D03*
Y277798D03*
X47892Y290137D03*
X41492Y292892D03*
Y298207D03*
X47892Y295452D03*
X40500Y288500D03*
X55254Y292892D03*
X50500Y311100D03*
X42449Y312916D03*
Y307798D03*
X40000Y323500D03*
X55190Y360862D03*
X42809D03*
X46834D03*
X51114D03*
X39410Y384582D03*
X49400Y384392D03*
X43020Y382942D03*
X40940Y387302D03*
X39226Y395346D03*
X49250Y396332D03*
X41933Y395652D03*
X47618Y412613D03*
X53825Y421746D03*
X47619Y419084D03*
X47618Y415184D03*
X50138Y425810D03*
X45182D03*
X47619Y421655D03*
X49360Y428806D03*
X45960D03*
X45022Y449106D03*
X50002D03*
X49848Y524210D03*
X47812Y517635D03*
X49889Y531149D03*
X42810Y528070D03*
X48626Y552365D03*
X39952Y551605D03*
X55099Y1298676D03*
Y1292676D03*
X51000Y1339200D03*
X50880Y1412563D03*
Y1421963D03*
X42822Y1462075D03*
Y1459075D03*
Y1456075D03*
Y1465075D03*
Y1477075D03*
Y1483075D03*
Y1486075D03*
Y1480075D03*
X49265Y1490950D03*
Y1493450D03*
X49188Y1499181D03*
X41360Y1498971D03*
X41309Y1496173D03*
X38650Y1499326D03*
X49177Y1496272D03*
X47138Y1513072D03*
X47089Y1510268D03*
X52405Y1514835D03*
X49405D03*
X52405Y1511986D03*
X49405D03*
X52330Y1509137D03*
X49330D03*
X52796Y1526469D03*
X52905Y1523335D03*
X47760Y1529506D03*
X48383Y1532395D03*
X48157Y1536296D03*
X49196Y1551294D03*
X48324Y1545961D03*
X50642Y1557451D03*
X48758Y1559295D03*
X48907Y1554972D03*
X47735Y1584885D03*
X45633Y1592481D03*
X50133D03*
X47973Y1589981D03*
X43633Y1606896D03*
X46833Y1612596D03*
X43933Y1613818D03*
X47633Y1600896D03*
X47602Y1622414D03*
X53633Y1629896D03*
X41208Y1619896D03*
X51333Y1640996D03*
X42491Y1638656D03*
X40167Y1632405D03*
X51358Y1647717D03*
Y1650217D03*
X38426Y1654079D03*
X40922Y1654869D03*
X41427Y1668587D03*
X38426Y1659059D03*
X40922Y1658269D03*
X52052Y1684027D03*
X44583Y1672433D03*
Y1677613D03*
X45052Y1684283D03*
X41679Y1673323D03*
Y1676723D03*
X54584Y8335D03*
Y30335D03*
X65933Y28406D03*
Y48720D03*
X65347Y66847D03*
X60367D03*
X65347Y71839D03*
X60367D03*
X58457Y69340D03*
X67257D03*
X61157D03*
X64557D03*
X66650Y265316D03*
X62930Y282866D03*
X57271Y272357D03*
X59780Y282866D03*
X66289Y301357D03*
X67575Y287500D03*
X62567Y295103D03*
X66289Y298207D03*
X62930Y312866D03*
X56620Y303500D03*
X59780Y312866D03*
X59322Y360702D03*
X63429D03*
X67681D03*
X61340Y384362D03*
X61250Y396142D03*
X53406Y402862D03*
X62833Y409597D03*
X62808Y418675D03*
X62812Y412100D03*
X62813Y416000D03*
X65380Y427810D03*
X60393D03*
X64150Y434972D03*
X64821Y430806D03*
X60921D03*
X53800Y435451D03*
X54762Y444993D03*
X63540Y438802D03*
X56800Y524220D03*
X64442Y510667D03*
X55682Y517595D03*
X56719Y531120D03*
X62142Y539495D03*
X56192Y537795D03*
X63633Y528229D03*
X58365Y552365D03*
X53299D03*
X56542Y589521D03*
X56627Y585818D03*
X59259Y737422D03*
X58751Y777718D03*
X61251D03*
Y775218D03*
X58751D03*
X61620Y768510D03*
X56440Y766180D03*
X58751Y790218D03*
Y792718D03*
Y780218D03*
X61251D03*
X56057Y792750D03*
X61251Y792718D03*
Y790218D03*
X56057Y790250D03*
Y787750D03*
X61251Y787718D03*
X56057Y785250D03*
X61251Y785218D03*
Y782718D03*
X56057Y782750D03*
X58751Y782718D03*
Y785218D03*
Y787718D03*
X57752Y808020D03*
X60547Y1276036D03*
X57747Y1270470D03*
X55099Y1289676D03*
X55043Y1295676D03*
X53700Y1342300D03*
X58349Y1403331D03*
Y1412731D03*
X66822Y1462075D03*
Y1459075D03*
Y1456075D03*
X57822Y1462075D03*
Y1459075D03*
Y1456075D03*
X66822Y1465075D03*
X57822D03*
X67010Y1476292D03*
X57822Y1477075D03*
X57777Y1490580D03*
X66710Y1485324D03*
Y1482324D03*
X66785Y1479175D03*
X57822Y1482791D03*
Y1485294D03*
Y1480075D03*
X64030Y1491595D03*
X57770Y1488047D03*
X66696Y1488010D03*
X64030Y1499095D03*
Y1501595D03*
Y1494095D03*
Y1496595D03*
X55755Y1511885D03*
X55905Y1514835D03*
X55789Y1509224D03*
X67196Y1552869D03*
X55370Y1551351D03*
X66229Y1549536D03*
X61605Y1546833D03*
X64275Y1546296D03*
X63990Y1562177D03*
Y1567627D03*
Y1564727D03*
X63915Y1558805D03*
Y1556254D03*
X63802Y1579997D03*
X63990Y1570427D03*
X58602Y1579997D03*
X61302D03*
X61225Y1570283D03*
X58564Y1570209D03*
X57811Y1598061D03*
X58633Y1587481D03*
X63633D03*
X65767Y1609405D03*
X59767D03*
X53767D03*
X61110Y1598146D03*
X65767Y1615405D03*
X65943Y1621405D03*
X59767D03*
X53767Y1615405D03*
Y1621405D03*
X58633Y1629896D03*
X64133Y1627896D03*
X58633Y1641388D03*
X54449Y1641722D03*
X64633Y1632896D03*
X59427Y1644410D03*
X53648Y1653088D03*
X64427Y1643496D03*
X64462Y1655624D03*
X61927Y1643496D03*
X65257Y1652941D03*
X56815Y1643431D03*
X61415Y1661695D03*
X61374Y1669931D03*
X70127Y1687362D03*
X62202Y1684579D03*
X66127Y1687362D03*
X75928Y3001D03*
X81159Y17045D03*
X78265Y26477D03*
X74865D03*
X81970Y19541D03*
X72087Y25977D03*
X74087Y23981D03*
X79043D03*
X73015Y28406D03*
X81043Y25977D03*
X80101Y28406D03*
X79192Y19541D03*
X81159Y22037D03*
X73025Y37106D03*
X80111D03*
X73015Y40020D03*
X80101D03*
X73025Y48720D03*
X80111D03*
X69453Y75343D03*
X78253D03*
X82367Y71839D03*
X80457Y69340D03*
X82367Y66847D03*
X76347Y72850D03*
X71367D03*
X72153Y75343D03*
X75553D03*
X76347Y77842D03*
X71367D03*
X79726Y145191D03*
X82026Y143491D03*
X71659Y149191D03*
X71779Y157194D03*
Y161194D03*
Y165194D03*
X71775Y153194D03*
X72462Y268223D03*
X77680Y378395D03*
Y380895D03*
X68020Y395222D03*
X71772Y421746D03*
X68365Y443677D03*
X80948Y525513D03*
Y521613D03*
X77790Y520108D03*
X77733Y526764D03*
X77790Y537808D03*
X80318Y543313D03*
Y539413D03*
X77733Y544464D03*
X80915Y767400D03*
X80784Y771366D03*
X68354Y1314097D03*
X76378Y1406622D03*
X80378Y1406676D03*
X83441Y1430500D03*
X81052Y1427410D03*
X81132Y1424195D03*
X71511Y1444379D03*
X79055Y1434000D03*
X73820Y1442893D03*
X81401Y1436105D03*
X73820Y1445945D03*
X73757Y1448500D03*
X81822Y1462075D03*
Y1456075D03*
Y1465075D03*
Y1477075D03*
X77883Y1491440D03*
X80932D03*
X80852Y1488638D03*
X75245Y1491440D03*
X81822Y1480075D03*
Y1483075D03*
Y1486075D03*
X72396Y1491290D03*
X72390Y1499211D03*
X77883Y1499240D03*
X80833D03*
X77883Y1494040D03*
Y1496640D03*
X80932Y1494040D03*
Y1496640D03*
X75245Y1499240D03*
Y1494040D03*
Y1496640D03*
X72396Y1493890D03*
Y1496490D03*
X81868Y1511285D03*
X81405Y1516835D03*
X81905Y1513835D03*
X81405Y1519835D03*
Y1522835D03*
X78808Y1522839D03*
X81905Y1508698D03*
X82696Y1529095D03*
X77920Y1538245D03*
X75796Y1545669D03*
X75396Y1542369D03*
X78796Y1545669D03*
X78096Y1542444D03*
X78372Y1556416D03*
Y1558916D03*
X78522Y1562641D03*
Y1565141D03*
Y1567888D03*
X78403Y1580311D03*
X81103D03*
X78522Y1570388D03*
X81468Y1570285D03*
X76806Y1593265D03*
X68133Y1587896D03*
X81006Y1593265D03*
X72660Y1587365D03*
X80400Y1602225D03*
X72375Y1604365D03*
X74133Y1610896D03*
X70567Y1625603D03*
X72255Y1616730D03*
X74134Y1621396D03*
X75380Y1627622D03*
X75764Y1636993D03*
X79164Y1636992D03*
X68427Y1644410D03*
X73427D03*
X77427D03*
X69486Y1661828D03*
X69589Y1669878D03*
X78127Y1687362D03*
X74127D03*
X82127D03*
X82500Y1698511D03*
X80000Y1702450D03*
X82500Y1706511D03*
X82000Y1716331D03*
X79500Y1720450D03*
X82500Y1720331D03*
X82000Y1724331D03*
X86139Y17045D03*
X95333D03*
X85370Y19541D03*
X92438Y26477D03*
X89038D03*
X96143Y19541D03*
X88148D03*
X95216Y25977D03*
X86260D03*
X93216Y23981D03*
X94274Y28406D03*
X88260Y23981D03*
X87188Y28406D03*
X86139Y22037D03*
X95333D03*
X93365Y19541D03*
X94284Y37106D03*
X87198D03*
X87188Y40020D03*
X94274D03*
X87198Y48720D03*
X94284D03*
X87347Y71839D03*
Y66847D03*
X89257Y69340D03*
X91457Y75340D03*
X93367Y72847D03*
X94157Y75340D03*
X83157Y69340D03*
X97557Y75340D03*
X86557Y69340D03*
X93367Y77839D03*
X92197Y143853D03*
X87137Y143663D03*
X89150Y154494D03*
X93717Y159053D03*
X93775Y197241D03*
Y212241D03*
Y207241D03*
Y202241D03*
X87654Y376026D03*
X87520Y386502D03*
Y382219D03*
Y391391D03*
Y395865D03*
X90225Y610351D03*
X84057Y599372D03*
X84038Y602233D03*
X90225Y614351D03*
Y618351D03*
Y622351D03*
X94474Y766871D03*
X95790Y1278014D03*
X90150Y1314560D03*
X82953Y1307607D03*
X83023Y1311607D03*
X90501Y1338952D03*
X92791Y1341302D03*
X96191Y1337721D03*
X92941Y1346172D03*
X97546Y1385912D03*
X85736Y1391597D03*
X84000Y1408000D03*
Y1412500D03*
Y1417000D03*
X97530Y1410247D03*
X86827Y1404080D03*
X93000Y1417000D03*
Y1408000D03*
X93069Y1412500D03*
X85103Y1433051D03*
X93000Y1430500D03*
X84000Y1421500D03*
Y1426000D03*
X93000D03*
X97800Y1433000D03*
X93000Y1421500D03*
Y1435500D03*
Y1440000D03*
X84500D03*
X93000Y1444500D03*
Y1448500D03*
X84500Y1444500D03*
Y1448500D03*
X88722Y1462075D03*
X85722D03*
X88722Y1456075D03*
X85722D03*
X88722Y1465075D03*
X85722D03*
X88722Y1476741D03*
X89092Y1491106D03*
X89042Y1488506D03*
X83991Y1491440D03*
X83892Y1488840D03*
X88722Y1479741D03*
Y1482741D03*
Y1485741D03*
X83892Y1499140D03*
X83991Y1494040D03*
Y1496540D03*
X84051Y1501690D03*
X85368Y1511285D03*
X85405Y1513835D03*
X88868Y1511285D03*
X88905Y1513835D03*
X85405Y1508698D03*
X88905D03*
X88696Y1526769D03*
Y1523769D03*
X83796Y1533746D03*
X83811Y1537296D03*
X85621Y1551969D03*
X82974Y1552051D03*
X91511Y1552296D03*
X93296Y1549142D03*
X97018Y1546331D03*
X88511Y1552296D03*
X83121Y1542294D03*
X94786Y1574205D03*
Y1576705D03*
X97486Y1574205D03*
Y1576705D03*
X83603Y1580311D03*
X84093Y1570285D03*
X90675Y1590783D03*
X96124Y1593458D03*
Y1595958D03*
X93424Y1593458D03*
X90675Y1593283D03*
X93424Y1595958D03*
X90675Y1595783D03*
X93537Y1598506D03*
X96237D03*
X90649Y1598507D03*
X84833Y1611896D03*
X85133Y1616396D03*
Y1620896D03*
Y1625396D03*
X85167Y1629905D03*
X90892Y1654749D03*
X83340Y1654353D03*
X85836Y1655143D03*
X89466Y1663138D03*
Y1667127D03*
X83340Y1659333D03*
X85395Y1670331D03*
X85836Y1658543D03*
X87891Y1671121D03*
X85395Y1675311D03*
X87891Y1674521D03*
X86127Y1687362D03*
X90127D03*
X96101Y1696469D03*
X92192Y1713741D03*
X93029Y1705225D03*
X82945Y1702511D03*
X95342Y1713741D03*
X96555Y1705508D03*
X97683Y1722477D03*
X95400Y1719741D03*
X95460Y1725241D03*
X92596Y1737117D03*
X97928Y3001D03*
X100313Y17045D03*
X109506D03*
X99543Y19541D03*
X106611Y26477D03*
X103211D03*
X110316Y19541D03*
X109389Y25977D03*
X100433D03*
X107389Y23981D03*
X108448Y28406D03*
X102433Y23981D03*
X101361Y28406D03*
X100313Y22037D03*
X102321Y19541D03*
X109506Y22037D03*
X107538Y19541D03*
X108458Y37106D03*
X101371D03*
X101361Y40020D03*
X108448D03*
X101371Y48720D03*
X108458D03*
X98347Y72847D03*
X100257Y75340D03*
X104367Y71839D03*
X109347D03*
X102457Y69340D03*
X104367Y66847D03*
X109347D03*
X111257Y69340D03*
X105157D03*
X108557D03*
X98347Y77839D03*
X104829Y151191D03*
X101679D03*
X107931Y158767D03*
X99754Y155807D03*
X101675Y160694D03*
X100818Y168906D03*
X110616Y767400D03*
X110485Y771366D03*
X105165Y1300380D03*
Y1302880D03*
X107665D03*
Y1300380D03*
X102665Y1302880D03*
Y1300380D03*
X105165Y1305380D03*
X107665D03*
X102665D03*
Y1307880D03*
Y1310380D03*
Y1312880D03*
X105165Y1307880D03*
Y1310380D03*
Y1312880D03*
X107665D03*
Y1310380D03*
Y1307880D03*
X105165Y1315380D03*
X107665D03*
X105165Y1317880D03*
X107665D03*
X102665D03*
Y1315380D03*
X99211Y1337771D03*
X98101Y1369018D03*
Y1371559D03*
X111630Y1385287D03*
X101995Y1388247D03*
X104863Y1382593D03*
X99594Y1379933D03*
X104863Y1380085D03*
X112305Y1382130D03*
X108817Y1380530D03*
X111555Y1379562D03*
X101874Y1376408D03*
X111600Y1403100D03*
X110000Y1407425D03*
X110075Y1410500D03*
X112355Y1426064D03*
Y1433564D03*
X101637Y1432938D03*
X102076Y1427833D03*
X112355Y1441064D03*
X101955Y1448660D03*
X101500Y1436000D03*
X102398Y1440000D03*
X113500Y1455600D03*
X112481Y1452424D03*
X112100Y1467500D03*
X103571Y1476485D03*
X103555Y1485128D03*
Y1479128D03*
Y1482128D03*
X109733Y1491367D03*
X110605Y1487896D03*
X104184Y1491292D03*
X106784D03*
X105453Y1487893D03*
X108053D03*
X102931Y1488097D03*
X101584Y1491292D03*
X106396Y1485113D03*
X108996D03*
X106371Y1482181D03*
X108971D03*
X107197Y1501756D03*
X109712Y1499196D03*
X104616Y1501811D03*
X107112Y1499196D03*
X109733Y1493967D03*
Y1496567D03*
X106784Y1493892D03*
Y1496492D03*
X101634D03*
X104512Y1499196D03*
X104184Y1496492D03*
Y1493892D03*
X101534Y1499244D03*
X101634Y1493992D03*
X101835Y1501863D03*
X109878Y1501879D03*
X101396Y1552769D03*
X102011Y1550242D03*
X99818Y1546296D03*
X111196Y1542569D03*
X111901Y1545543D03*
X102096Y1555442D03*
X112418Y1555680D03*
X112339Y1565015D03*
Y1562515D03*
X112418Y1558180D03*
X99986Y1574205D03*
Y1576705D03*
X108555Y1574657D03*
Y1577462D03*
X110144Y1597831D03*
X110996Y1592018D03*
X98824Y1593558D03*
X101524D03*
X98824Y1596058D03*
X101524D03*
X101637Y1598606D03*
X98937D03*
X112353Y1646612D03*
X100439Y1667361D03*
X106573Y1660235D03*
X101939Y1657742D03*
Y1662728D03*
X112473Y1660235D03*
X109073D03*
X110378Y1670313D03*
X99443Y1661931D03*
Y1658531D03*
X100915Y1679564D03*
X105069Y1685763D03*
X102243Y1682263D03*
X107569Y1685763D03*
X110969D03*
X110378Y1674313D03*
X100443Y1684063D03*
X106448Y1696436D03*
X102243Y1689263D03*
X100443Y1687463D03*
X107500Y1707450D03*
X119928Y3001D03*
X114486Y17045D03*
X123683D03*
X113716Y19541D03*
X120785Y26477D03*
X117385D03*
X124490Y19541D03*
X123563Y25977D03*
X114607D03*
X122621Y28406D03*
X116607Y23981D03*
X121563D03*
X115534Y28406D03*
X114486Y22037D03*
X116494Y19541D03*
X121712D03*
X123683Y22037D03*
X122631Y37106D03*
X115544D03*
X115534Y40020D03*
X122621D03*
X115544Y48720D03*
X122631D03*
X113457Y75340D03*
X115367Y72847D03*
X120347D03*
X122257Y75340D03*
X126367Y71842D03*
X124457Y69343D03*
X126367Y66850D03*
X116157Y75340D03*
X127153Y69343D03*
X119557Y75340D03*
X115367Y77839D03*
X120347D03*
X120016Y300654D03*
X115016Y300281D03*
X120016Y320631D03*
X115016Y320715D03*
X120891Y521216D03*
X118407Y526766D03*
X113042Y686285D03*
X113980Y717480D03*
X116480D03*
X118980D03*
X121480D03*
X123980D03*
X113980Y714980D03*
X116480D03*
X118980D03*
X121480D03*
X123980D03*
X116480Y722480D03*
X118980D03*
X121480D03*
X123980D03*
X113980Y719980D03*
X116480D03*
X118980D03*
X121480D03*
X123980D03*
X113980Y722480D03*
X124174Y766871D03*
X120965Y1307880D03*
Y1310380D03*
Y1312880D03*
X118465D03*
Y1310380D03*
Y1307880D03*
Y1300380D03*
X123465Y1302880D03*
Y1300380D03*
X120965Y1305380D03*
X118465D03*
X123465D03*
Y1307880D03*
Y1310380D03*
Y1312880D03*
X120965Y1300380D03*
Y1302880D03*
X118465D03*
X120965Y1315380D03*
X118465D03*
X120965Y1317880D03*
X118465D03*
X123465D03*
Y1315380D03*
X124071Y1337843D03*
X126671D03*
X126491Y1354871D03*
X125241Y1357371D03*
X126491Y1352271D03*
X123891Y1354871D03*
Y1352271D03*
X126491Y1349671D03*
X123891D03*
X121241Y1367047D03*
Y1369947D03*
X127211Y1373177D03*
Y1378977D03*
X125111Y1377577D03*
X122945Y1379207D03*
X127211Y1376077D03*
X125011Y1374577D03*
X122945Y1376307D03*
X122050Y1403750D03*
X129200Y1401000D03*
X126000Y1414000D03*
Y1418000D03*
X116700Y1415700D03*
Y1410500D03*
X119855Y1426064D03*
X127355Y1433564D03*
Y1426064D03*
X119855Y1441064D03*
X127355D03*
X116900Y1449000D03*
X113600Y1449100D03*
X116122Y1458000D03*
X119100Y1460300D03*
X124600Y1465100D03*
X114405Y1516335D03*
Y1512835D03*
Y1519835D03*
Y1522835D03*
X116905D03*
Y1519835D03*
Y1512835D03*
Y1516335D03*
Y1509335D03*
Y1526335D03*
X113100Y1537346D03*
X114030Y1542419D03*
X114610Y1545543D03*
X127374Y1572749D03*
X127392Y1575524D03*
X125768Y1568744D03*
X127246Y1585801D03*
X127264Y1588576D03*
X113496Y1592018D03*
X121705Y1619460D03*
X114618Y1624541D03*
X117655Y1621766D03*
X118956Y1635244D03*
X124312Y1633488D03*
X126717Y1635893D03*
X116353Y1646612D03*
X120353D03*
X124353D03*
X123278Y1658587D03*
X114973Y1660235D03*
X126428Y1658587D03*
X113469Y1685763D03*
X126760Y1682383D03*
X119353Y1695941D03*
X115353D03*
X123353D03*
X127353Y1696062D03*
X127710Y1700166D03*
X120052Y1712450D03*
X125107Y1702666D03*
X127290Y1705666D03*
X125183Y1716741D03*
X124461Y1726116D03*
X127168Y1721695D03*
X129020Y1726741D03*
X114596Y1737117D03*
X141928Y3001D03*
X128663Y17045D03*
X127890Y19541D03*
X129708Y28406D03*
X130668Y19541D03*
X128663Y22037D03*
X129718Y37106D03*
X129708Y40020D03*
X129718Y48720D03*
X135457Y75340D03*
X137367Y72847D03*
X142347D03*
X133257Y69343D03*
X131347Y71842D03*
Y66850D03*
X138157Y75340D03*
X141557D03*
X130553Y69343D03*
X137367Y77839D03*
X142347D03*
X128367Y202241D03*
Y207241D03*
Y197241D03*
Y212241D03*
X140360Y430160D03*
X139440Y439000D03*
X138090Y441900D03*
X140800Y441920D03*
X141642Y491434D03*
Y488684D03*
Y494147D03*
X139980Y507420D03*
X139890Y503440D03*
X134812Y530955D03*
X140471Y670445D03*
X131861Y664958D03*
X131752Y668506D03*
X134902D03*
X140600Y683029D03*
X139869Y686582D03*
X131752Y686074D03*
X134902D03*
X131960Y679290D03*
X140317Y767400D03*
Y771200D03*
X140265Y1307880D03*
Y1310380D03*
Y1312880D03*
X137765D03*
Y1310380D03*
Y1307880D03*
X135265Y1312880D03*
Y1310380D03*
Y1307880D03*
Y1305380D03*
X140265D03*
X137765D03*
X135265Y1300380D03*
Y1302880D03*
X140265Y1300380D03*
Y1302880D03*
X137765D03*
Y1300380D03*
X140265Y1315380D03*
X137765D03*
X135265D03*
Y1317880D03*
X140265D03*
X137765D03*
X137551Y1337771D03*
X131791Y1337811D03*
X130701Y1369018D03*
Y1371559D03*
X130492Y1384789D03*
X132150Y1386740D03*
X137463Y1382593D03*
X132194Y1379933D03*
X137463Y1380085D03*
X141417Y1380530D03*
X134474Y1376408D03*
X138000Y1400600D03*
X134800Y1408100D03*
X142000Y1414500D03*
X136000Y1432000D03*
X141500Y1433500D03*
Y1429500D03*
X139500Y1446000D03*
X133100Y1444100D03*
X138013Y1440487D03*
X133120Y1454751D03*
X137120D03*
X141028Y1454705D03*
X128661Y1464000D03*
X128617Y1561022D03*
X139802Y1556133D03*
X129892Y1575524D03*
X129874Y1572749D03*
X128268Y1568744D03*
X129764Y1588576D03*
X129746Y1585801D03*
X129070Y1608338D03*
X137386Y1626412D03*
X135543Y1637055D03*
X128353Y1646612D03*
X140353D03*
X132353D03*
X136353D03*
X136048Y1666851D03*
X142465Y1662493D03*
X133548Y1677351D03*
X131353Y1696062D03*
X135353D03*
X139353D03*
X143000Y1701011D03*
X132643Y1711846D03*
X142293Y1705166D03*
X129493Y1711846D03*
X143000Y1709166D03*
X135722Y1715672D03*
X130000Y1719450D03*
X136596Y1737117D03*
X156651Y26477D03*
X153251D03*
X150473Y25977D03*
X157429Y23981D03*
X152473D03*
X151400Y28406D03*
X147920Y28261D03*
X151410Y37106D03*
X151400Y40020D03*
X151410Y48720D03*
X148780D03*
X144257Y75340D03*
X153347Y71842D03*
X148367D03*
X153347Y66850D03*
X148367D03*
X155253Y69343D03*
X146453D03*
X149153D03*
X152553D03*
X149231Y224204D03*
X148228Y216118D03*
X150318Y233536D03*
X158380Y419760D03*
X144610Y429560D03*
X147450Y423860D03*
X142660Y438930D03*
X143720Y441960D03*
X145960Y438800D03*
X146930Y441870D03*
X149210Y438640D03*
X149830Y441920D03*
X154770Y441830D03*
X147810Y475710D03*
X146982Y521997D03*
Y526997D03*
Y530997D03*
X149672Y665500D03*
X159513Y674855D03*
X152822Y665500D03*
X152705Y683218D03*
X153875Y766871D03*
X151065Y1307880D03*
Y1310380D03*
Y1312880D03*
X153565D03*
Y1310380D03*
Y1307880D03*
X156065Y1312880D03*
Y1310380D03*
Y1307880D03*
Y1305380D03*
X151065D03*
X153565D03*
X156065Y1300380D03*
Y1302880D03*
X151065Y1300380D03*
Y1302880D03*
X153565D03*
Y1300380D03*
X151065Y1315380D03*
X153565D03*
X156065D03*
Y1317880D03*
X151065D03*
X153565D03*
X156491Y1354871D03*
Y1352271D03*
Y1349671D03*
X153741Y1369977D03*
Y1367077D03*
X144230Y1385287D03*
X144905Y1382130D03*
X144155Y1379562D03*
X155545Y1379207D03*
Y1376307D03*
X145000Y1414425D03*
X150900Y1433500D03*
Y1429500D03*
Y1425500D03*
X143478Y1440000D03*
X151082Y1436653D03*
X146978Y1440000D03*
X154443Y1441195D03*
X156174Y1435396D03*
X156477Y1447733D03*
X154083Y1456007D03*
X145028Y1454705D03*
X148340Y1454674D03*
X154671Y1450019D03*
X154305Y1453101D03*
X159000Y1525480D03*
X155618Y1549331D03*
X155071Y1543604D03*
X152843Y1559146D03*
Y1562666D03*
X146453Y1614879D03*
X149171Y1616759D03*
X148353Y1646612D03*
X144353D03*
X152353D03*
X155328Y1670087D03*
X151611Y1663933D03*
X154111D03*
X146928Y1685087D03*
X159427Y1687843D03*
X151510Y1676811D03*
X154010D03*
X157410D03*
X143778Y1685087D03*
X143353Y1696062D03*
X147253Y1696343D03*
X155353Y1687843D03*
X159427Y1696652D03*
X152605Y1715941D03*
X147277Y1712791D03*
X152815Y1705500D03*
X149338Y1705603D03*
X156825Y1705510D03*
X146000Y1718241D03*
X146086Y1705603D03*
X155740Y1729726D03*
X145267Y1722241D03*
X152496Y1722941D03*
X146483Y1725636D03*
X155260Y1723682D03*
X163928Y3001D03*
X164525Y17045D03*
X159545D03*
X170824Y26477D03*
X163756Y19541D03*
X167424Y26477D03*
X160356Y19541D03*
X159429Y25977D03*
X158487Y28406D03*
X164646Y25977D03*
X171602Y23981D03*
X166646D03*
X165574Y28406D03*
X157578Y19541D03*
X166534D03*
X171751D03*
X164525Y22037D03*
X159545D03*
X158497Y37106D03*
X165584D03*
X158487Y40020D03*
X165574D03*
X158497Y48720D03*
X165584D03*
X158661Y75340D03*
X160571Y72847D03*
X165551D03*
X167461Y75340D03*
X171571Y71839D03*
X169661Y69340D03*
X171571Y66847D03*
X161361Y75340D03*
X164761D03*
X160571Y77839D03*
X165551D03*
X162830Y396930D03*
X172120Y416600D03*
X168950Y412950D03*
X168910Y415930D03*
X172120Y412350D03*
X170500Y441420D03*
X167580Y441380D03*
X164870Y441360D03*
X169440Y438390D03*
X166220Y438460D03*
X172010Y474900D03*
X166760Y506880D03*
X166670Y502900D03*
X163372Y670863D03*
X172725Y667898D03*
X162482Y679319D03*
X161735Y684456D03*
X172725Y679230D03*
X169987Y767666D03*
Y771266D03*
X170265Y1312880D03*
Y1310380D03*
Y1307880D03*
X167765Y1312880D03*
Y1310380D03*
Y1307880D03*
Y1305380D03*
X170265D03*
X167765Y1300380D03*
Y1302880D03*
X170265D03*
Y1300380D03*
Y1315380D03*
X167765D03*
Y1317880D03*
X170265D03*
X171481Y1337853D03*
X164481Y1337813D03*
X161881D03*
X159091Y1354871D03*
X157841Y1357371D03*
X159091Y1352271D03*
Y1349671D03*
X163401Y1369018D03*
Y1371559D03*
X159811Y1373177D03*
X163192Y1384789D03*
X164850Y1386740D03*
X170163Y1382593D03*
X164894Y1379933D03*
X170163Y1380085D03*
X167174Y1376408D03*
X159811Y1378977D03*
Y1376077D03*
X157711Y1377577D03*
X157611Y1374577D03*
X163099Y1414400D03*
X162873Y1411611D03*
X163061Y1409048D03*
Y1406548D03*
X163421Y1425171D03*
Y1427671D03*
Y1430171D03*
Y1432671D03*
X160684Y1441046D03*
X158704Y1439411D03*
X161210Y1443542D03*
X163271Y1441588D03*
X168661Y1459995D03*
X166751Y1462595D03*
X169351D03*
X168661Y1465195D03*
X163113Y1477590D03*
X163148Y1474504D03*
X163113Y1486190D03*
X160513Y1479500D03*
Y1484280D03*
X165713Y1479500D03*
Y1484280D03*
X163113Y1483590D03*
Y1480190D03*
X172180Y1490210D03*
X172070Y1495550D03*
X163460Y1491010D03*
X163113Y1499490D03*
X160513Y1501300D03*
Y1506080D03*
X165713D03*
X163113Y1507982D03*
X165713Y1501300D03*
X163113Y1501990D03*
Y1505390D03*
X163320Y1494340D03*
X164730Y1521561D03*
X161188Y1510800D03*
X162188Y1518040D03*
X164650Y1529350D03*
X162531Y1523331D03*
Y1526731D03*
X164650Y1540250D03*
X167666Y1550751D03*
X165166D03*
X162666D03*
X170166D03*
X170230Y1542960D03*
X160150Y1553251D03*
Y1555751D03*
X162666D03*
X165166D03*
X167666D03*
X170166D03*
Y1553251D03*
X167666D03*
X165166D03*
X162666D03*
X170166Y1567621D03*
X167666D03*
X165166D03*
X162666D03*
X170166Y1565121D03*
X167666D03*
X165166D03*
X162666D03*
Y1562621D03*
X165166D03*
X167666D03*
X170166D03*
X162466Y1570121D03*
X164966D03*
X167466D03*
X169966D03*
X162995Y1661377D03*
X160011Y1663933D03*
X163003Y1666462D03*
X157511Y1663933D03*
X165491Y1665582D03*
Y1662182D03*
X159910Y1676811D03*
X162848Y1679357D03*
X162840Y1674272D03*
X165336Y1675077D03*
Y1678477D03*
X162740Y1713172D03*
Y1704885D03*
X171925Y1708428D03*
X167500Y1712864D03*
X171925Y1727581D03*
X157860Y1718500D03*
X166467Y1720973D03*
X171925Y1717984D03*
X171945Y1730693D03*
X162740Y1723886D03*
X158596Y1737117D03*
X185928Y3001D03*
X173719Y17045D03*
X178699D03*
X177929Y19541D03*
X174529D03*
X173602Y25977D03*
X172660Y28406D03*
X179747D03*
X173719Y22037D03*
X178699D03*
X180707Y19541D03*
X172670Y37106D03*
X179757D03*
X172660Y40020D03*
X179747D03*
X172670Y48720D03*
X179757D03*
X176551Y71839D03*
Y66847D03*
X178461Y69340D03*
X180657Y75343D03*
X182571Y72850D03*
X183357Y75343D03*
X172361Y69340D03*
X186757Y75343D03*
X175761Y69340D03*
X182571Y77842D03*
X187250Y129674D03*
X184930Y125502D03*
X182548Y147260D03*
X181025Y159123D03*
X183890Y388180D03*
X173960Y400560D03*
X174320Y395040D03*
X189290Y396730D03*
X177675Y419260D03*
X185160Y419220D03*
X176610Y441380D03*
X175990Y438100D03*
X173710Y441330D03*
X172740Y438260D03*
X181550Y441290D03*
X173299Y664958D03*
X182500Y672500D03*
X172802Y682036D03*
X172500Y684799D03*
X183576Y766871D03*
X183565Y1310380D03*
Y1312880D03*
X186065D03*
Y1310380D03*
Y1307880D03*
X172765D03*
Y1310380D03*
Y1312880D03*
X183565Y1307880D03*
Y1305380D03*
X186065D03*
X183565Y1300380D03*
Y1302880D03*
X186065D03*
Y1300380D03*
X172765Y1305380D03*
Y1300380D03*
Y1302880D03*
Y1315380D03*
X183565D03*
X186065D03*
X183565Y1317880D03*
X186065D03*
X172765D03*
X185701Y1337853D03*
X183101D03*
X174081D03*
X186481Y1370147D03*
Y1367247D03*
X176930Y1385287D03*
X177605Y1382130D03*
X174117Y1380530D03*
X176855Y1379562D03*
X185558Y1418560D03*
Y1416060D03*
X183058Y1418560D03*
Y1416060D03*
X173164Y1406397D03*
Y1408897D03*
X172976Y1411460D03*
X173202Y1414249D03*
X172721Y1425171D03*
Y1430171D03*
Y1427671D03*
Y1432671D03*
X185558Y1421060D03*
Y1423560D03*
Y1426060D03*
X183058Y1421060D03*
Y1426060D03*
Y1423560D03*
Y1428560D03*
X185558D03*
X173441Y1459995D03*
X175351Y1462595D03*
X182051Y1452895D03*
X173451D03*
X180141Y1450295D03*
X175361D03*
X180141Y1455495D03*
X175361D03*
X172751Y1462595D03*
X179451Y1452895D03*
X176051D03*
X173441Y1465195D03*
X186851Y1472295D03*
X177322Y1498320D03*
X173488Y1510800D03*
Y1514420D03*
Y1518040D03*
X173980Y1528731D03*
X173490Y1542540D03*
X173050Y1555751D03*
Y1553251D03*
X178582Y1575390D03*
X181087Y1576135D03*
X178582Y1572490D03*
Y1569590D03*
X180292Y1582589D03*
X177792D03*
X177509Y1653825D03*
X177666Y1649223D03*
X183974Y1656804D03*
X183920Y1653973D03*
X184139Y1651088D03*
X180103Y1668921D03*
X177672Y1657538D03*
X183986Y1659548D03*
X182533Y1676854D03*
X185254Y1686870D03*
X179999Y1699156D03*
X185173Y1695138D03*
X179444Y1708810D03*
X184340Y1718000D03*
X178385Y1715441D03*
X183813Y1705404D03*
X178376Y1720559D03*
X181760Y1731351D03*
X185760Y1731666D03*
X180596Y1737117D03*
X200785Y26477D03*
X197385D03*
X194607Y25977D03*
X196607Y23981D03*
X201563D03*
X195534Y28406D03*
X201712Y19541D03*
X195544Y37106D03*
X195534Y40020D03*
X195544Y48720D03*
X189457Y75343D03*
X193571Y71839D03*
X198551D03*
X191661Y69340D03*
X193571Y66847D03*
X198551D03*
X200461Y69340D03*
X187656Y72850D03*
X194361Y69340D03*
X197761D03*
X187656Y77842D03*
X195979Y109462D03*
X203061Y131158D03*
X200577Y125502D03*
X190000Y143000D03*
X191264Y147768D03*
X193610Y153951D03*
X192592Y353072D03*
X189410Y388180D03*
X195690Y415390D03*
X195730Y412410D03*
X200754Y595174D03*
Y603274D03*
X200405Y622385D03*
Y632385D03*
X188055Y731734D03*
X199718Y767400D03*
X197651Y769241D03*
X200365Y1312880D03*
Y1310380D03*
Y1307880D03*
Y1305380D03*
Y1300380D03*
Y1302880D03*
X188565Y1312880D03*
Y1310380D03*
Y1307880D03*
Y1305380D03*
Y1300380D03*
Y1302880D03*
X200365Y1315380D03*
Y1317880D03*
X188565Y1315380D03*
Y1317880D03*
X195771Y1337903D03*
X193171D03*
X190541Y1357371D03*
X189191Y1354871D03*
Y1352271D03*
X191791Y1354871D03*
Y1352271D03*
X189191Y1349671D03*
X191791D03*
X196301Y1369018D03*
Y1371559D03*
X192511Y1373177D03*
X196092Y1384789D03*
X197750Y1386740D03*
X197794Y1379933D03*
X200074Y1376408D03*
X188245Y1379207D03*
X190411Y1377577D03*
X192511Y1378977D03*
X190311Y1374577D03*
X188245Y1376307D03*
X192511Y1376077D03*
X200408Y1416249D03*
Y1418749D03*
X192983Y1417568D03*
X188058Y1416060D03*
Y1418560D03*
X190483Y1417568D03*
X197983D03*
X195483D03*
X188695Y1404813D03*
Y1407313D03*
X191995Y1404813D03*
Y1407313D03*
X194495Y1404813D03*
Y1407313D03*
X196995Y1404813D03*
Y1407313D03*
X199495Y1404813D03*
Y1407313D03*
X188507Y1409876D03*
X191807D03*
X194307D03*
X196807D03*
X199307D03*
X200558Y1421551D03*
X195483Y1420068D03*
X192983D03*
X195483Y1422568D03*
X197983D03*
X192983D03*
X188058Y1421060D03*
Y1423560D03*
X190483Y1420068D03*
Y1422568D03*
X197983Y1420068D03*
X188058Y1426060D03*
X202151Y1462595D03*
X193551D03*
X200241Y1459995D03*
X195461D03*
X202161Y1450295D03*
X200251Y1452895D03*
X202161Y1455495D03*
X199551Y1462595D03*
X196151D03*
X195451Y1472295D03*
X193541Y1469695D03*
X188761D03*
X193541Y1474895D03*
X188761D03*
X200241Y1465195D03*
X195461D03*
X192851Y1472295D03*
X189451D03*
X192951Y1560498D03*
X196081Y1639349D03*
X200848Y1655656D03*
X190242Y1656635D03*
X195504Y1645359D03*
X201120Y1668603D03*
X199040Y1666925D03*
X196366Y1664821D03*
X190271Y1671753D03*
X199747Y1675603D03*
X195153Y1679774D03*
X200424Y1686870D03*
X190391Y1701988D03*
X195300Y1694898D03*
X197780Y1696973D03*
X200478Y1701758D03*
X200448Y1690771D03*
X202076Y1717845D03*
X194000Y1712362D03*
X201531Y1715000D03*
X192745Y1707106D03*
X199547Y1704605D03*
X189760Y1713061D03*
X193274Y1709769D03*
X199843Y1709837D03*
X203510Y1712441D03*
X196763Y1710444D03*
X189760Y1723041D03*
Y1731564D03*
X195150Y1723000D03*
X194000Y1720551D03*
X203655Y1723000D03*
X198760Y1719991D03*
X207928Y3001D03*
X208659Y17045D03*
X203679D03*
X207890Y19541D03*
X214958Y26477D03*
X204490Y19541D03*
X211558Y26477D03*
X208780Y25977D03*
X203563D03*
X202621Y28406D03*
X210780Y23981D03*
X215736D03*
X216794Y28406D03*
X209708D03*
X210668Y19541D03*
X215885D03*
X208659Y22037D03*
X203679D03*
X202631Y37106D03*
X216804D03*
X209718D03*
X202621Y40020D03*
X209708D03*
X216794D03*
X202631Y48720D03*
X209718D03*
X216804D03*
X202795Y75340D03*
X204705Y72847D03*
X209685D03*
X211595Y75340D03*
X213791Y69343D03*
X215705Y66850D03*
Y71842D03*
X216491Y69343D03*
X205495Y75340D03*
X208895D03*
X204705Y77839D03*
X209685D03*
X214107Y113022D03*
X205489Y142790D03*
X206760Y148760D03*
X217687Y522453D03*
X203754Y595174D03*
X214999Y585668D03*
X211254Y595145D03*
X208254D03*
X203754Y603274D03*
X211009Y610001D03*
X208009D03*
X214202Y606943D03*
X208254Y603245D03*
X211254D03*
X214202Y609681D03*
X208326Y606918D03*
X211326D03*
X206805Y622385D03*
X203605D03*
X206805Y632385D03*
X203605D03*
X210199Y714074D03*
X206199D03*
X206254Y732537D03*
X206933Y737277D03*
X208818Y766871D03*
X205365Y1307880D03*
Y1310380D03*
Y1312880D03*
X202865D03*
Y1310380D03*
Y1307880D03*
X216165D03*
Y1310380D03*
Y1312880D03*
Y1305380D03*
Y1300380D03*
Y1302880D03*
X205365Y1305380D03*
X202865D03*
X205365Y1300380D03*
Y1302880D03*
X202865D03*
Y1300380D03*
X205365Y1315380D03*
X202865D03*
X216165D03*
Y1317880D03*
X205365D03*
X202865D03*
X209830Y1385287D03*
X203063Y1382593D03*
Y1380085D03*
X210505Y1382130D03*
X207017Y1380530D03*
X209755Y1379562D03*
X213648Y1416262D03*
X205558Y1418560D03*
Y1416060D03*
X202945Y1415910D03*
Y1418410D03*
X208058Y1416060D03*
X208061Y1418605D03*
X206941Y1450295D03*
X208851Y1452895D03*
X206941Y1455495D03*
X206251Y1452895D03*
X202851D03*
X213651Y1472295D03*
X215561Y1469695D03*
Y1474895D03*
X216251Y1472295D03*
X207968Y1653130D03*
X203800Y1646832D03*
X206788Y1660960D03*
X210833Y1660867D03*
X210217Y1668603D03*
X203807Y1681173D03*
X207807Y1681302D03*
X203807Y1696366D03*
X207807Y1696409D03*
X211103Y1708988D03*
X212365Y1705403D03*
X211000Y1717675D03*
X202596Y1737117D03*
X229928Y3001D03*
X217853Y17045D03*
X222833D03*
X222063Y19541D03*
X218663D03*
X217736Y25977D03*
X223881Y28406D03*
X230967D03*
X217853Y22037D03*
X222833D03*
X224841Y19541D03*
X229131Y26477D03*
X225731D03*
X223891Y37106D03*
X230977D03*
X223881Y40020D03*
X230967D03*
X223891Y48720D03*
X230977D03*
X229127Y50649D03*
X225727D03*
X222591Y69343D03*
X224795Y75340D03*
X226705Y72847D03*
X231685D03*
X220685Y66850D03*
Y71842D03*
X227495Y75340D03*
X230895D03*
X219891Y69343D03*
X231685Y77839D03*
X226705D03*
X224055Y127146D03*
X233284Y137195D03*
X233653Y162074D03*
X222000Y160000D03*
X221051Y153167D03*
X220687Y522453D03*
X226687D03*
X223687D03*
X229687D03*
X226599Y570970D03*
X217999Y585668D03*
X223999D03*
X220999D03*
X217202Y606943D03*
X220202D03*
X223202D03*
X223111Y603782D03*
X225895Y609691D03*
X228895D03*
X220111Y603782D03*
X217202Y609681D03*
X220202D03*
X223202D03*
X218024Y622385D03*
X221024D03*
X224024D03*
X227024D03*
X221024Y632385D03*
X218024D03*
X224024D03*
X227024D03*
X233493Y676906D03*
X227493D03*
X224493D03*
X230493D03*
X221493D03*
X224157Y715915D03*
Y712915D03*
X229263Y765863D03*
X229275Y769292D03*
X218665Y1312880D03*
Y1310380D03*
Y1307880D03*
X221165Y1312880D03*
Y1310380D03*
Y1307880D03*
Y1305380D03*
X218665D03*
X221165Y1300380D03*
Y1302880D03*
X218665D03*
Y1300380D03*
X224481Y1326418D03*
X221881D03*
X224481Y1323918D03*
X221881Y1321418D03*
X224481D03*
X221881Y1323918D03*
X230171Y1323904D03*
Y1321404D03*
X218665Y1315380D03*
X221165D03*
Y1317880D03*
X218665D03*
X227871Y1338124D03*
X223941Y1338068D03*
X221341D03*
X230661Y1338124D03*
X224691Y1354871D03*
Y1352271D03*
X223441Y1357371D03*
X222091Y1354871D03*
Y1352271D03*
X224691Y1349671D03*
X222091D03*
X229101Y1369018D03*
Y1371559D03*
X219401Y1370067D03*
Y1367167D03*
X225411Y1373177D03*
X228892Y1384789D03*
X230550Y1386740D03*
X230594Y1379933D03*
X225411Y1378977D03*
Y1376077D03*
X221145Y1379207D03*
X223311Y1377577D03*
X223211Y1374577D03*
X221145Y1376307D03*
X228693Y1408885D03*
X224881Y1410685D03*
X220803Y1412115D03*
X217097Y1413863D03*
X227051Y1452895D03*
X228951Y1462595D03*
X220351D03*
X228961Y1450295D03*
Y1455495D03*
X227041Y1459995D03*
X222261D03*
X226351Y1462595D03*
X222951D03*
X229651Y1452895D03*
X222251Y1472295D03*
X220341Y1469695D03*
Y1474895D03*
X227041Y1465195D03*
X222261D03*
X219651Y1472295D03*
X224596Y1737117D03*
X243486Y23005D03*
X238059Y26235D03*
X233335Y17665D03*
X235697Y21585D03*
X241306Y20325D03*
X246356Y26855D03*
X246506Y20365D03*
X242216Y39365D03*
X246216D03*
X238059Y37165D03*
X235697Y39755D03*
X248816Y48965D03*
X244296Y59765D03*
X239816Y54365D03*
X233595Y75340D03*
X248487Y68690D03*
X242920Y67915D03*
X238846Y72977D03*
X235186Y98067D03*
X234331Y103286D03*
X232529Y114830D03*
X238297Y121555D03*
X244818Y111546D03*
Y115546D03*
X235460Y115790D03*
X235186Y112022D03*
X238600Y130400D03*
X235147Y124435D03*
X241271Y130719D03*
X242215Y151788D03*
X234000Y148000D03*
X239988Y141986D03*
X236104Y151996D03*
X242251Y162515D03*
X245486Y159705D03*
X234628Y166735D03*
X246250Y204360D03*
X240413Y360867D03*
X233413D03*
X235913D03*
X234727Y584030D03*
Y571211D03*
X233438Y593556D03*
X236638D03*
X233456Y601598D03*
X236656D03*
X236674Y609640D03*
X233474D03*
X243845Y656940D03*
X246045Y655540D03*
X243845Y651140D03*
Y654040D03*
X245945Y652540D03*
X245815Y672746D03*
X244565Y677846D03*
Y680446D03*
Y675246D03*
X242543Y691115D03*
X239443Y691015D03*
X239843Y709715D03*
X232981Y743983D03*
X240200Y766300D03*
X246371Y772388D03*
X232965Y1297880D03*
X237965D03*
X235465D03*
Y1300380D03*
Y1302880D03*
X237965D03*
Y1300380D03*
X235465Y1305380D03*
X237965D03*
X232965Y1302880D03*
Y1300380D03*
Y1305380D03*
Y1307880D03*
Y1310380D03*
Y1312880D03*
X237965Y1307880D03*
Y1310380D03*
Y1312880D03*
X235465D03*
Y1310380D03*
Y1307880D03*
X232961Y1323904D03*
Y1321404D03*
X237965Y1315380D03*
X235465D03*
X232965D03*
X239561Y1338124D03*
X242630Y1385287D03*
X235863Y1380085D03*
X243305Y1382130D03*
X239817Y1380530D03*
X242555Y1379562D03*
X235863Y1382593D03*
X232874Y1376408D03*
X233194Y1407349D03*
X235651Y1452895D03*
X233741Y1450295D03*
Y1455495D03*
X233051Y1452895D03*
X240451Y1472295D03*
X242361Y1469695D03*
Y1474895D03*
X246451Y1472295D03*
X243051D03*
X251928Y3001D03*
X255106Y16615D03*
X251106Y12615D03*
X252996Y28365D03*
X256496D03*
X249496D03*
X259996D03*
X250216Y39365D03*
X254046Y39425D03*
X259316Y48965D03*
X261016Y51565D03*
X252316Y48965D03*
X255816D03*
X254016Y51565D03*
X250516D03*
X257516D03*
X247716Y75865D03*
Y71865D03*
X251793Y100846D03*
X247893Y100546D03*
X248093Y92146D03*
X261416Y100665D03*
X253874Y111774D03*
X252800Y114800D03*
X261383Y133786D03*
X258253D03*
X252195Y144320D03*
X249735Y152694D03*
X262886Y147391D03*
X256586Y138373D03*
X260596Y151065D03*
X248350Y165700D03*
X257252Y156730D03*
X254095Y209235D03*
X258439Y214000D03*
X247859Y375389D03*
X250359D03*
X254859D03*
X247694Y378523D03*
X250194D03*
X254694D03*
X254671Y642138D03*
X259426Y644830D03*
X258751Y647987D03*
X262239Y649587D03*
X259501Y650555D03*
X248111Y653810D03*
Y650910D03*
X250312Y670080D03*
Y667180D03*
Y663080D03*
Y660180D03*
X247165Y677846D03*
Y680446D03*
Y675246D03*
X254448Y692050D03*
X247587Y714760D03*
Y717260D03*
X252591Y714737D03*
Y717237D03*
X250091D03*
Y714737D03*
X247587Y712237D03*
X250087D03*
X252587D03*
X247587Y719760D03*
X252591Y719737D03*
X250091D03*
X247587Y724760D03*
X252587D03*
X250087D03*
X247587Y722260D03*
Y727260D03*
X250087Y729760D03*
X247587D03*
X250087Y727260D03*
X252587D03*
Y729760D03*
X252591Y722237D03*
X250091D03*
X254671Y776388D03*
X257071Y772770D03*
X258470Y775410D03*
X260971Y777988D03*
X248765Y1297880D03*
X251265D03*
X248765Y1292880D03*
Y1295380D03*
X251265D03*
Y1292880D03*
X248765Y1307880D03*
Y1310380D03*
Y1312880D03*
X251265D03*
Y1310380D03*
Y1307880D03*
X248765Y1305380D03*
X251265D03*
X248765Y1300380D03*
Y1302880D03*
X251265D03*
Y1300380D03*
X248765Y1315380D03*
X251265D03*
Y1317880D03*
X248765D03*
X260671Y1338124D03*
X258071D03*
X247725Y1338141D03*
X257491Y1352271D03*
X256241Y1357371D03*
X257491Y1354871D03*
X254891Y1352271D03*
Y1354871D03*
X257491Y1349671D03*
X254891D03*
X258211Y1373177D03*
X256111Y1377577D03*
X258211Y1378977D03*
X256011Y1374577D03*
X258211Y1376077D03*
X253945Y1379207D03*
Y1376307D03*
X253851Y1452895D03*
X255751Y1462595D03*
X247151D03*
X260541Y1450295D03*
X255761D03*
X260541Y1455495D03*
X255761D03*
X253841Y1459995D03*
X249061D03*
X253151Y1462595D03*
X259851Y1452895D03*
X249751Y1462595D03*
X256451Y1452895D03*
X249051Y1472295D03*
X253841Y1465195D03*
X249061D03*
X247141Y1469695D03*
Y1474895D03*
X261530Y1550300D03*
X273928Y3001D03*
X275116Y28565D03*
X272596Y27185D03*
X263276Y34625D03*
X271596Y40165D03*
X275896Y48875D03*
X266420Y39120D03*
X265365Y49171D03*
X263516Y51565D03*
X261816Y48965D03*
X263182Y73396D03*
X269860Y72741D03*
X262893Y77529D03*
Y80029D03*
X263316Y87665D03*
X275238Y83024D03*
X264916Y100665D03*
X268416D03*
X262916Y97965D03*
X266416D03*
X269916D03*
X273616Y96665D03*
X270364Y118415D03*
X272361Y120243D03*
X264293Y120972D03*
X269487Y121095D03*
X275793Y120248D03*
X266000Y125800D03*
X275793Y129595D03*
X266971Y140110D03*
X264574Y151206D03*
X276821Y140465D03*
X270178Y140322D03*
X264574Y159206D03*
Y155206D03*
X262500Y161100D03*
X273500Y207500D03*
X266360Y203070D03*
X267500Y220441D03*
X269925Y217700D03*
X272242Y523076D03*
X274993Y522052D03*
X269568Y522366D03*
X266327Y522456D03*
X274201Y579478D03*
X274096Y574698D03*
X266601Y586578D03*
X265100Y595078D03*
X273208Y588237D03*
X270905Y608485D03*
X273905D03*
Y611485D03*
X267601Y608378D03*
X271571Y644796D03*
X271462Y650184D03*
X266193Y650032D03*
X272955Y658558D03*
X266193Y647524D03*
X269182Y653709D03*
X270857Y668515D03*
X272955Y661099D03*
X276575Y685381D03*
Y688281D03*
X263839Y692049D03*
X272603Y692910D03*
Y695510D03*
X276575Y691181D03*
X265891Y714737D03*
Y717237D03*
X263391D03*
Y714737D03*
X263387Y712237D03*
X265887D03*
X265891Y719737D03*
X263391D03*
X265787Y724760D03*
X263287D03*
X265787Y727260D03*
X263287D03*
X265787Y729760D03*
X263287D03*
X265787Y732260D03*
X263287D03*
X265891Y722237D03*
X263391D03*
X265787Y737260D03*
X263287D03*
X265787Y734760D03*
X263287D03*
X271161Y780588D03*
X268991Y783248D03*
X271245Y785474D03*
X274282Y786741D03*
X272054Y801112D03*
X270850Y797605D03*
X272165Y1256716D03*
X269665Y1259216D03*
X272165D03*
X269765Y1269234D03*
X272265D03*
X269765Y1261734D03*
Y1264234D03*
Y1266734D03*
X272265D03*
Y1264234D03*
Y1261734D03*
X267179Y1269273D03*
Y1266773D03*
Y1264273D03*
Y1261773D03*
Y1271773D03*
X269679D03*
X272179D03*
X271491Y1291740D03*
X274091D03*
X262701Y1322872D03*
Y1325413D03*
X276230Y1339141D03*
X264085Y1339175D03*
X264194Y1333787D03*
X269463Y1333939D03*
X273417Y1334384D03*
X276155Y1333416D03*
X269463Y1336447D03*
X266474Y1330262D03*
X275851Y1452895D03*
X267251D03*
X262451D03*
X273941Y1450295D03*
X269161D03*
X273941Y1455495D03*
X269161D03*
X269851Y1452895D03*
X273251D03*
X276085Y1509654D03*
X269829Y1521436D03*
X273597Y1519845D03*
X269144Y1511953D03*
X273474Y1516120D03*
Y1512220D03*
X269144Y1514453D03*
Y1516953D03*
X267322Y1519250D03*
X276624Y1516120D03*
Y1512220D03*
X276637Y1521436D03*
Y1523953D03*
X270720Y1531073D03*
X273220D03*
X275720D03*
X270139Y1548563D03*
X274546Y1549295D03*
Y1546795D03*
X267297Y1546119D03*
X266596Y1737117D03*
X291000Y14820D03*
X285896Y23965D03*
X278979Y28406D03*
X286066D03*
X291156Y21395D03*
X286996Y20365D03*
X290795Y28365D03*
X284228Y25935D03*
X280828D03*
X286716Y40020D03*
X282716D03*
X290716D03*
X285499Y53191D03*
X278989Y48720D03*
X286076D03*
X287988Y54893D03*
X291379Y55746D03*
X293157Y50525D03*
X284226Y50649D03*
X280826D03*
X278638Y83024D03*
X279273Y99186D03*
X288553Y105006D03*
X285353D03*
X289553Y121806D03*
X280853Y109906D03*
X282853Y115606D03*
X285853D03*
X280853Y107306D03*
X286996Y139865D03*
X283049Y139731D03*
X283949Y152506D03*
X288516Y157065D03*
X288000Y209000D03*
X290000Y222575D03*
X289163Y212503D03*
X285260Y234000D03*
X279500Y234075D03*
X278425Y230925D03*
X289393Y498960D03*
X278547Y523041D03*
X281147Y521803D03*
X284018Y522300D03*
X287723Y548499D03*
X289421Y575098D03*
X290865Y609470D03*
X277105Y608485D03*
X280305D03*
X277105Y611485D03*
X280305D03*
X286665Y609470D03*
X283705Y608485D03*
X284705Y605485D03*
X283705Y611485D03*
X287832Y674150D03*
X291481Y682228D03*
X280841Y688051D03*
X278675Y686781D03*
X280841Y685151D03*
X278775Y689781D03*
X283042Y697280D03*
Y694380D03*
X279895Y709487D03*
X278545Y706987D03*
X279895Y712087D03*
Y714687D03*
X277295Y709487D03*
Y712087D03*
Y714687D03*
X277055Y722649D03*
X279171Y724988D03*
X285317Y746478D03*
X282817D03*
X280317D03*
Y759110D03*
X285317D03*
X282817D03*
X285317Y761610D03*
X285321Y748978D03*
Y751478D03*
Y753978D03*
X282821D03*
Y751478D03*
Y748978D03*
X285321Y756478D03*
X282821D03*
X280317Y756610D03*
Y751610D03*
Y754110D03*
Y749110D03*
Y761610D03*
X282817D03*
X284035Y796850D03*
X285258Y799314D03*
X282323Y794867D03*
X281449Y809609D03*
X283987Y811342D03*
X285565Y1246716D03*
X288065D03*
X283065D03*
X288065Y1251716D03*
X285565D03*
X283065D03*
X288065Y1249216D03*
X285565D03*
X283065D03*
Y1254216D03*
X288065D03*
X285565D03*
X283065Y1269234D03*
X285565D03*
X283065Y1261734D03*
Y1264234D03*
Y1266734D03*
X285565D03*
Y1264234D03*
Y1261734D03*
X283065Y1256716D03*
X285565D03*
X288065D03*
X283065Y1259216D03*
X285565D03*
X288065D03*
Y1266716D03*
Y1264216D03*
Y1261716D03*
Y1269216D03*
X285479Y1271773D03*
X282979D03*
X287979D03*
X283921Y1291740D03*
X281321D03*
X288491Y1306125D03*
Y1308725D03*
X291091Y1306125D03*
Y1308725D03*
X288491Y1303525D03*
X291091D03*
X289841Y1311225D03*
X289611Y1328431D03*
X281992Y1342705D03*
X276905Y1335984D03*
X289711Y1331431D03*
X287545Y1330161D03*
Y1333061D03*
X280621Y1478082D03*
X291175Y1477590D03*
X280621Y1486682D03*
X283221Y1484772D03*
Y1479992D03*
X278021Y1484772D03*
Y1479992D03*
X291175Y1486190D03*
X288575Y1484280D03*
Y1479500D03*
X283221Y1493392D03*
X280621Y1491482D03*
X278021Y1493392D03*
X280621Y1484082D03*
Y1480682D03*
X291175Y1483590D03*
Y1480190D03*
X280621Y1500082D03*
X291175Y1499490D03*
X288575Y1506080D03*
Y1501300D03*
X291175Y1507990D03*
X283221Y1498172D03*
X278021D03*
X280621Y1497482D03*
Y1494082D03*
X291175Y1501990D03*
Y1505390D03*
X280088Y1509469D03*
X282588D03*
X279774Y1512220D03*
Y1516120D03*
X284024Y1514576D03*
X279499Y1519845D03*
X284024Y1512076D03*
X283946Y1530595D03*
X286446D03*
X291619Y1536606D03*
X291593Y1529402D03*
Y1531902D03*
X284800Y1526750D03*
X277572Y1536763D03*
X280072D03*
X290593Y1523331D03*
Y1526731D03*
X291619Y1539106D03*
X291416Y1541795D03*
Y1549295D03*
Y1546795D03*
Y1544295D03*
X285586Y1551844D03*
X288004Y1551099D03*
X290509Y1551844D03*
X288004Y1548199D03*
X284014Y1538682D03*
X286514D03*
X284546Y1549295D03*
Y1546795D03*
Y1541795D03*
Y1544295D03*
X287046D03*
Y1541795D03*
X277046Y1546795D03*
Y1549295D03*
X282046D03*
Y1546795D03*
Y1544295D03*
X279546Y1549295D03*
Y1546795D03*
X282046Y1541795D03*
X295928Y3001D03*
X300230Y14820D03*
X302606Y26365D03*
X292056Y24475D03*
X295516Y26365D03*
X300244Y28365D03*
X299496Y22865D03*
X304923Y24657D03*
X304968Y28365D03*
X303252Y38199D03*
X298716Y40020D03*
X296337Y55855D03*
X301306Y52485D03*
X298542Y51088D03*
X303711Y50860D03*
X296272Y69128D03*
X295755Y72800D03*
X301107Y75676D03*
X305820Y73693D03*
X303852Y65042D03*
X306470Y65160D03*
X293443Y78576D03*
X293448Y82486D03*
Y85986D03*
X303043Y79376D03*
X299943Y79276D03*
X301780Y82900D03*
X299002Y88700D03*
X299653Y92506D03*
X307816Y95727D03*
X301747Y121469D03*
X301179Y112806D03*
Y110006D03*
Y107106D03*
X301747Y127469D03*
Y124469D03*
X299628Y149203D03*
X296478D03*
X299624Y158706D03*
X294553Y153819D03*
X296474Y158706D03*
X293000Y216500D03*
X292811Y213242D03*
X296283Y242391D03*
X306528Y256528D03*
X292705Y580275D03*
X297815Y580384D03*
X294299Y577188D03*
X302130Y584160D03*
X294165Y609570D03*
X297838Y609585D03*
X300965Y609570D03*
X304449D03*
X292156Y679071D03*
X304301Y679037D03*
X304192Y684425D03*
X298923Y684273D03*
X294969Y683828D03*
X292231Y684796D03*
X298923Y681765D03*
X301912Y687950D03*
X305685Y695340D03*
Y692799D03*
X305121Y726348D03*
X298991D03*
X298617Y746478D03*
X296117D03*
X301117D03*
X298621Y753978D03*
X296121D03*
Y751478D03*
Y748978D03*
X298621Y756478D03*
X296121D03*
X301121Y748996D03*
Y751496D03*
Y753996D03*
Y756496D03*
X296117Y759110D03*
Y761610D03*
X301117Y759110D03*
X298617D03*
X301117Y761610D03*
X298617D03*
X298621Y748978D03*
Y751478D03*
X301117Y766610D03*
X296117D03*
Y764110D03*
X301117Y771610D03*
X298617D03*
Y769110D03*
X301117D03*
X296117Y771610D03*
Y769110D03*
X298617Y766610D03*
Y764110D03*
X301117D03*
X305061Y1254131D03*
X300061D03*
X302561D03*
X305061Y1249131D03*
Y1251631D03*
X300061D03*
X302561D03*
X300061Y1249131D03*
X302561D03*
X305061Y1246631D03*
X300061D03*
X302561D03*
X302661Y1269149D03*
X305161D03*
X302661Y1261649D03*
Y1264149D03*
Y1266649D03*
X305161D03*
Y1264149D03*
Y1261649D03*
X300061Y1269131D03*
Y1266631D03*
X305061Y1259131D03*
Y1256631D03*
X300061D03*
Y1259131D03*
Y1261631D03*
Y1264131D03*
X302561Y1256631D03*
Y1259131D03*
X305075Y1271688D03*
X302575D03*
X300075D03*
X294541Y1291378D03*
X291941D03*
X295597Y1322844D03*
Y1325385D03*
X291811Y1327031D03*
X295388Y1338615D03*
X297046Y1340566D03*
X297090Y1333759D03*
X302359Y1333911D03*
X306313Y1334356D03*
X302359Y1336419D03*
X299370Y1330234D03*
X291811Y1332831D03*
Y1329931D03*
X294725Y1381612D03*
X294533Y1384401D03*
X305204Y1381461D03*
X305012Y1384250D03*
X294684Y1387040D03*
X305163Y1386889D03*
X305199Y1398269D03*
Y1400769D03*
X295116Y1398132D03*
Y1400632D03*
X292516D03*
Y1398132D03*
X294683Y1390281D03*
X305163Y1389678D03*
X303413Y1462595D03*
X301513Y1452895D03*
X294813Y1462595D03*
X303423Y1450295D03*
Y1455495D03*
X301503Y1459995D03*
X296723D03*
X300813Y1462595D03*
X297413D03*
X304113Y1452895D03*
X301503Y1465195D03*
X296723D03*
X293775Y1484280D03*
Y1479500D03*
Y1506080D03*
Y1501300D03*
X299950Y1499500D03*
X301550Y1518040D03*
Y1514420D03*
Y1510800D03*
X292792Y1521561D03*
X302042Y1528731D03*
X295042Y1530596D03*
X304606Y1546333D03*
X296416Y1549295D03*
X293916D03*
Y1546795D03*
X296416D03*
Y1544295D03*
X293916D03*
X296416Y1541795D03*
X293916D03*
X298916D03*
Y1549295D03*
Y1546795D03*
Y1544295D03*
X303041Y1544299D03*
X297323Y1651172D03*
Y1659772D03*
X317928Y3001D03*
X318660Y24989D03*
X306716Y39985D03*
X310396Y50365D03*
X306566Y50225D03*
X323036Y73125D03*
X310455Y75895D03*
X320190Y77648D03*
X314653Y71806D03*
Y68906D03*
X320053Y85806D03*
Y88806D03*
X312410Y89060D03*
X322871Y84321D03*
X316982Y89003D03*
X311754Y121472D03*
X311053Y112806D03*
Y110006D03*
Y107106D03*
X311754Y124472D03*
Y127472D03*
X323646Y147120D03*
Y152120D03*
X308240Y148100D03*
X317472Y222262D03*
Y225217D03*
X319970Y228167D03*
X320095Y231810D03*
X310425Y243925D03*
X317240Y252970D03*
X308925Y260075D03*
X319075D03*
X311749Y440921D03*
X314780Y545716D03*
X322955Y556148D03*
X307865Y609570D03*
X311349Y609632D03*
X313961Y607088D03*
Y604588D03*
X319657Y696415D03*
X310445Y700931D03*
X312611Y702301D03*
X311545Y709931D03*
X310445Y703931D03*
X311445Y706931D03*
X313611Y708201D03*
Y705301D03*
X315912Y717400D03*
Y714500D03*
X312665Y729637D03*
Y732237D03*
X310065Y729637D03*
Y732237D03*
X311315Y727137D03*
X313255Y746279D03*
X312665Y734837D03*
X310065D03*
X313087Y769160D03*
Y771660D03*
Y774160D03*
Y776660D03*
X318091Y769128D03*
Y771628D03*
Y774128D03*
X315591D03*
Y771628D03*
Y769128D03*
X318091Y776628D03*
X315591D03*
X313087Y766628D03*
X315587D03*
X318087D03*
Y791660D03*
X313087D03*
X315587D03*
X318087Y789160D03*
X313087D03*
X315587D03*
Y779160D03*
X313087Y784160D03*
X315587D03*
X313087Y786660D03*
X315587D03*
X313087Y781660D03*
X315587D03*
X313087Y779160D03*
X318087Y786660D03*
Y784160D03*
Y779160D03*
Y781660D03*
X318461Y1254131D03*
X320961D03*
X315961D03*
Y1249131D03*
X318461D03*
X320961D03*
X315961Y1251631D03*
X318461D03*
X320961D03*
X315961Y1246631D03*
X318461D03*
X320961D03*
X315961Y1269149D03*
X318461D03*
X315961Y1261649D03*
Y1264149D03*
Y1266649D03*
X318461D03*
Y1264149D03*
Y1261649D03*
X320961Y1269131D03*
Y1256631D03*
Y1259131D03*
Y1261631D03*
X318461Y1256631D03*
Y1259131D03*
X320961Y1264131D03*
Y1266631D03*
X315961Y1256631D03*
Y1259131D03*
X320875Y1271688D03*
X315875D03*
X318375D03*
X319621Y1291740D03*
X321387Y1306097D03*
Y1308697D03*
Y1303497D03*
X309126Y1339113D03*
X309801Y1335956D03*
X309051Y1333388D03*
X320441Y1330133D03*
Y1333033D03*
X307799Y1400769D03*
Y1398269D03*
X318199Y1400549D03*
X314199D03*
X310399D03*
X310113Y1452895D03*
X308203Y1450295D03*
Y1455495D03*
X307513Y1452895D03*
X314913Y1472295D03*
X316823Y1469695D03*
Y1474895D03*
X320913Y1472295D03*
X317513D03*
X311476Y1552567D03*
X307255Y1641150D03*
Y1649750D03*
X312596Y1737117D03*
X329535Y49379D03*
X323113Y76941D03*
X334339Y162580D03*
X323646Y160120D03*
Y156120D03*
X326475Y182855D03*
X331780Y182900D03*
X331000Y270260D03*
X336000Y284000D03*
X324406Y367744D03*
X328966Y543012D03*
Y548030D03*
X325816Y543012D03*
X334744Y566086D03*
X324647D03*
X333500Y582500D03*
Y578500D03*
X333988Y590633D03*
X334031Y613498D03*
Y610498D03*
X331391D03*
Y613498D03*
X333502Y600019D03*
Y603019D03*
X330109Y602883D03*
Y605883D03*
X334031Y619398D03*
Y616498D03*
X331391D03*
Y619398D03*
X324926Y699221D03*
X324251Y702378D03*
X331693Y701915D03*
Y704423D03*
X327739Y703978D03*
X325001Y704946D03*
X334682Y708100D03*
X331391Y769128D03*
Y771628D03*
Y774128D03*
X328891D03*
Y771628D03*
Y769128D03*
X331391Y776628D03*
X328891D03*
X333887Y766628D03*
X328887D03*
X331387D03*
X333891Y776646D03*
Y774146D03*
Y771646D03*
Y769146D03*
X333887Y791660D03*
X328887D03*
X331387D03*
X333887Y789160D03*
X328887D03*
X331387D03*
X333887Y779160D03*
Y781660D03*
X331387Y779160D03*
X328887D03*
Y781660D03*
X331387D03*
X333887Y786660D03*
X328887D03*
X331387D03*
X333887Y784160D03*
X328887D03*
X331387D03*
X335465Y1246631D03*
X332965D03*
X335465Y1249131D03*
X332965D03*
X335465Y1251631D03*
X332965D03*
X335465Y1254131D03*
X332965D03*
X335465Y1259131D03*
Y1256631D03*
X332965Y1259131D03*
Y1256631D03*
X335565Y1269149D03*
Y1261649D03*
Y1264149D03*
Y1266649D03*
X332961Y1269188D03*
Y1266688D03*
Y1261688D03*
Y1264188D03*
Y1271688D03*
X335461D03*
X329471Y1291778D03*
X322221Y1291740D03*
X326761Y1291778D03*
X323987Y1303497D03*
Y1306097D03*
Y1308697D03*
X322737Y1311197D03*
X328501Y1322787D03*
Y1325328D03*
X324707Y1327003D03*
X322507Y1328403D03*
X328292Y1338558D03*
X329950Y1340509D03*
X329994Y1333702D03*
X335263Y1333854D03*
Y1336362D03*
X332274Y1330177D03*
X324707Y1332803D03*
X322607Y1331403D03*
X324707Y1329903D03*
X334038Y1373469D03*
X334230Y1370680D03*
X323559Y1373620D03*
X323751Y1370831D03*
X334189Y1376108D03*
X323710Y1376259D03*
X334189Y1378897D03*
X323709Y1379500D03*
X333830Y1396299D03*
Y1398899D03*
Y1401499D03*
Y1393799D03*
X324309Y1396599D03*
Y1399199D03*
Y1401799D03*
Y1394099D03*
X321999Y1400549D03*
X330213Y1462595D03*
X321613D03*
X323523Y1459995D03*
X328303D03*
X328313Y1452895D03*
X335003Y1450295D03*
X330223D03*
X335003Y1455495D03*
X330223D03*
X327613Y1462595D03*
X334313Y1452895D03*
X324213Y1462595D03*
X330913Y1452895D03*
X323513Y1472295D03*
X328313D03*
X323523Y1465195D03*
X328303D03*
X321603Y1469695D03*
Y1474895D03*
X334596Y1737117D03*
X341082Y56308D03*
X340436Y120555D03*
X343036Y122525D03*
X343446Y131170D03*
X339914Y165170D03*
X338244Y192264D03*
X344984Y199299D03*
X344106Y222659D03*
X348107Y220420D03*
X348645Y229180D03*
X352000Y230643D03*
Y235643D03*
X349676Y276708D03*
X344034Y282609D03*
X349695Y286712D03*
X342075Y287925D03*
X348890Y409120D03*
Y411620D03*
X340337Y496462D03*
X346751Y515376D03*
X350566Y541882D03*
X350817Y558248D03*
X351157Y562415D03*
X351018Y554896D03*
X351157Y566936D03*
X345521Y564388D03*
X349397Y564459D03*
X345500Y574415D03*
X351157D03*
Y570415D03*
X341500Y574500D03*
X342500Y582500D03*
Y578500D03*
X338420Y574500D03*
X343182Y586415D03*
Y591335D03*
X351157Y586415D03*
X337031Y607498D03*
Y613498D03*
Y610498D03*
X346031Y607498D03*
X343031D03*
X349031D03*
X346031Y610498D03*
X343031D03*
X349031D03*
X340031Y607498D03*
Y610498D03*
Y613498D03*
X346031Y604498D03*
X343031D03*
X349031D03*
X340031D03*
X343691Y614018D03*
X346191D03*
X348691D03*
X343721Y618348D03*
X346221D03*
X348721D03*
X351191Y614018D03*
X351221Y618348D03*
X340031Y619398D03*
Y616498D03*
X337031Y619398D03*
Y616498D03*
X342675Y640994D03*
X345175D03*
X347675D03*
X350175D03*
X342675Y643494D03*
X345175D03*
X347675D03*
X350175D03*
X342595Y646054D03*
X345095D03*
X347595D03*
X350095D03*
X338664Y699660D03*
X337030Y697750D03*
X336962Y704575D03*
X338455Y715490D03*
Y712949D03*
X346671Y705033D03*
X344505Y706663D03*
X346671Y707933D03*
X344605Y709663D03*
X342405Y705263D03*
Y708163D03*
Y711063D03*
X348395Y717060D03*
Y714160D03*
X345725Y729369D03*
X343125D03*
X345725Y731969D03*
X343125D03*
X344375Y726869D03*
X339825Y746269D03*
X342425D03*
X349625D03*
X345725Y734569D03*
X343125D03*
X346051Y769058D03*
Y771558D03*
Y774058D03*
Y776558D03*
X351151Y769040D03*
Y771540D03*
Y774040D03*
X348651D03*
Y771540D03*
Y769040D03*
X351151Y776540D03*
X348651D03*
X351147Y766540D03*
X348647D03*
X346147D03*
X346051Y791558D03*
X348551D03*
X351051D03*
X346051Y789058D03*
X348551D03*
X346051Y784058D03*
X348551D03*
X346051Y786558D03*
X348551D03*
X346051Y779058D03*
X348551D03*
X346051Y781558D03*
X348551D03*
X351051Y789058D03*
Y784058D03*
Y786558D03*
Y779058D03*
Y781558D03*
X347107Y1174343D03*
X339278Y1192112D03*
X336778D03*
X347885Y1206426D03*
X339532Y1218605D03*
X349938Y1214563D03*
X337965Y1251631D03*
Y1249131D03*
Y1254131D03*
X348865Y1246631D03*
Y1251631D03*
Y1249131D03*
Y1254131D03*
X337965Y1246631D03*
X348865Y1269149D03*
Y1261649D03*
Y1264149D03*
Y1266649D03*
X338065Y1269149D03*
Y1266649D03*
Y1264149D03*
Y1261649D03*
X337965Y1256631D03*
Y1259131D03*
X348865D03*
Y1256631D03*
X337961Y1271688D03*
X348861D03*
X342030Y1339056D03*
X342705Y1335899D03*
X339217Y1334299D03*
X341955Y1333331D03*
X346464Y1380102D03*
X343964D03*
X348964D03*
Y1387602D03*
Y1385102D03*
Y1382602D03*
X343964Y1385102D03*
Y1387602D03*
X346464Y1385102D03*
Y1387602D03*
X343964Y1382602D03*
X346464D03*
X347110Y1398312D03*
X351110D03*
X341760Y1401449D03*
X337760D03*
X349760D03*
X345760D03*
X348964Y1390102D03*
X343964D03*
Y1392602D03*
X346464D03*
Y1390102D03*
X343777Y1395166D03*
X346302Y1395242D03*
X348828Y1395392D03*
X349032Y1392675D03*
X348413Y1462595D03*
X350323Y1459995D03*
X336913Y1452895D03*
X351013Y1462595D03*
X350313Y1472295D03*
X341713D03*
X350323Y1465195D03*
X348403Y1469695D03*
X343623D03*
X348403Y1474895D03*
X343623D03*
X347713Y1472295D03*
X344313D03*
X351535Y49379D03*
X361744Y120713D03*
X366874Y135157D03*
X366771Y127665D03*
X363621D03*
X352418Y225329D03*
Y222329D03*
X361171Y223114D03*
X358618Y223129D03*
X361171Y220614D03*
X358671D03*
X355910Y223847D03*
X365739Y221871D03*
X365559Y238896D03*
X355733Y275059D03*
X359734Y288768D03*
X360433Y294030D03*
X355832Y297855D03*
X357925Y304082D03*
X351390Y409120D03*
X353890D03*
Y411620D03*
X351390D03*
X365852Y516466D03*
X353700Y547893D03*
X356850D03*
X355100Y544390D03*
X359200Y566990D03*
X359657Y570702D03*
X359157Y574415D03*
X365158Y597546D03*
Y593580D03*
X352031Y607498D03*
Y610498D03*
X355031Y607498D03*
Y613498D03*
Y610498D03*
X352031Y604498D03*
X355031D03*
X361031Y607498D03*
Y613498D03*
Y610498D03*
X358031Y607498D03*
Y613498D03*
Y610498D03*
Y604498D03*
X365593Y621622D03*
X358031Y619398D03*
Y616498D03*
X355031Y619398D03*
Y616498D03*
X361031Y619398D03*
Y616498D03*
X352675Y640994D03*
Y643494D03*
X355275Y641034D03*
Y643534D03*
X355195Y646094D03*
X352595Y646054D03*
X357986Y698953D03*
X357311Y702110D03*
X364753Y701647D03*
Y704155D03*
X360799Y703710D03*
X358061Y704678D03*
X352225Y746269D03*
X360025D03*
X362625D03*
X364451Y769040D03*
Y771540D03*
Y774040D03*
X361951D03*
Y771540D03*
Y769040D03*
X364451Y776540D03*
X361951D03*
X364447Y766540D03*
X361947D03*
X364451Y791558D03*
X361951D03*
X364451Y786558D03*
Y789058D03*
X361951D03*
Y786558D03*
X364451Y784058D03*
X361951Y781558D03*
X364451Y779058D03*
Y781558D03*
X361951Y779058D03*
Y784058D03*
X361671Y803588D03*
X356671D03*
X351671D03*
X363313Y812088D03*
X359813Y812188D03*
X356313D03*
X352813D03*
X356535Y849708D03*
X364897Y852564D03*
X364821Y861852D03*
X357400Y855982D03*
X356895Y859791D03*
X353281Y859620D03*
X364788Y1193918D03*
X364457Y1188109D03*
X363236Y1199632D03*
X361922Y1206891D03*
X357271Y1208988D03*
X351413Y1210052D03*
X352943Y1214510D03*
X365461Y1254188D03*
Y1251688D03*
Y1249188D03*
Y1246688D03*
X351365Y1246631D03*
X353865D03*
Y1251631D03*
X351365D03*
X353865Y1249131D03*
X351365D03*
X353865Y1254131D03*
X351365D03*
Y1269149D03*
Y1266649D03*
Y1264149D03*
Y1261649D03*
X365461Y1256688D03*
Y1259188D03*
X353865Y1266631D03*
Y1264131D03*
Y1261631D03*
Y1269131D03*
X351365Y1259131D03*
Y1256631D03*
X353865Y1259131D03*
Y1256631D03*
X365561Y1269288D03*
Y1264288D03*
Y1266788D03*
Y1261788D03*
Y1271788D03*
X351361Y1271688D03*
X353861D03*
X359541Y1291918D03*
X362311Y1291968D03*
X356551Y1291880D03*
X353951D03*
X356891Y1306040D03*
Y1308640D03*
Y1303440D03*
X354291Y1306040D03*
Y1308640D03*
Y1303440D03*
X355641Y1311140D03*
X361301Y1322987D03*
Y1325528D03*
X357611Y1326946D03*
X355411Y1328346D03*
X361092Y1338758D03*
X362750Y1340709D03*
X362794Y1333902D03*
X365074Y1330377D03*
X353345Y1332976D03*
X357611Y1329846D03*
X353345Y1330076D03*
X355511Y1331346D03*
X357611Y1332746D03*
X356764Y1359296D03*
X354264D03*
X364764D03*
X362264D03*
X359764D03*
X351632Y1359203D03*
X351923Y1364724D03*
X354423D03*
X356923D03*
X359423D03*
X362223D03*
X364723D03*
X351772Y1362085D03*
X354272D03*
X356772D03*
X359272D03*
X362072D03*
X364572D03*
X363964Y1385102D03*
X356464Y1380102D03*
X358964D03*
X361464D03*
X353964D03*
X351464D03*
X363964D03*
Y1382602D03*
X351464Y1385102D03*
X353964D03*
X361464D03*
X356464D03*
X358964D03*
X351464Y1382602D03*
X361464D03*
X358964D03*
X356464D03*
X353964D03*
X352067Y1387665D03*
X354567D03*
X357067D03*
X359567D03*
X363190Y1387527D03*
X365979Y1387641D03*
X355110Y1398312D03*
X359110D03*
X363110D03*
X357760Y1401449D03*
X353760D03*
X352332Y1391886D03*
X354832D03*
X357332D03*
X359832D03*
X363191Y1390292D03*
Y1392792D03*
X365980Y1392906D03*
Y1390406D03*
X363003Y1395393D03*
X365792Y1395507D03*
X352313Y1395223D03*
X359859D03*
X357208D03*
X363713Y1452895D03*
X355113D03*
X357013Y1462595D03*
X361803Y1450295D03*
X357023D03*
X361803Y1455495D03*
X357023D03*
X355103Y1459995D03*
X354413Y1462595D03*
X361113Y1452895D03*
X357713D03*
X355103Y1465195D03*
X365493Y1655107D03*
X356596Y1737117D03*
X373535Y49379D03*
X375920Y146577D03*
X370888Y155250D03*
X379023Y225149D03*
X371318Y218629D03*
X377118Y222229D03*
X379023Y228649D03*
X379028Y232559D03*
X369428Y231759D03*
X372528Y231859D03*
X380181Y236674D03*
X380012Y239615D03*
X370327Y228951D03*
X370352Y235455D03*
X380012Y243615D03*
X379200Y298772D03*
X366671Y297114D03*
X369171D03*
X369671Y292114D03*
Y294614D03*
X367902Y303760D03*
X380935Y443386D03*
X375935D03*
X378435D03*
X382184Y466351D03*
X378976Y479226D03*
X379633Y493942D03*
X380771Y524903D03*
X375943D03*
X368371Y553038D03*
X371971Y553138D03*
X375410Y552254D03*
X377502Y554193D03*
X380157Y553090D03*
X375271Y542191D03*
X379114Y544866D03*
X368647Y550422D03*
X369171Y562380D03*
X376671D03*
X370271Y555038D03*
X369100Y577400D03*
X369171Y569880D03*
X376600Y577400D03*
X369271Y600138D03*
X373477Y593338D03*
X378577Y593026D03*
X377577Y590126D03*
X371724Y699450D03*
X370090Y697482D03*
X370022Y704307D03*
X371515Y715222D03*
Y712681D03*
X367742Y707832D03*
X379711Y708001D03*
Y705101D03*
X375445Y708231D03*
X377545Y706731D03*
X375445Y705331D03*
X377645Y709731D03*
X375445Y711131D03*
X376165Y729437D03*
X378765D03*
X376165Y732037D03*
X378765D03*
X377415Y726937D03*
X373425Y746169D03*
X370825D03*
X376165Y734637D03*
X378765D03*
X366951Y769058D03*
Y771558D03*
Y774058D03*
Y776558D03*
X379187Y766428D03*
Y768960D03*
Y771460D03*
Y773960D03*
Y776460D03*
X366947Y766540D03*
X366951Y781558D03*
Y786558D03*
Y789058D03*
Y784058D03*
X379187Y786460D03*
Y783960D03*
Y788960D03*
Y778960D03*
Y781460D03*
X366951Y791558D03*
X379187Y791460D03*
X366951Y779058D03*
X376671Y803588D03*
X371671D03*
X366671D03*
X372000Y816862D03*
X371999Y819527D03*
X372000Y826362D03*
Y828862D03*
Y831797D03*
Y835197D03*
X371999Y822927D03*
X372000Y837862D03*
Y840362D03*
Y849362D03*
Y846427D03*
Y843027D03*
X366864Y857274D03*
X369626Y860717D03*
X378083Y1184949D03*
X367782Y1199648D03*
X367836Y1209506D03*
X370316Y1204673D03*
X367931Y1196981D03*
X376271Y1207488D03*
X380718Y1221906D03*
X379223Y1219527D03*
X367961Y1254188D03*
Y1251688D03*
Y1249188D03*
Y1246688D03*
X370461Y1254188D03*
Y1249188D03*
Y1251688D03*
Y1246688D03*
X367961Y1256688D03*
Y1259188D03*
X370461D03*
Y1256688D03*
X368061Y1269206D03*
X370561D03*
X368061Y1261706D03*
Y1264206D03*
Y1266706D03*
X370561D03*
Y1264206D03*
Y1261706D03*
Y1271788D03*
X368061D03*
X374830Y1339256D03*
X368063Y1334054D03*
X375505Y1336099D03*
X372017Y1334499D03*
X374755Y1333531D03*
X368063Y1336562D03*
X377190Y1387697D03*
X368964Y1382602D03*
Y1385102D03*
X366464D03*
X368964Y1380102D03*
X366464D03*
Y1382602D03*
X368542Y1387639D03*
X379610Y1391781D03*
X375056Y1393741D03*
X368543Y1390404D03*
Y1392904D03*
X368355Y1395505D03*
X375213Y1462595D03*
X377123Y1459995D03*
X377813Y1462595D03*
X377113Y1472295D03*
X368513D03*
X377123Y1465195D03*
X375203Y1469695D03*
X370423D03*
X375203Y1474895D03*
X370423D03*
X374513Y1472295D03*
X371113D03*
X374432Y1582600D03*
X372313Y1641759D03*
X375050Y1639400D03*
X371823Y1644516D03*
X370533Y1658605D03*
X374962Y1648511D03*
X372953Y1653197D03*
X379895Y1670046D03*
X373330Y1668539D03*
X370369Y1661817D03*
X372350Y1683284D03*
X372449Y1680520D03*
X372395Y1677449D03*
X381770Y-30570D03*
X385023Y-30584D03*
X388048Y-29264D03*
X381755Y-28055D03*
X385008Y-28069D03*
X393287Y-28508D03*
X390841Y-25571D03*
Y-22171D03*
X381740Y-25540D03*
X381725Y-23025D03*
X385024Y-17575D03*
X381771Y-17589D03*
X388049Y-18895D03*
X381756Y-20104D03*
X385009Y-20090D03*
X381725Y-14717D03*
X393287Y-18508D03*
X385008Y-9673D03*
X385023Y-7158D03*
X381755Y-9687D03*
X388048Y-8478D03*
X381770Y-7172D03*
X381740Y-12202D03*
X393287Y-9234D03*
X395535Y49379D03*
X391600Y121178D03*
X395048D03*
X387712Y147441D03*
X384375Y147365D03*
X386350Y138980D03*
X395590Y147010D03*
X391635Y161091D03*
X384600Y221800D03*
X391310Y227871D03*
X390461Y270694D03*
Y267694D03*
Y275194D03*
X386563Y280370D03*
X389912Y280345D03*
X390881Y284156D03*
X395053Y318125D03*
X383525Y443386D03*
X384668Y471926D03*
X387184Y470495D03*
X389784Y476070D03*
X387184Y494382D03*
X384827Y507057D03*
X397184Y507101D03*
X382184D03*
X387440Y525154D03*
X395657Y546894D03*
X391657Y546816D03*
X387657Y546876D03*
X383071Y553738D03*
X382705Y546433D03*
X384259Y562426D03*
X395669Y563328D03*
X385318Y555238D03*
X394168Y568482D03*
X384301Y577446D03*
X393481Y571239D03*
X385443Y597279D03*
X392471Y596988D03*
X391021Y588788D03*
X391026Y699021D03*
X390351Y702178D03*
X393839Y703778D03*
X391101Y704746D03*
X381812Y717060D03*
Y714160D03*
X394987Y766428D03*
X381687D03*
X384187D03*
X394991Y773928D03*
Y771428D03*
Y768928D03*
Y776428D03*
X384191Y768928D03*
Y771428D03*
Y773928D03*
X381691D03*
Y771428D03*
Y768928D03*
X384191Y776428D03*
X381691D03*
X381687Y791460D03*
X384187D03*
X394987Y784060D03*
Y779060D03*
Y781560D03*
Y789060D03*
Y786560D03*
X381687Y778960D03*
Y786460D03*
Y783960D03*
Y788960D03*
Y781460D03*
X384187Y788960D03*
Y786460D03*
Y783960D03*
Y778960D03*
Y781460D03*
X384500Y810862D03*
X384499Y819862D03*
X385001Y816927D03*
Y813527D03*
X381361Y1254188D03*
Y1249188D03*
Y1251688D03*
Y1246688D03*
X383861Y1254188D03*
X386361D03*
X383861Y1249188D03*
X386361D03*
X383861Y1251688D03*
X386361D03*
X383861Y1246688D03*
X386361D03*
X381361Y1269206D03*
X383861D03*
X381361Y1261706D03*
Y1264206D03*
Y1266706D03*
X383861D03*
Y1264206D03*
Y1261706D03*
X381361Y1256688D03*
Y1259188D03*
X386361Y1256688D03*
Y1259188D03*
X383861Y1256688D03*
Y1259188D03*
X386361Y1269288D03*
Y1261788D03*
Y1266788D03*
Y1264288D03*
X381361Y1271788D03*
X386361D03*
X383861D03*
X388361Y1293713D03*
X385701Y1291828D03*
X392176Y1309859D03*
X394951Y1311259D03*
X389691Y1306240D03*
Y1308840D03*
X387091Y1306240D03*
Y1308840D03*
X389691Y1303640D03*
X387091D03*
X388441Y1311340D03*
X392950Y1315280D03*
X392910Y1317880D03*
X388211Y1328546D03*
X393883Y1342318D03*
X388311Y1331546D03*
X386145Y1333176D03*
Y1330276D03*
X386611Y1336056D03*
X388771Y1337546D03*
Y1334546D03*
X395267Y1358621D03*
X395376Y1353233D03*
X393883Y1344859D03*
X393321Y1385630D03*
X388718Y1387386D03*
X384270Y1389875D03*
X383813Y1462595D03*
X390513Y1452895D03*
X395313D03*
X381913D03*
X383823Y1450295D03*
X388603D03*
X383823Y1455495D03*
X388603D03*
X381903Y1459995D03*
X381213Y1462595D03*
X387913Y1452895D03*
X384513D03*
X381903Y1465195D03*
X395384Y1519250D03*
X390082Y1549178D03*
X395359Y1546519D03*
X389290Y1561250D03*
X387939Y1565534D03*
X389276Y1568413D03*
X391526Y1582373D03*
X393322Y1573347D03*
X394521Y1575891D03*
X388784Y1581801D03*
X394915Y1590018D03*
X393005Y1592304D03*
X381711Y1593842D03*
X381607Y1590393D03*
X388445Y1585898D03*
X389333Y1598816D03*
X387805Y1607802D03*
Y1604802D03*
Y1610802D03*
X387325Y1627212D03*
X387805Y1617302D03*
Y1614802D03*
X394824Y1629713D03*
X394000Y1621500D03*
X389824Y1629713D03*
X389000Y1621500D03*
X384824Y1629713D03*
X381350Y1649000D03*
Y1642900D03*
Y1645800D03*
X385502Y1667154D03*
X394824Y1667120D03*
X389824D03*
X382115Y1661545D03*
X387324Y1680495D03*
X392324D03*
X382642Y1680979D03*
X385068Y1683502D03*
X410701Y99148D03*
X406243Y100076D03*
X410500Y104883D03*
X403734Y110326D03*
Y118976D03*
X397426Y112815D03*
Y116215D03*
X410400Y107383D03*
X399264Y121144D03*
X400426Y112815D03*
Y116215D03*
X402606Y129465D03*
Y126065D03*
X405606Y125815D03*
Y129715D03*
X403141Y144300D03*
Y148300D03*
X410678Y159140D03*
X408603Y152278D03*
X411299Y212096D03*
X396977Y216685D03*
X400000Y220300D03*
X411940Y240501D03*
X396237Y315507D03*
X410000Y304000D03*
X399625Y479119D03*
X402184Y466469D03*
X404743Y494451D03*
X410984Y496649D03*
X402184Y507101D03*
X406184Y507900D03*
X403657Y546915D03*
X403133Y565415D03*
X408550Y557850D03*
X404871Y567338D03*
X403157Y569415D03*
X403381Y573516D03*
X410111Y572608D03*
X407543Y577415D03*
Y580490D03*
X408445Y687531D03*
X401880Y696220D03*
X404771Y698670D03*
X397793Y701715D03*
X410645Y691931D03*
X410545Y688931D03*
X408445Y690431D03*
Y693331D03*
X410415Y709137D03*
X409165Y711637D03*
Y714237D03*
Y716837D03*
X403062Y704375D03*
X397793Y704223D03*
X404555Y715290D03*
Y712749D03*
X400782Y707900D03*
X399991Y776560D03*
X397491Y768928D03*
Y771428D03*
Y773928D03*
Y776428D03*
X397487Y766428D03*
X399991Y771560D03*
Y769060D03*
X399987Y766428D03*
X399991Y774060D03*
X397487Y779060D03*
Y781560D03*
Y786560D03*
Y784060D03*
X399991D03*
Y779060D03*
Y781560D03*
X403347Y1266162D03*
Y1268662D03*
X400847Y1266162D03*
X398347D03*
X400847Y1268662D03*
X398347D03*
X403347Y1271162D03*
Y1273662D03*
X400847Y1271162D03*
X398347D03*
X400847Y1273662D03*
X398347D03*
X403347Y1276162D03*
Y1278662D03*
X400847D03*
Y1276162D03*
X398347Y1278662D03*
Y1276162D03*
X398447Y1281262D03*
Y1283762D03*
X400947Y1281180D03*
Y1283680D03*
X403447D03*
Y1281180D03*
X400947Y1288680D03*
X403447D03*
X400947Y1286180D03*
X403447D03*
X398447Y1286262D03*
Y1288762D03*
X398461Y1291319D03*
X403461D03*
X400961D03*
X407412Y1358587D03*
X400645Y1353385D03*
X408087Y1355430D03*
X404599Y1353830D03*
X407337Y1352862D03*
X400645Y1355893D03*
X397656Y1349708D03*
X410002Y1375093D03*
X405978Y1377794D03*
X401953Y1380494D03*
X397187Y1383354D03*
X403913Y1452895D03*
X397223Y1450295D03*
X402003D03*
X397223Y1455495D03*
X402003D03*
X401313Y1452895D03*
X397913D03*
X408683Y1478082D03*
Y1486682D03*
Y1491482D03*
X406083Y1479992D03*
Y1484772D03*
Y1493392D03*
X408683Y1480682D03*
Y1484082D03*
Y1500082D03*
X406083Y1498172D03*
X401583Y1504872D03*
X408683Y1497482D03*
Y1494082D03*
X404147Y1509654D03*
X401536Y1516120D03*
Y1512220D03*
X397206Y1516953D03*
Y1511953D03*
Y1514453D03*
X397891Y1521436D03*
X401659Y1519845D03*
X404686Y1516120D03*
Y1512220D03*
X410650Y1509469D03*
X408150D03*
X407836Y1512220D03*
Y1516120D03*
X407561Y1519845D03*
X404699Y1521436D03*
Y1523953D03*
X398782Y1531073D03*
X401282D03*
X403782D03*
X410108Y1535680D03*
X398201Y1548563D03*
X408895Y1553644D03*
X405331Y1548928D03*
X410672Y1561170D03*
X410851Y1557434D03*
X407198Y1564990D03*
X401249Y1564422D03*
X405758Y1557900D03*
X402912Y1558011D03*
X396452Y1577738D03*
X403163Y1579357D03*
X403004Y1582457D03*
X408925Y1573805D03*
Y1576805D03*
X400905Y1596091D03*
X404669Y1594317D03*
X403417Y1606224D03*
X403837Y1609056D03*
Y1612456D03*
X399447Y1612609D03*
X399801Y1606376D03*
X406697Y1604207D03*
X403848Y1615354D03*
X408856Y1623435D03*
X400380Y1621500D03*
X405436Y1620268D03*
X406343Y1613847D03*
X405747Y1623350D03*
X400623Y1629772D03*
X406075Y1641000D03*
X404640Y1637425D03*
X397822Y1629615D03*
X409552Y1633606D03*
X405342Y1628611D03*
X404661Y1634139D03*
X412000Y1647177D03*
X399824Y1667120D03*
X409000Y1667025D03*
X403844Y1665769D03*
X405000Y1683500D03*
X401666Y1677925D03*
X405000Y1675000D03*
X397324Y1680495D03*
X409000Y1683500D03*
X417535Y49379D03*
X424975Y54762D03*
X417025D03*
X413949Y69270D03*
X416549Y66365D03*
Y71665D03*
X427300Y71300D03*
X425555Y92014D03*
X417617Y79073D03*
X425555Y82014D03*
X423376Y96664D03*
X419900Y96620D03*
X414100D03*
X424084Y110839D03*
X411952Y132751D03*
Y123051D03*
X414486Y127579D03*
Y124179D03*
X417486D03*
Y127579D03*
X424086Y123023D03*
X422890Y136700D03*
X424086Y133265D03*
X412370Y188210D03*
X411800Y220200D03*
X411610Y223140D03*
X424815Y217646D03*
X422936Y223501D03*
X419299Y212096D03*
X423299D03*
X422936Y228147D03*
Y232793D03*
X420115Y230323D03*
Y240501D03*
Y235442D03*
Y226323D03*
X411940Y235442D03*
X420288Y244184D03*
X412715Y254165D03*
X423730Y249570D03*
X412715Y251165D03*
Y262165D03*
Y270165D03*
Y258165D03*
Y266165D03*
X419617Y308000D03*
X424151Y453174D03*
X413425Y479042D03*
X415984Y466392D03*
X418543Y494374D03*
X415984Y507024D03*
X424784Y496572D03*
X419984Y508000D03*
X411500Y510800D03*
X412771Y524820D03*
X414402Y544690D03*
X424026Y681221D03*
X423351Y684378D03*
X424101Y686946D03*
X412711Y687301D03*
Y690201D03*
X414712Y699440D03*
Y696540D03*
X411765Y711637D03*
Y714237D03*
Y716837D03*
X420158Y748643D03*
X415158Y756175D03*
Y751175D03*
Y753675D03*
X417658Y748643D03*
X415158D03*
Y761175D03*
X420158D03*
X417658D03*
X415158Y758675D03*
X420162Y751143D03*
Y753643D03*
Y756143D03*
X417662D03*
Y753643D03*
Y751143D03*
X420162Y758643D03*
X417662D03*
X415158Y771175D03*
X420158Y763675D03*
Y766175D03*
X417658Y768675D03*
X415158D03*
X417658Y763675D03*
Y766175D03*
X415158Y763675D03*
Y766175D03*
X424024Y1267144D03*
X414247Y1268662D03*
X416747D03*
X419247D03*
X424024Y1269644D03*
Y1272144D03*
X414247Y1281180D03*
Y1283680D03*
X416747D03*
Y1281180D03*
Y1271162D03*
X414247D03*
X416747Y1278662D03*
Y1276162D03*
X419247Y1278662D03*
Y1276162D03*
Y1273662D03*
X416747D03*
X414247Y1278662D03*
Y1276162D03*
Y1273662D03*
X419361Y1283719D03*
Y1281219D03*
X419247Y1271162D03*
X424024Y1274644D03*
X414247Y1288680D03*
X416747D03*
X414247Y1286180D03*
X416747D03*
X419361Y1288719D03*
Y1291219D03*
X414361D03*
X416861D03*
X419361Y1286219D03*
X423521Y1311969D03*
X421091Y1311219D03*
X419673Y1325571D03*
Y1322971D03*
Y1328171D03*
X422273Y1322971D03*
Y1325571D03*
Y1328171D03*
X424333Y1331447D03*
X421023Y1330671D03*
X421315Y1354276D03*
Y1351376D03*
X421205Y1348586D03*
Y1345686D03*
X418675Y1352166D03*
Y1349266D03*
X414132Y1372234D03*
X424686Y1484280D03*
Y1479500D03*
X411283Y1479992D03*
Y1484772D03*
Y1493392D03*
X424686Y1506080D03*
Y1501300D03*
X411283Y1498172D03*
X415862Y1503715D03*
X425631Y1517138D03*
X425087Y1510708D03*
X422587D03*
X423131Y1517138D03*
X412086Y1512076D03*
Y1514576D03*
X422557Y1530595D03*
X420057D03*
X412862Y1526750D03*
X417098Y1533764D03*
Y1531264D03*
X422557Y1537595D03*
X420057D03*
X417098Y1536411D03*
X418157Y1549295D03*
X423157Y1541795D03*
Y1544295D03*
X415657Y1541795D03*
X418157Y1546795D03*
Y1544295D03*
Y1541795D03*
X415657Y1549295D03*
Y1546795D03*
Y1544295D03*
X420657Y1541795D03*
Y1544295D03*
Y1546795D03*
Y1549295D03*
X417098Y1538911D03*
X424115Y1548199D03*
Y1551099D03*
X421697Y1551844D03*
X421683Y1565312D03*
X421108Y1560235D03*
X424488Y1565400D03*
X413540Y1556646D03*
X424616Y1560086D03*
X414202Y1559396D03*
X421294Y1557729D03*
X419254Y1566828D03*
X421059Y1569168D03*
X427081Y1581620D03*
X421277Y1571923D03*
X416163Y1594450D03*
X422007Y1592330D03*
X413396Y1594597D03*
X410991Y1597002D03*
X425469Y1595433D03*
X422069D03*
X413100Y1607600D03*
X418293Y1607495D03*
X423379Y1607675D03*
X413200Y1612700D03*
X423439Y1612407D03*
X411515Y1599649D03*
X419277Y1600725D03*
X413100Y1617900D03*
X418500Y1618000D03*
X423349Y1617857D03*
X416962Y1634123D03*
X415437Y1636382D03*
X417365Y1630495D03*
X420765D03*
X421347Y1636668D03*
X414500Y1639075D03*
X417365Y1627695D03*
X420765D03*
X411500Y1653500D03*
X417441Y1643946D03*
X423500Y1652500D03*
X411448Y1650598D03*
X420000Y1668075D03*
Y1664925D03*
X411500Y1657500D03*
X417000Y1683500D03*
Y1675000D03*
X413000Y1683500D03*
X415500Y1672500D03*
X422596Y1737117D03*
X439535Y49379D03*
X430564Y56348D03*
X430500Y72900D03*
X433673Y73960D03*
X428149Y65016D03*
X429685Y88657D03*
X431359Y82589D03*
X436090Y116007D03*
Y120007D03*
Y124007D03*
Y132007D03*
Y128007D03*
X440090Y132007D03*
X429997Y166400D03*
X441997D03*
X433997D03*
X437997D03*
X436103Y158594D03*
X437997Y170701D03*
X433997D03*
X431299Y204145D03*
X438200Y212096D03*
X431299Y212095D03*
X433124Y222253D03*
Y225205D03*
X439299Y220046D03*
X440029Y240381D03*
X434420Y239930D03*
X437440Y237270D03*
X442710Y237990D03*
X435710Y250340D03*
X440710D03*
X426947Y320749D03*
X433277Y471970D03*
X427225Y478965D03*
X429784Y466315D03*
X426208Y468977D03*
X436226Y475526D03*
X432343Y494297D03*
X439500Y484000D03*
X437084Y501865D03*
X429784Y506947D03*
X442084Y511870D03*
X427500Y510553D03*
X426011Y524888D03*
X440591Y684518D03*
X436130Y683281D03*
X436062Y686575D03*
X430793Y686423D03*
X426839Y685978D03*
X430793Y683915D03*
X437555Y697490D03*
Y694949D03*
X433782Y690100D03*
X439411Y733527D03*
X436811D03*
X439411Y736147D03*
X436811D03*
X436411Y738717D03*
X439011D03*
X436411Y743917D03*
X439011D03*
X436411Y741317D03*
X439011D03*
X430958Y748643D03*
X433458D03*
X433462Y751143D03*
Y753643D03*
Y756143D03*
X430962D03*
Y753643D03*
Y751143D03*
Y758643D03*
X427615Y1282917D03*
Y1275417D03*
Y1280417D03*
Y1277917D03*
X427251Y1291747D03*
X436903Y1285694D03*
Y1289694D03*
X431830Y1311240D03*
X438561Y1321622D03*
X432561D03*
X435561D03*
X439524Y1462595D03*
X437624Y1452895D03*
X430924Y1462595D03*
X439534Y1450295D03*
Y1455495D03*
X437614Y1459995D03*
X432834D03*
X436924Y1462595D03*
X433524D03*
X440224Y1452895D03*
X437614Y1465195D03*
X432834D03*
X427286Y1477590D03*
Y1486190D03*
X429886Y1484280D03*
Y1479500D03*
X427286Y1483590D03*
Y1480190D03*
Y1499490D03*
X429886Y1506080D03*
Y1501300D03*
X427286Y1507990D03*
X436140Y1499320D03*
X427286Y1501990D03*
Y1505390D03*
X437661Y1518040D03*
Y1514420D03*
Y1510800D03*
X428746Y1521727D03*
X438153Y1528731D03*
X427730Y1536606D03*
X427704Y1531902D03*
Y1529402D03*
X426704Y1523331D03*
Y1526731D03*
X439935Y1532600D03*
X438732Y1546977D03*
X427730Y1539106D03*
X430027Y1546795D03*
Y1544295D03*
X432527Y1541795D03*
Y1549295D03*
Y1546795D03*
Y1544295D03*
X430027Y1541795D03*
Y1549295D03*
X435027D03*
Y1546795D03*
Y1544295D03*
Y1541795D03*
X427527Y1549295D03*
Y1546795D03*
Y1544295D03*
Y1541795D03*
X426620Y1551844D03*
X437736Y1544392D03*
X431923Y1565790D03*
X432051Y1560635D03*
X437910Y1553910D03*
X430239Y1581726D03*
X433440Y1581700D03*
X429947Y1594398D03*
X426688Y1598003D03*
X439283Y1608704D03*
X436776Y1610394D03*
X430500Y1605835D03*
X432559Y1627500D03*
X439404Y1615146D03*
X431664Y1624342D03*
X436776Y1613794D03*
X433012Y1621612D03*
X430500Y1613709D03*
X428000Y1640500D03*
X434500Y1641500D03*
X431000Y1640500D03*
X432000Y1650000D03*
X428500D03*
X436925Y1649500D03*
X441182Y77125D03*
X450102Y87011D03*
X455502Y88711D03*
X452102D03*
X445267Y82124D03*
X450414Y92384D03*
X443014D03*
X448414Y94684D03*
X445014D03*
X452948Y104003D03*
X444090Y116007D03*
X452090D03*
X448090D03*
X452090Y124007D03*
Y132007D03*
X444090D03*
X452090Y128007D03*
X445997Y166400D03*
X453997D03*
X449997D03*
X448038Y158659D03*
X445997Y170701D03*
X441997D03*
X449997D03*
X448499Y212036D03*
X443299Y212095D03*
X453783Y217646D03*
X456231Y227764D03*
X443299Y220046D03*
X447299D03*
X456231Y232883D03*
X443400Y247880D03*
X455422Y244103D03*
X444310Y243370D03*
X446710Y249340D03*
X448852Y283318D03*
X452480Y273420D03*
X454518Y280793D03*
X447840Y275970D03*
X441320Y298170D03*
Y295170D03*
Y304170D03*
Y310170D03*
Y301170D03*
Y307170D03*
Y313170D03*
Y316170D03*
X442297Y474442D03*
X453269Y478388D03*
X449496Y474009D03*
X446547Y480123D03*
X449760Y497240D03*
X443683Y502256D03*
X448024Y505345D03*
X452084Y511870D03*
X447084D03*
X457084D03*
X453723Y526558D03*
X444441Y565549D03*
X452565Y652837D03*
X440845Y668731D03*
Y665831D03*
X445111Y662701D03*
X442945Y664331D03*
X440845Y662931D03*
X443045Y667331D03*
X445111Y665601D03*
X447212Y671640D03*
X444165Y687037D03*
X441565D03*
X443235Y684637D03*
X447212Y674540D03*
X444325Y702449D03*
X441725D03*
X444165Y689637D03*
Y692237D03*
X441565D03*
Y689637D03*
X446591Y716837D03*
X443991D03*
X446591Y719437D03*
X443991D03*
X446686Y726660D03*
Y729160D03*
Y731660D03*
X449190Y726528D03*
Y729028D03*
Y731528D03*
X451690D03*
Y729028D03*
Y726528D03*
X446686Y724028D03*
X449186D03*
X451686D03*
Y741660D03*
X449186D03*
Y739160D03*
Y736660D03*
X451686Y739160D03*
Y736660D03*
X446686Y741660D03*
Y736660D03*
Y739160D03*
Y734160D03*
X449190Y734028D03*
X451690D03*
X443764Y1179395D03*
X448688Y1305947D03*
X449440Y1308386D03*
X450220Y1310834D03*
X451083Y1313347D03*
X441561Y1321622D03*
X444561D03*
X452089Y1316074D03*
X452936Y1318775D03*
X453823Y1321436D03*
X454603Y1324033D03*
X454909Y1326721D03*
X446224Y1452895D03*
X444314Y1450295D03*
Y1455495D03*
X443624Y1452895D03*
X451024Y1472295D03*
X452934Y1469695D03*
Y1474895D03*
X453624Y1472295D03*
X447587Y1552567D03*
X446810Y1565020D03*
X446910Y1562098D03*
X440846Y1576526D03*
X446653Y1573264D03*
X441931Y1581662D03*
X443590Y1593880D03*
X441460Y1596020D03*
X444128Y1604200D03*
Y1600200D03*
X450500Y1612450D03*
X448776Y1622266D03*
Y1617166D03*
Y1619766D03*
X446182Y1625555D03*
X450180Y1614950D03*
X452500Y1637559D03*
X447387Y1641441D03*
X445800Y1633200D03*
Y1636000D03*
X454099Y1649575D03*
X446000Y1650000D03*
X444596Y1737117D03*
X461535Y49379D03*
X468228Y70016D03*
X462653Y72525D03*
X457502Y87011D03*
X464456Y93101D03*
X457056D03*
X462456Y95101D03*
X459056D03*
X470010Y141070D03*
X465997Y166400D03*
X457997D03*
X461997D03*
X457931Y212703D03*
X464051Y224799D03*
X471371Y227764D03*
X461931Y212703D03*
X468574Y213104D03*
X471371Y222764D03*
X464440Y218253D03*
X460567Y225205D03*
X463402Y229970D03*
X457731Y237588D03*
X463653Y237390D03*
X460567Y235442D03*
X460624Y240953D03*
Y230323D03*
Y244103D03*
X462703Y242342D03*
X463240Y244980D03*
X465699Y282833D03*
X456720Y285158D03*
X457248Y280143D03*
Y282643D03*
X470243Y285693D03*
X469323Y306273D03*
X462093Y310123D03*
X467943Y311563D03*
X465153Y310123D03*
X467893Y308643D03*
X458873Y310173D03*
X455813D03*
X467644Y353417D03*
X467545Y356864D03*
X465925Y489925D03*
X460441Y499842D03*
X457424Y497978D03*
X468638Y514096D03*
X465766Y524991D03*
X458725Y524480D03*
X470331Y566632D03*
X465331D03*
X467831D03*
X462831D03*
X467831Y569132D03*
X470331D03*
X459931Y566632D03*
X457431D03*
X462831Y569132D03*
X457431D03*
X459931D03*
X465331D03*
X470331Y576132D03*
X467831Y571632D03*
X465331D03*
X467831Y576132D03*
X465331D03*
X470331Y571632D03*
X462831D03*
Y576132D03*
X457431Y571632D03*
Y574132D03*
X459931Y571632D03*
Y574132D03*
X457431Y576632D03*
X459931D03*
X462831Y598514D03*
X467831D03*
X470331D03*
X465331D03*
X457711D03*
X460211D03*
X462831Y601014D03*
X467831D03*
X470331D03*
X465331D03*
X457711D03*
X460211D03*
X469046Y657062D03*
X456426Y656621D03*
X469955Y672890D03*
X463193Y659315D03*
X468462Y661975D03*
X463193Y661823D03*
X455751Y659778D03*
X459239Y661378D03*
X469955Y670349D03*
X456501Y662346D03*
X466182Y665500D03*
X462490Y731528D03*
Y726528D03*
Y729028D03*
X464990D03*
Y726528D03*
X467486Y724028D03*
X464986D03*
X462486D03*
X467490Y726660D03*
X466324Y1462595D03*
X457724D03*
X459634Y1459995D03*
X464414D03*
X466334Y1450295D03*
X464424Y1452895D03*
X466334Y1455495D03*
X463724Y1462595D03*
X470424Y1452895D03*
X460324Y1462595D03*
X467024Y1452895D03*
X459624Y1472295D03*
X459634Y1465195D03*
X464414D03*
X457714Y1469695D03*
Y1474895D03*
X457024Y1472295D03*
X462215Y1581510D03*
X462753Y1641289D03*
X457240Y1629500D03*
X459500Y1659000D03*
X462500Y1655500D03*
X468350Y1645351D03*
X461000Y1650000D03*
X467500Y1651500D03*
X457000Y1650000D03*
X466041Y1664913D03*
X468075Y1662500D03*
X470463Y1670038D03*
X464925Y1662500D03*
X470309Y1689000D03*
X470500Y1674075D03*
X467500Y1678500D03*
X462500Y1701000D03*
X468575Y1704000D03*
X462500Y1697000D03*
X468500Y1708500D03*
X466000Y1714575D03*
X467416Y1724808D03*
X469975D03*
X464734Y1730518D03*
X468575Y1731000D03*
X466596Y1737117D03*
X462500Y1733500D03*
X483535Y49379D03*
X478949Y60029D03*
Y55135D03*
Y64975D03*
X479400Y90574D03*
Y94574D03*
Y97574D03*
Y110930D03*
X479465Y119644D03*
Y115644D03*
X470895Y128020D03*
X478295D03*
X482255Y127322D03*
Y135722D03*
X476295Y130020D03*
X472895D03*
X482255Y133222D03*
Y129822D03*
X479465Y123644D03*
X479630Y141942D03*
X482380D03*
X486682Y197516D03*
X483800Y189400D03*
X480200Y191900D03*
X483467Y209755D03*
X480700Y208200D03*
X480715Y211099D03*
X471371Y231764D03*
Y235764D03*
X483227Y233000D03*
X483800Y270440D03*
X487620Y270400D03*
X479870D03*
X483823Y285893D03*
X480323Y291023D03*
X474808Y291492D03*
X482893Y291293D03*
X474691Y306073D03*
X471743Y304923D03*
X473643Y308683D03*
X471003Y311563D03*
X470953Y308643D03*
X484063Y313956D03*
X479148Y315502D03*
X484063Y305669D03*
X480773Y307153D03*
X471015Y527283D03*
X475731Y566632D03*
X473231D03*
Y569132D03*
X475731D03*
Y574132D03*
Y571632D03*
X473231Y574132D03*
Y571632D03*
X475731Y576632D03*
X473231D03*
X473445Y642231D03*
X477711Y639101D03*
X475645Y640831D03*
X473445Y639331D03*
X475545Y637831D03*
X473445Y636431D03*
X477711Y636201D03*
X475415Y658037D03*
X479812Y645240D03*
Y648140D03*
X476765Y660537D03*
X474165D03*
X476765Y663137D03*
X474165D03*
X476765Y665737D03*
X474165D03*
X479058Y702660D03*
Y700160D03*
X484062Y700028D03*
Y702528D03*
X481562D03*
Y700028D03*
X479058Y697528D03*
X481558D03*
X484058D03*
X479058Y717660D03*
Y707660D03*
Y712660D03*
Y710160D03*
Y715160D03*
X484058Y710160D03*
Y712660D03*
X481558Y710160D03*
Y712660D03*
X484058Y715160D03*
X481558D03*
X484062Y707528D03*
X481562D03*
X479058Y705160D03*
X484062Y705028D03*
X481562D03*
X484524Y1462595D03*
X471114Y1450295D03*
X473024Y1452895D03*
X471114Y1455495D03*
X477824Y1472295D03*
X484514Y1469695D03*
X479734D03*
X484514Y1474895D03*
X479734D03*
X483824Y1472295D03*
X480424D03*
X478500Y1655500D03*
X483500Y1658500D03*
X479500Y1666500D03*
X473500Y1662500D03*
X477538Y1661463D03*
X476000Y1680000D03*
X478500Y1701000D03*
X474000Y1704000D03*
X478500Y1697000D03*
Y1714500D03*
Y1710500D03*
Y1733500D03*
X491849Y55095D03*
Y60105D03*
X497885Y51315D03*
X491849Y64965D03*
X487590Y105969D03*
X494810D03*
X492300Y121389D03*
X500674Y116261D03*
X487880Y131442D03*
X496280D03*
X492300Y124389D03*
X490380Y131442D03*
X493780D03*
X488580Y141942D03*
X485780D03*
X500136Y141058D03*
X494200Y158800D03*
X495500Y161386D03*
X497700Y157200D03*
X492685Y160994D03*
X495232Y189516D03*
X486682Y193516D03*
X495232D03*
Y185516D03*
X486682Y189516D03*
X498776Y209285D03*
X486600Y200800D03*
X495232Y197516D03*
X496831Y205030D03*
X491635Y212577D03*
X498776Y213285D03*
X500269Y225071D03*
X499380Y222510D03*
X491635Y225970D03*
X494144Y221370D03*
X487442Y223377D03*
X500209Y227881D03*
X491635Y215652D03*
X487541Y226527D03*
X500209Y233000D03*
X491859D03*
X500119Y243173D03*
X500209Y238119D03*
X491577Y238120D03*
X488908Y242754D03*
X491577Y243240D03*
X485962Y290679D03*
X488076Y350420D03*
X487827Y354017D03*
X490419Y362138D03*
X488260Y418980D03*
X498500Y419425D03*
X488405Y578572D03*
X501171Y630087D03*
X489026Y630121D03*
X495793Y632815D03*
X495839Y635323D03*
X488351Y633278D03*
X491839Y634878D03*
X489101Y635846D03*
X498782Y639000D03*
X497362Y700028D03*
Y702528D03*
X494862D03*
Y700028D03*
X499858Y697528D03*
X497358D03*
X494858D03*
X499862Y700160D03*
Y702660D03*
X494862Y705028D03*
X497362D03*
X499862Y705160D03*
X499824Y1452895D03*
X491224D03*
X493124Y1462595D03*
X497914Y1450295D03*
X493134D03*
X497914Y1455495D03*
X493134D03*
X486434Y1459995D03*
X491214D03*
X490524Y1462595D03*
X497224Y1452895D03*
X487124Y1462595D03*
X493824Y1452895D03*
X486424Y1472295D03*
X486434Y1465195D03*
X491214D03*
X488596Y1737117D03*
X512658Y46613D03*
X510810Y49193D03*
X510815Y69562D03*
X504796Y86320D03*
X502815Y106984D03*
X512654Y94967D03*
X516020Y105370D03*
Y109270D03*
X514240Y97146D03*
X500836Y119092D03*
X511140Y109829D03*
X513772Y121220D03*
X502750Y111276D03*
X503000Y135600D03*
X509346Y125842D03*
X514418Y145171D03*
X503161Y149895D03*
X514418Y149171D03*
Y141171D03*
Y153171D03*
X507945Y160919D03*
X503161Y154620D03*
X500600Y157100D03*
X513360Y169190D03*
X505315Y196944D03*
X503507Y185516D03*
X511771Y199576D03*
X504351Y202776D03*
X508238Y199506D03*
X512076Y206404D03*
X511170Y224930D03*
X515151Y220166D03*
X511684Y221219D03*
X504351Y215901D03*
X508001Y220166D03*
X511170Y227882D03*
X501718Y240558D03*
X508723Y280721D03*
X510223Y289035D03*
X507698D03*
Y297090D03*
X510223D03*
X515223Y289035D03*
X507698Y305145D03*
X510223D03*
X510606Y314124D03*
X508081D03*
X515223Y313200D03*
Y305145D03*
X501500Y433000D03*
X506745Y608131D03*
X508945Y606731D03*
X506745Y602331D03*
Y605231D03*
X508845Y603731D03*
X511011Y602101D03*
Y605001D03*
X513012Y611040D03*
X510065Y626437D03*
X508715Y623937D03*
X507465Y626437D03*
X513012Y613940D03*
X510065Y629037D03*
X507465D03*
X510065Y631637D03*
X507465D03*
X514771Y643138D03*
X501062Y635475D03*
X502555Y646390D03*
Y643849D03*
X514162Y673428D03*
Y665928D03*
Y668428D03*
Y670928D03*
X514158Y663428D03*
Y678460D03*
Y683460D03*
Y680960D03*
Y675960D03*
X509572Y865327D03*
X513572D03*
X506261Y865338D03*
X511324Y1462595D03*
X513234Y1459995D03*
X513924Y1462595D03*
X513224Y1472295D03*
X504624D03*
X513234Y1465195D03*
X511314Y1469695D03*
X506534D03*
X511314Y1474895D03*
X506534D03*
X510624Y1472295D03*
X507224D03*
X518843Y23788D03*
X524713Y33346D03*
X529713D03*
X516058Y46613D03*
X517915Y42257D03*
X525001D03*
X519765Y40328D03*
X523165D03*
X517896Y49193D03*
X524763Y49189D03*
X517907Y69507D03*
X524993D03*
X519743Y71436D03*
X523143D03*
X523831Y95445D03*
Y102931D03*
X516020Y102870D03*
X519240Y94967D03*
X526460Y100895D03*
Y97495D03*
X517640Y97146D03*
X521420Y109829D03*
X516020Y111770D03*
X524993Y125914D03*
X522418Y137171D03*
X526418D03*
X518418D03*
X522418Y153171D03*
X521618Y165428D03*
X519268Y167428D03*
X519601Y196117D03*
X518691Y191846D03*
X519579Y207435D03*
X517314Y200449D03*
X517973Y211998D03*
X519248Y280721D03*
X516723D03*
X521773D03*
X520273Y289035D03*
X517748D03*
X522798D03*
X520273Y313200D03*
X517748D03*
X520273Y305145D03*
X517748D03*
X515523Y335613D03*
X529317Y403784D03*
X524680Y417602D03*
X529095Y452049D03*
X522831Y443712D03*
X522326Y596021D03*
X529153Y598735D03*
X529235Y601543D03*
X521651Y599178D03*
X525139Y600778D03*
X522401Y601746D03*
X521771Y643138D03*
X528771D03*
X529962Y673428D03*
Y670928D03*
Y668428D03*
Y665928D03*
X516662Y673428D03*
Y670928D03*
Y668428D03*
Y665928D03*
X527462Y673428D03*
Y665928D03*
Y668428D03*
Y670928D03*
X516658Y663428D03*
X527458D03*
X529958D03*
X516658Y678460D03*
Y683460D03*
Y680960D03*
X527458Y678460D03*
X516658Y675960D03*
X527458D03*
X529958D03*
Y678460D03*
X526474Y851934D03*
Y849434D03*
X516572Y865327D03*
X517009Y856494D03*
X523074Y853439D03*
Y855939D03*
X528220Y1167366D03*
X517118D03*
X520818D03*
X519924Y1462595D03*
X526624Y1452895D03*
X518024D03*
X519934Y1450295D03*
X524714D03*
X519934Y1455495D03*
X524714D03*
X518014Y1459995D03*
X517324Y1462595D03*
X524024Y1452895D03*
X520624D03*
X518014Y1465195D03*
X528940Y1548260D03*
X539120Y31340D03*
X540843Y23788D03*
X535117Y31340D03*
X544721Y42892D03*
X542723Y39562D03*
X539721Y42862D03*
X533918Y47067D03*
X537318D03*
X532070Y49193D03*
X539156D03*
X532080Y69507D03*
X539166D03*
X541003Y71436D03*
X544403D03*
X543277Y88632D03*
X538210Y90618D03*
X540615Y88213D03*
X538620Y93289D03*
X535170Y108730D03*
Y117630D03*
Y111230D03*
Y115130D03*
X530567Y125914D03*
X543408Y133912D03*
X538166Y130698D03*
X530418Y145171D03*
Y137171D03*
Y149171D03*
Y141171D03*
X541675Y146874D03*
Y151470D03*
Y142021D03*
Y137169D03*
X530418Y153171D03*
X541675Y156195D03*
X533442Y164428D03*
X531280Y210922D03*
X532222Y207849D03*
X541013Y222441D03*
X540695Y217874D03*
X534277Y224930D03*
X538613Y227882D03*
X537051Y211959D03*
X538613Y238119D03*
X534277Y230441D03*
Y235560D03*
X538613Y233000D03*
X533097Y246780D03*
X539217Y245270D03*
X538567Y294777D03*
X543780Y294168D03*
X541808Y289743D03*
X544628Y291633D03*
Y289133D03*
X542813Y319173D03*
X542983Y334531D03*
X533211Y350838D03*
X533543Y404130D03*
X530729Y398634D03*
X532000Y426500D03*
X543170Y434737D03*
X534455Y428561D03*
X544844Y439701D03*
X543500Y463500D03*
X531753Y453232D03*
X540616Y463486D03*
X534471Y595987D03*
X538067Y592652D03*
X542071Y593089D03*
X535855Y612290D03*
X539657Y607658D03*
X534362Y601375D03*
X535855Y609749D03*
X532082Y604900D03*
X534271Y643138D03*
X540106Y657325D03*
X534962Y670960D03*
Y665960D03*
Y668460D03*
X532462D03*
Y665960D03*
Y670960D03*
Y673460D03*
Y663460D03*
X534962D03*
Y673460D03*
Y675960D03*
X532462D03*
X531921Y1167366D03*
X540024Y1452895D03*
X531424D03*
X533334Y1450295D03*
X538114D03*
X533334Y1455495D03*
X538114D03*
X544814Y1459995D03*
X537424Y1452895D03*
X534024D03*
X544794Y1478082D03*
Y1491482D03*
Y1486682D03*
X542194Y1479992D03*
Y1484772D03*
Y1493392D03*
X544794Y1480682D03*
Y1484082D03*
Y1500082D03*
X537694Y1504872D03*
X542194Y1498172D03*
X544794Y1497482D03*
Y1494082D03*
X543947Y1516120D03*
Y1512220D03*
X543672Y1519845D03*
X540810Y1521436D03*
X533317Y1511953D03*
Y1514453D03*
Y1516953D03*
X531495Y1519250D03*
X537770Y1519845D03*
X537647Y1516120D03*
Y1512220D03*
X534002Y1521436D03*
X540797Y1516120D03*
Y1512220D03*
X540810Y1523953D03*
X543759Y1536882D03*
X540193Y1531073D03*
X537693D03*
X535193D03*
X541259Y1536882D03*
X543719Y1549295D03*
Y1546795D03*
X541219D03*
Y1549295D03*
X538719D03*
Y1546795D03*
X531339Y1546481D03*
X532596Y1737117D03*
X553620Y31048D03*
X549919D03*
X554984Y45312D03*
X553651Y48842D03*
X546350Y39562D03*
X550972Y42902D03*
X561721Y41024D03*
X556351Y41538D03*
X548610Y48082D03*
Y57990D03*
X546253Y69507D03*
X553340D03*
X547821Y79372D03*
X551721D03*
X555176Y71436D03*
X558576D03*
X545935Y77516D03*
X553821D03*
X559069Y105385D03*
Y101985D03*
X546400Y120700D03*
X553780Y118740D03*
X557091Y114382D03*
X550505D03*
X552105Y112203D03*
X555505D03*
X553780Y121240D03*
Y127140D03*
Y124640D03*
X549800Y147000D03*
X553300Y164500D03*
X556811Y152742D03*
X559484Y156667D03*
X553757Y160075D03*
X547196Y195256D03*
Y190256D03*
X550196D03*
X554196D03*
X553578Y193541D03*
X547196Y199256D03*
X550553Y200304D03*
Y197778D03*
X548963Y218441D03*
X553100Y227700D03*
X549248Y237652D03*
Y230441D03*
X555567Y236970D03*
X549248Y234152D03*
X559774Y243176D03*
X546800Y262800D03*
X552699Y291833D03*
X557243Y294693D03*
X561808Y300492D03*
X556323Y315273D03*
X558743Y313923D03*
X545873Y319173D03*
X549093Y319123D03*
X558003Y320563D03*
X554943D03*
X552153Y319123D03*
X554893Y317643D03*
X557953D03*
X562030Y372872D03*
X551044Y373085D03*
X551200Y377650D03*
X562208Y383668D03*
Y404717D03*
X550573Y399586D03*
Y403586D03*
X562208Y397599D03*
X550573Y414274D03*
X549854Y406298D03*
X547529Y425411D03*
X551591Y443665D03*
X548856Y440452D03*
X552510Y446490D03*
X547751Y472678D03*
X550925Y475178D03*
X553360Y477822D03*
X555727Y479968D03*
X558379Y482096D03*
X556993Y616406D03*
X550993D03*
X553993D03*
X547993D03*
X549957Y658478D03*
Y661478D03*
X551171Y1167678D03*
X558690Y1226149D03*
X558986Y1462595D03*
X545931Y1451344D03*
X559090Y1452185D03*
X558876Y1454905D03*
Y1458305D03*
X546253Y1454107D03*
Y1457507D03*
X555348Y1477590D03*
Y1486190D03*
X552748Y1484280D03*
Y1479500D03*
X557948Y1484280D03*
Y1479500D03*
X547394Y1479992D03*
Y1484772D03*
Y1493392D03*
X555348Y1483590D03*
Y1480190D03*
Y1499490D03*
X552748Y1506080D03*
Y1501300D03*
X557948Y1506080D03*
Y1501300D03*
X555348Y1507990D03*
X547394Y1498172D03*
X555348Y1501990D03*
Y1505390D03*
X556965Y1521561D03*
X548197Y1514641D03*
X550471Y1513584D03*
Y1511031D03*
X548197Y1512088D03*
X556642Y1529389D03*
X554715Y1531564D03*
X548119Y1530595D03*
X550619D03*
X550540Y1526910D03*
X556197Y1536687D03*
X554766Y1523331D03*
Y1526731D03*
X550939Y1536646D03*
X559215Y1530596D03*
X556197Y1539187D03*
X546219Y1549295D03*
Y1541795D03*
Y1546795D03*
Y1544295D03*
X548719Y1549295D03*
Y1546795D03*
Y1541795D03*
Y1544295D03*
X551219D03*
Y1541795D03*
X549674Y1538890D03*
X558089Y1541795D03*
Y1544295D03*
Y1546795D03*
Y1549295D03*
X555589Y1541795D03*
Y1549295D03*
Y1546795D03*
Y1544295D03*
X549759Y1551844D03*
X552177Y1551099D03*
X554682Y1551844D03*
X552177Y1548199D03*
X554596Y1737117D03*
X562843Y23788D03*
X565185Y47982D03*
X575331Y47672D03*
X564431Y45132D03*
X573191Y42912D03*
X570209Y47982D03*
X566771Y41133D03*
X564794Y58911D03*
X567997Y58992D03*
X573763Y58688D03*
X562331Y48438D03*
X560426Y69507D03*
X561248Y106985D03*
Y100399D03*
X570860Y118310D03*
Y121310D03*
X565210Y125819D03*
X570860Y127510D03*
Y124710D03*
X568472Y149226D03*
X563951Y153640D03*
Y148640D03*
Y160644D03*
Y157494D03*
X572003Y164356D03*
Y169415D03*
X564603Y197778D03*
Y200304D03*
X573911Y212196D03*
X568804Y221926D03*
X571427Y217771D03*
X569004Y225496D03*
Y228571D03*
X568736Y235821D03*
X562475Y242721D03*
X565093Y242640D03*
X567323Y300023D03*
X570823Y294893D03*
X572447Y299470D03*
X569893Y300293D03*
X561691Y315073D03*
X571063Y314669D03*
X560643Y317683D03*
X568573Y321993D03*
X566148Y324502D03*
X567773Y316153D03*
X562208Y387227D03*
Y376427D03*
Y401158D03*
X568433Y415846D03*
X575913Y413287D03*
X570863Y410728D03*
X572121Y437038D03*
X564407Y431638D03*
X563230Y426508D03*
X568709Y434227D03*
X563575Y448425D03*
X569464Y462140D03*
X563763Y486350D03*
X567297Y487551D03*
X560890Y484664D03*
X569923Y490726D03*
X559993Y616406D03*
X561346Y1228547D03*
X564669Y1238907D03*
X564283Y1231192D03*
X565537Y1235456D03*
X574200Y1229900D03*
X567127Y1249536D03*
X561580Y1242740D03*
X571271Y1259488D03*
X570775Y1263008D03*
X567586Y1462595D03*
X574286Y1452895D03*
X565686D03*
X567596Y1450295D03*
X572376D03*
X567596Y1455495D03*
X572376D03*
X565676Y1459995D03*
X560896D03*
X564986Y1462595D03*
X571686Y1452895D03*
X561586Y1462595D03*
X568286Y1452895D03*
X565676Y1465195D03*
X560896D03*
X562860Y1499360D03*
X565723Y1510800D03*
Y1514420D03*
Y1518040D03*
X566215Y1528731D03*
X568779Y1546333D03*
X560589Y1541795D03*
Y1544295D03*
Y1546795D03*
Y1549295D03*
X563089Y1541795D03*
Y1549295D03*
Y1546795D03*
Y1544295D03*
X567214Y1544299D03*
X584843Y23788D03*
X578621Y45112D03*
X591938Y46308D03*
X576478Y58563D03*
X591070Y60201D03*
X586953Y63441D03*
X583685Y70678D03*
X586390Y69291D03*
X579561Y73090D03*
X585000Y82500D03*
X584752Y86248D03*
X590501Y86909D03*
X578454Y88926D03*
X580098Y96439D03*
X586394Y95948D03*
X591811Y97421D03*
X576510Y125819D03*
X580485Y133056D03*
Y130530D03*
X583485D03*
Y133056D03*
X589203Y164356D03*
X581203D03*
X585685Y178125D03*
X589203Y169415D03*
X585685Y174975D03*
X581203Y169415D03*
X575425Y189835D03*
X582124Y194150D03*
X588244Y208991D03*
X575440Y200785D03*
X582002Y197481D03*
X588554Y221277D03*
X585296Y222954D03*
X577859Y212196D03*
X582766Y225496D03*
Y221421D03*
X588554Y217277D03*
Y225277D03*
X580343Y217771D03*
X588215Y214079D03*
X588554Y229277D03*
X578172Y231393D03*
X588968Y240112D03*
X582816Y228696D03*
X587140Y257630D03*
X575524Y261171D03*
X581099Y263680D03*
X586157Y366827D03*
X585585Y372052D03*
X581985Y379577D03*
X577482Y383668D03*
X581985Y387227D03*
Y376427D03*
Y390377D03*
Y404308D03*
X587710Y399287D03*
X581985Y401158D03*
X587710Y404287D03*
X588723Y415846D03*
Y423949D03*
X575917Y421390D03*
X588798Y435949D03*
X588723Y427949D03*
X588742Y431976D03*
X577845Y437151D03*
X587829Y445138D03*
X575345Y437151D03*
X580523Y435949D03*
X583505Y457925D03*
X575075Y451263D03*
X582390Y464701D03*
X589507Y462559D03*
X583116Y476745D03*
X587812Y474353D03*
X577801Y466000D03*
X587500Y470308D03*
X587795Y479631D03*
X581335Y472100D03*
X586000Y808862D03*
X581421Y813078D03*
X588500Y812093D03*
X578830Y1218588D03*
X585501Y1229536D03*
X578830Y1238075D03*
X578071Y1244425D03*
X584271Y1263988D03*
X588630Y1255075D03*
X583630D03*
X585786Y1462595D03*
X587696Y1459995D03*
X588386Y1462595D03*
X587686Y1472295D03*
X579086D03*
X587696Y1465195D03*
X580996Y1469695D03*
X585776D03*
X580996Y1474895D03*
X585776D03*
X585086Y1472295D03*
X581686D03*
X575649Y1552567D03*
X576596Y1737117D03*
X602837Y32910D03*
X595682Y44842D03*
X603064Y44523D03*
X599284Y32866D03*
X603064Y48023D03*
X599284Y42481D03*
X597956Y48047D03*
X606585Y43529D03*
X593920Y49193D03*
X601073Y60301D03*
X603379Y70512D03*
X603350Y73642D03*
X599295Y100747D03*
X606183Y95873D03*
X597275Y94922D03*
X596068Y106798D03*
X591385Y109165D03*
X602328Y109062D03*
X597769Y153640D03*
Y148640D03*
X603344Y139131D03*
X593975Y164440D03*
X598552Y159066D03*
X599678Y175534D03*
X600793Y193185D03*
X596661Y188775D03*
X590300Y190660D03*
X600161Y188776D03*
X593661D03*
X604293Y193185D03*
X597293Y193186D03*
X602294Y203786D03*
X595563Y239128D03*
X598968Y238878D03*
X603526Y229995D03*
X597050Y281950D03*
X595723Y289721D03*
X594698Y298035D03*
X597223D03*
X602223D03*
X603723Y289721D03*
X594698Y314145D03*
X597223D03*
X594698Y306090D03*
X597223D03*
X602223Y314145D03*
X597223Y322200D03*
X594698D03*
X602223D03*
X598414Y372357D03*
X598208Y387227D03*
Y376427D03*
Y383668D03*
X600520Y401728D03*
X603283Y419744D03*
X599884Y412000D03*
X593758Y415850D03*
X599164Y432209D03*
X603326Y429530D03*
X590326Y445015D03*
X594430Y463600D03*
X592529Y461563D03*
X598496Y451421D03*
X597500Y483500D03*
X602833Y791746D03*
X597071Y799268D03*
X592612Y805986D03*
X590710Y804192D03*
X603743Y794963D03*
X595619Y806084D03*
X600337Y800649D03*
X596821Y802688D03*
X592572Y809088D03*
X592761Y1220688D03*
X594330Y1238075D03*
X595671Y1245688D03*
X595598Y1251075D03*
X599659Y1241734D03*
X596621Y1240366D03*
X603947Y1258575D03*
X595947D03*
X596944Y1270115D03*
X595532Y1262668D03*
X605771Y1263098D03*
X598112Y1264365D03*
X594991Y1285582D03*
Y1289582D03*
X594386Y1462595D03*
X592476Y1459995D03*
X594396Y1450295D03*
X599176D03*
X592486Y1452895D03*
X601086D03*
X594396Y1455495D03*
X599176D03*
X591786Y1462595D03*
X598486Y1452895D03*
X595086D03*
X592476Y1465195D03*
X598596Y1737117D03*
X606843Y23788D03*
X618427Y43432D03*
X613025Y42725D03*
X612608Y35961D03*
X618732Y39913D03*
X619563Y49193D03*
X615587Y45611D03*
X615180Y49193D03*
X606263Y60301D03*
X616815Y60277D03*
X611579D03*
X615190Y70533D03*
Y74533D03*
X615772Y106645D03*
X618182Y100786D03*
X610009Y100748D03*
X614282Y95873D03*
X617420Y119640D03*
X619240Y123232D03*
X605853Y149640D03*
Y145640D03*
X618600Y160750D03*
X605853Y152140D03*
Y155131D03*
X618801Y165356D03*
Y175534D03*
Y170415D03*
X613207Y182229D03*
X616357D03*
X608794Y203786D03*
X607834Y222611D03*
X612414Y227041D03*
X604718Y257562D03*
X607868D03*
X618705Y285305D03*
X608773Y289721D03*
X609798Y298035D03*
X607273D03*
X606248Y289721D03*
X604748Y298035D03*
X609798Y314145D03*
X607273D03*
X604748D03*
X621585Y331358D03*
X609798Y322200D03*
X607273D03*
X604748D03*
X615464Y347522D03*
X607871Y359262D03*
X611118Y359462D03*
X613565Y350819D03*
X619035Y369542D03*
X617985Y379577D03*
X613482Y383668D03*
X617985Y387227D03*
Y376427D03*
Y398578D03*
Y390377D03*
Y401728D03*
X606032Y418968D03*
X610935Y409996D03*
X617985Y407346D03*
X617998Y415546D03*
X606811Y429528D03*
X605796Y425585D03*
X615075Y443000D03*
X612969Y447260D03*
X611925Y437000D03*
X605769Y442593D03*
X615903Y493474D03*
X608886Y494400D03*
X618680Y511302D03*
X618957Y502306D03*
X616457D03*
X611896Y535178D03*
Y538178D03*
X607091Y528168D03*
X613761Y790418D03*
X616171Y780364D03*
X618645Y783582D03*
X609402Y788678D03*
X615571Y788448D03*
X606559Y796116D03*
X612871Y1248488D03*
X612947Y1252075D03*
X609159Y1240234D03*
X608940Y1265991D03*
X610551Y1262988D03*
X612447Y1258575D03*
X605771Y1267098D03*
X618761Y1266988D03*
X615591Y1282038D03*
X618761Y1278668D03*
X606619Y1278302D03*
X610551Y1269888D03*
X616037Y1367166D03*
X608148Y1373890D03*
X616654Y1382864D03*
X616615Y1386232D03*
X616629Y1375082D03*
X616527Y1390732D03*
X619286Y1452895D03*
X612586Y1462595D03*
X614496Y1459995D03*
X619276D03*
X618586Y1462595D03*
X615186D03*
X614486Y1472295D03*
X605886D03*
X614496Y1465195D03*
X619276D03*
X612576Y1469695D03*
X607796D03*
X612576Y1474895D03*
X607796D03*
X611886Y1472295D03*
X608486D03*
X613948Y1641600D03*
X628843Y23788D03*
X624937Y44019D03*
X620390Y36794D03*
X624634Y48104D03*
X628410Y45381D03*
X624689Y58262D03*
X627881Y57120D03*
X622207Y60573D03*
X627496Y74977D03*
X626642Y71365D03*
X622156Y95948D03*
X626208Y100861D03*
X630900Y118920D03*
X628885Y127057D03*
X630810Y122089D03*
X625574Y150177D03*
X625532Y146982D03*
X625553Y152683D03*
X625755Y168917D03*
X626372Y193431D03*
X626824Y182080D03*
X623605Y219277D03*
X620455D03*
X623605Y228777D03*
X620455D03*
X631505Y284355D03*
X622705Y285305D03*
X633805Y302289D03*
X626473Y305338D03*
X626388Y330536D03*
X631694Y341300D03*
X626555Y343929D03*
X624133Y346520D03*
X626596Y360196D03*
X636500Y360362D03*
X634105Y404652D03*
X635058Y399700D03*
X627925Y421966D03*
X624760Y424569D03*
X631075Y429888D03*
X632281Y441904D03*
X622174Y438925D03*
X622197Y436116D03*
X622800Y461348D03*
X627880Y455310D03*
X620800Y474700D03*
X621916Y465088D03*
X632996Y478309D03*
X627364Y478823D03*
X632984Y471462D03*
X621309Y483346D03*
X630758Y505874D03*
X633406Y497964D03*
X624381Y503765D03*
X631510Y510613D03*
X624718Y553428D03*
X633882Y587488D03*
X634794Y590504D03*
X635567Y671774D03*
X634288Y766646D03*
X631557Y773359D03*
X631741Y770318D03*
X633406Y1358576D03*
X634776Y1353739D03*
X630477Y1350109D03*
Y1353109D03*
X632695Y1366157D03*
Y1372257D03*
X624795Y1373257D03*
X632695Y1378257D03*
X624976Y1378313D03*
X630195Y1384263D03*
X625195Y1383457D03*
X622352Y1393285D03*
X630523Y1392554D03*
X635849Y1393376D03*
X627886Y1452895D03*
X621186Y1462595D03*
X625976Y1450295D03*
X621196D03*
X625976Y1455495D03*
X621196D03*
X625286Y1452895D03*
X621886D03*
X632686Y1472295D03*
X627958Y1654114D03*
X629808Y1668863D03*
X633422Y1673488D03*
X631643Y1670946D03*
X635491Y1696845D03*
X635472Y1711808D03*
X620596Y1737117D03*
X644963Y29143D03*
X648487Y44106D03*
X638490Y33340D03*
X642157Y44695D03*
X639876Y49193D03*
X651042Y41545D03*
X647987Y47606D03*
X646042Y41545D03*
X640653Y58274D03*
X645151Y69507D03*
X640670Y74369D03*
X650846Y74074D03*
X647938Y83795D03*
X644202Y84604D03*
X642607Y94116D03*
X642394Y131172D03*
X645752Y134988D03*
X643800Y166053D03*
X641111Y158300D03*
X641006Y161829D03*
X643800Y161862D03*
X640923Y169388D03*
X649871Y181942D03*
X642481Y184862D03*
X641276Y187557D03*
X643012Y201913D03*
Y199313D03*
X637804Y235371D03*
X640804D03*
X637804Y239371D03*
X640804D03*
X640084Y227113D03*
X637804Y243371D03*
X640804D03*
X646285Y297171D03*
X642171Y311280D03*
X641013Y324459D03*
X640922Y360342D03*
X639000Y364862D03*
X642128Y363279D03*
X636579Y366941D03*
X642617Y389299D03*
X637314Y393680D03*
X640317Y391085D03*
X640784Y395957D03*
X651279Y404458D03*
X634566Y407848D03*
X635200Y415425D03*
X637160Y405449D03*
X635243Y433518D03*
X637432Y428935D03*
X642406Y427614D03*
X644673Y425816D03*
X639211Y433862D03*
Y438191D03*
X635449Y449797D03*
X639002Y449862D03*
X639500Y442362D03*
X637504Y454352D03*
X639313Y452361D03*
X635690Y461441D03*
X648500Y453862D03*
X635640Y464257D03*
X644849Y495582D03*
X647576Y497964D03*
X643053Y502891D03*
X640076Y497964D03*
X635906D03*
X636614Y512597D03*
X642310Y535773D03*
X649592Y540078D03*
X639757Y533440D03*
X636055Y528605D03*
X646151Y535227D03*
X648314Y571169D03*
X644414D03*
X642816Y574185D03*
X639482Y587488D03*
X645446Y587300D03*
X638694Y590504D03*
X650258Y590316D03*
X646358D03*
X650228Y674761D03*
X634529Y674890D03*
X640129D03*
X643649Y674781D03*
X646446Y674643D03*
X640271Y763488D03*
X636551Y767900D03*
X642804Y766871D03*
X636247Y771179D03*
X635092Y1277102D03*
X642436Y1350877D03*
X646236D03*
X638436D03*
X638695Y1366157D03*
X644795D03*
X643395Y1372857D03*
X638695Y1378257D03*
X644795D03*
X634995Y1384457D03*
X638053Y1384491D03*
X647401Y1384160D03*
X643563Y1392581D03*
X647445Y1392605D03*
X647986Y1462595D03*
X646086Y1452895D03*
X639386Y1462595D03*
X647996Y1450295D03*
Y1455495D03*
X641296Y1459995D03*
X646076D03*
X645386Y1462595D03*
X641986D03*
X648686Y1452895D03*
X641286Y1472295D03*
X641296Y1465195D03*
X646076D03*
X639376Y1469695D03*
X634596D03*
X639376Y1474895D03*
X634596D03*
X638686Y1472295D03*
X635286D03*
X639907Y1570443D03*
X639132Y1573127D03*
X645180Y1597800D03*
X645190Y1595050D03*
X649153Y1625726D03*
X649297Y1623185D03*
X640520Y1635483D03*
X640242Y1639951D03*
X647630Y1641522D03*
X643128Y1639803D03*
X649266Y1650126D03*
X642151Y1649961D03*
X642716Y1653939D03*
X637218Y1654131D03*
X644905Y1646491D03*
X639800Y1646650D03*
X643074Y1668505D03*
X647574D03*
X647460Y1662952D03*
X640846Y1665189D03*
X639284Y1683049D03*
X647500Y1682850D03*
X650158Y1687189D03*
X643041Y1682883D03*
X647500Y1674805D03*
X640600D03*
X643300D03*
X639391Y1700695D03*
X640690Y1703547D03*
X651143Y1706162D03*
X644975Y1725236D03*
X635210Y1721545D03*
Y1718395D03*
X641825Y1730516D03*
X640865Y1719684D03*
X642596Y1737117D03*
X650843Y23788D03*
X649585Y29298D03*
X657921Y30864D03*
X654117Y29099D03*
X663703Y32574D03*
X654582Y45448D03*
X653570Y58363D03*
X654590Y49193D03*
X661676D03*
X660928Y60707D03*
X651014Y60820D03*
X656600Y60537D03*
X661601Y75562D03*
X656501Y69662D03*
X656427Y75431D03*
X661588Y69662D03*
X660775Y78330D03*
X653821Y90326D03*
X658228Y88447D03*
X666200Y84862D03*
X654037Y93241D03*
Y96041D03*
X651950Y99890D03*
X658949Y139840D03*
X662881Y149912D03*
Y146912D03*
X649441Y177003D03*
X653700Y179962D03*
X659881Y208262D03*
Y205762D03*
Y210762D03*
X662781Y207862D03*
Y205362D03*
Y210362D03*
X663915Y234476D03*
X659918Y326503D03*
X658905Y341885D03*
X661019Y344831D03*
X663551Y346035D03*
X662740Y375240D03*
X649500Y373500D03*
Y382500D03*
X652425Y385924D03*
X659095Y381020D03*
X649495Y385118D03*
X659354Y393938D03*
X653523Y399987D03*
X652954Y394284D03*
X661297Y409857D03*
X662016Y417897D03*
X660885Y412588D03*
X652027Y415930D03*
X654273Y419251D03*
X662000Y433862D03*
X654248Y422500D03*
X657535Y422694D03*
X666000Y429844D03*
X651432Y433532D03*
X662000Y429844D03*
X652763Y427866D03*
X653013Y443200D03*
X664170Y445711D03*
X651384Y445252D03*
X661546Y444497D03*
X662000Y449862D03*
X654441Y449618D03*
X662000Y437844D03*
X657622Y437819D03*
X651853Y439518D03*
X653449Y458542D03*
X662570Y461547D03*
Y457755D03*
X662000Y473862D03*
X666000Y473844D03*
X650268Y479141D03*
X651072Y465939D03*
X654000Y465824D03*
X654014Y473862D03*
X662000Y465862D03*
X651114Y473884D03*
X662000Y469862D03*
X653266Y479106D03*
X663374Y484295D03*
X652380Y482390D03*
X657520Y486330D03*
X649500Y490260D03*
X660215Y483109D03*
X658758Y497964D03*
X655917D03*
X649771Y505736D03*
X661718Y498056D03*
X651406Y501178D03*
X650404Y496102D03*
X652576Y497964D03*
X659398Y516260D03*
X659425Y521075D03*
X665689Y550294D03*
X649922Y545610D03*
X655967Y544375D03*
X658642Y573893D03*
X649936Y574185D03*
X661718Y579932D03*
X653368Y581468D03*
X655572Y572603D03*
X656832Y577205D03*
X662992Y598660D03*
X651046Y587300D03*
X658613Y599534D03*
X660062Y672761D03*
X654676Y674806D03*
X662628Y674761D03*
X660175Y679517D03*
X657428Y674761D03*
X663580Y731509D03*
X658947Y767300D03*
Y771100D03*
X662600Y1311502D03*
Y1308502D03*
X657836Y1350877D03*
X653836D03*
X650036D03*
X661685Y1367283D03*
X661713Y1373981D03*
X653376Y1365793D03*
X661719Y1363394D03*
X651973Y1363038D03*
X653149Y1372500D03*
X653101Y1369862D03*
X652651Y1375308D03*
X661813Y1370081D03*
X653117Y1378037D03*
X655702Y1391107D03*
X659559Y1391027D03*
X651877Y1391074D03*
X653999Y1426757D03*
Y1423357D03*
X655873Y1428844D03*
X652189Y1421276D03*
X654686Y1452895D03*
X659486D03*
X661396Y1450295D03*
X652776D03*
X661396Y1455495D03*
X652776D03*
X652086Y1452895D03*
X662086D03*
X663160Y1511734D03*
Y1516734D03*
Y1519234D03*
Y1521734D03*
X660660Y1519234D03*
X661710Y1514148D03*
X663160Y1524234D03*
X662374Y1548563D03*
X654005Y1548999D03*
X666092Y1553650D03*
X660953Y1539998D03*
X663133Y1543744D03*
Y1541244D03*
Y1538744D03*
X660953Y1542498D03*
X657430Y1555228D03*
X659532Y1546519D03*
X651840Y1567752D03*
X664246Y1561009D03*
X661731Y1561083D03*
X661156Y1626532D03*
X650966Y1618934D03*
X651870Y1612986D03*
X650753Y1615912D03*
X660542Y1638169D03*
X657392Y1628137D03*
X652274Y1630366D03*
X650895Y1648115D03*
X653542Y1649059D03*
X660058Y1648889D03*
X660389Y1654481D03*
X654712Y1653813D03*
X664315Y1654484D03*
X655914Y1668744D03*
X650074Y1668505D03*
X658648Y1664169D03*
X655683Y1664212D03*
X653154Y1683265D03*
X664159Y1674844D03*
X661528Y1674865D03*
X650200Y1674805D03*
X659436Y1694697D03*
X658491Y1688965D03*
X649464Y1691180D03*
X649526Y1709274D03*
X663997Y1703111D03*
X659557Y1714672D03*
X658759Y1707147D03*
X659028Y1710047D03*
X660930Y1730277D03*
X662153Y1727718D03*
X659673Y1722174D03*
X661845Y1717340D03*
X654508Y1728000D03*
X654527Y1718229D03*
X662120Y1720404D03*
X659673Y1732836D03*
X672843Y23788D03*
X670613Y42464D03*
X674013D03*
X668739Y45262D03*
X677594Y36205D03*
X675887Y45262D03*
X677476Y33317D03*
X680864Y38190D03*
X666506Y32750D03*
X674647Y38190D03*
X677305Y57947D03*
X675849Y49193D03*
X668763D03*
X665469Y58525D03*
X666411Y69507D03*
X674036Y74522D03*
X678664Y88080D03*
X673751Y78092D03*
X675509Y88173D03*
X667941Y80142D03*
X677561Y118409D03*
X677738Y115428D03*
X665651Y147692D03*
X673011Y169021D03*
X673691Y200672D03*
X673301Y211332D03*
X679035Y204181D03*
X678226Y215771D03*
X674348Y218580D03*
X666552Y346115D03*
X677111Y345662D03*
X672111D03*
X674611D03*
X676800Y369362D03*
X672800D03*
X680800Y380280D03*
X672800Y382362D03*
X676000Y378100D03*
X667090Y385150D03*
X671753Y397936D03*
X671500Y390862D03*
X679940Y400933D03*
X675500Y398862D03*
Y390862D03*
X670018Y418690D03*
X669929Y407999D03*
X666000Y433862D03*
Y425862D03*
X670000Y429864D03*
Y433844D03*
Y425894D03*
X666000Y437844D03*
X670000Y442362D03*
Y437844D03*
X666000Y442362D03*
X670000Y446362D03*
X679062Y455140D03*
X670000Y457844D03*
X666000Y453844D03*
Y457862D03*
X670000Y453844D03*
X666000Y461862D03*
X670000Y469824D03*
Y465844D03*
Y477862D03*
X678000D03*
X670000Y482862D03*
X678000D03*
X681213Y495658D03*
X669955Y495468D03*
X672699Y506907D03*
X664741Y506865D03*
X680488Y504784D03*
X671500Y529500D03*
X665425Y537000D03*
X664454Y574896D03*
X665774Y571762D03*
X666192Y598660D03*
X679047Y678733D03*
X673287Y733156D03*
X674123Y736083D03*
X667101Y736071D03*
X672505Y766871D03*
X674552Y1342488D03*
Y1351988D03*
Y1349488D03*
Y1344988D03*
X665167Y1380836D03*
Y1376836D03*
X673671Y1431922D03*
X675272Y1434525D03*
X668086Y1452895D03*
X666176Y1450295D03*
Y1455495D03*
X665486Y1452895D03*
X672856Y1478082D03*
Y1486682D03*
Y1491482D03*
X675112Y1479602D03*
X675456Y1484772D03*
Y1493392D03*
X670256Y1479992D03*
Y1484772D03*
Y1493392D03*
X672856Y1484082D03*
Y1480682D03*
Y1500082D03*
X665756Y1504872D03*
X675456Y1498172D03*
X670256D03*
X666050Y1501670D03*
X672856Y1497482D03*
Y1494082D03*
X678386Y1507965D03*
X672684Y1522690D03*
X674687Y1519726D03*
X677871Y1522079D03*
X678345Y1516994D03*
X677871Y1519579D03*
X673174Y1515806D03*
X675505Y1512606D03*
X678339Y1510960D03*
X665800Y1530575D03*
X674620Y1535271D03*
X677871Y1524579D03*
X678121Y1528516D03*
X665832Y1527425D03*
X672715Y1526626D03*
Y1530526D03*
X674620Y1542125D03*
X672617Y1545089D03*
Y1538235D03*
X678350Y1567400D03*
X669524Y1560850D03*
X672163Y1560899D03*
X673729Y1556768D03*
X666978Y1560945D03*
X672810Y1571560D03*
X666610Y1571580D03*
X668133Y1625828D03*
X670839Y1620863D03*
X674894Y1629042D03*
X673982Y1639289D03*
X673960Y1633042D03*
X669648Y1640917D03*
X665802Y1652337D03*
X674486Y1647842D03*
X670803Y1654606D03*
X671068Y1650818D03*
X674908Y1644481D03*
X667971Y1654404D03*
X669178Y1646627D03*
X673480Y1662668D03*
X673548Y1669550D03*
X678117Y1662787D03*
X675497Y1687253D03*
X673359Y1674409D03*
X671631Y1690786D03*
X671001Y1696017D03*
X671798Y1704542D03*
X673113Y1716599D03*
X667701Y1705043D03*
X668058Y1720092D03*
X673113Y1727261D03*
X664596Y1737117D03*
X693672Y32684D03*
X686855Y43701D03*
X684611Y41857D03*
X682291Y46822D03*
X690476Y32684D03*
X692390Y46939D03*
X692466Y35950D03*
X687835Y37850D03*
X687345Y46940D03*
X679719Y59066D03*
X687018Y58357D03*
X683369Y58157D03*
X692390Y72692D03*
X690028Y70142D03*
X687665Y73202D03*
X685781Y70022D03*
X682946Y69982D03*
X682891Y72642D03*
X688552Y79166D03*
X681895Y82212D03*
X685783Y78768D03*
X680580Y79230D03*
X684954Y104968D03*
X681054Y104668D03*
X686891Y115868D03*
X687000Y119500D03*
X691058Y131408D03*
X685500Y124000D03*
X684521Y152482D03*
X688521D03*
X692521D03*
X679316Y209861D03*
X680576Y207105D03*
X681333Y212326D03*
X679737Y217763D03*
X682264Y224116D03*
X693621Y346169D03*
X680828Y363500D03*
X684800Y369362D03*
X680800D03*
X691484Y360643D03*
X691500Y382462D03*
X691547Y386834D03*
X685200Y377820D03*
X690105Y401775D03*
X687500Y390680D03*
X684794Y402268D03*
X683500Y390862D03*
X679500D03*
X688249Y405628D03*
X679862Y409320D03*
X692996Y418358D03*
X694299Y413108D03*
X689269Y410420D03*
X687612Y471850D03*
X691572Y465214D03*
X684800Y477862D03*
X687472Y486994D03*
X684680Y485942D03*
X684800Y481862D03*
X680187Y491243D03*
X690452Y486984D03*
X687310Y500453D03*
X682915Y500568D03*
X683000Y521500D03*
X687310Y522141D03*
X694111Y537881D03*
X679500Y526834D03*
X691496Y575081D03*
X690718Y578913D03*
X694996Y575081D03*
X689574Y572866D03*
X681352Y681305D03*
X688078Y675493D03*
X691417Y680382D03*
X685786Y680936D03*
X686509Y677440D03*
X688648Y767300D03*
Y771100D03*
X688076Y1297506D03*
Y1305206D03*
Y1300006D03*
Y1302606D03*
X687961Y1314308D03*
Y1320308D03*
Y1323308D03*
Y1317308D03*
X684868Y1327117D03*
X682348D03*
Y1339617D03*
X683052Y1342548D03*
X684868Y1329617D03*
X682348D03*
X684868Y1332117D03*
X682348D03*
X684868Y1334617D03*
X682348D03*
X684868Y1337117D03*
Y1339617D03*
X682348Y1337117D03*
X683052Y1352048D03*
Y1349548D03*
Y1345048D03*
X685187Y1368700D03*
Y1363500D03*
Y1366100D03*
X681289Y1418291D03*
X687577Y1425054D03*
X683391Y1420531D03*
X685448Y1423137D03*
X691587Y1429515D03*
X689538Y1427467D03*
X684350Y1448911D03*
X692376Y1438326D03*
X691943Y1441626D03*
X691276Y1455112D03*
X688540Y1455140D03*
X687040Y1452300D03*
X684280Y1452260D03*
X684603Y1507851D03*
X681517Y1508034D03*
X687529Y1508173D03*
X690683Y1508058D03*
X693395D03*
X688120Y1519601D03*
X680710Y1520284D03*
X683674Y1522287D03*
X693532Y1510755D03*
X690820D03*
X687666Y1510870D03*
X687711Y1513612D03*
X690751Y1513750D03*
X693655Y1513818D03*
X693587Y1516470D03*
X690752Y1516516D03*
X683666Y1515189D03*
X680717Y1513292D03*
X684557Y1510685D03*
X681563Y1510708D03*
X693495Y1519305D03*
X683352Y1530526D03*
Y1526526D03*
X682016Y1539067D03*
X679854Y1551492D03*
X679413Y1548843D03*
X680107Y1554330D03*
X681780Y1574280D03*
X684080Y1576500D03*
X686949Y1625144D03*
X689897Y1621781D03*
X692209Y1620037D03*
X691036Y1625508D03*
X686994Y1629077D03*
X688308Y1631636D03*
X693150Y1640773D03*
X693451Y1628733D03*
X686808Y1643500D03*
X685578Y1637479D03*
X683067Y1641758D03*
X682925Y1657116D03*
X686825Y1647430D03*
X686075Y1657082D03*
X679413Y1653251D03*
X685719Y1672391D03*
X685747Y1669303D03*
X693608Y1671081D03*
X685485Y1682259D03*
X685635Y1675310D03*
X691560Y1682047D03*
X693480Y1673940D03*
X692390Y1687594D03*
X694843Y23788D03*
X705666Y48010D03*
X701839Y45112D03*
X697678Y47132D03*
X697893Y35950D03*
X702481Y48327D03*
X698462Y60683D03*
X695220Y60455D03*
X704201Y72112D03*
X699476Y69982D03*
X701081Y72450D03*
X694752Y70212D03*
X707608Y69718D03*
X696701Y72462D03*
X698711Y86035D03*
X696371Y78512D03*
X696728Y81552D03*
Y84052D03*
X706721Y100462D03*
X702721Y102162D03*
X701221Y104862D03*
X697721D03*
X695721Y102162D03*
X694221Y104862D03*
X699221Y102162D03*
X699398Y123668D03*
X705570Y133760D03*
X704144Y122602D03*
X707243Y123946D03*
X704709Y125586D03*
X701927Y166535D03*
Y172441D03*
Y178346D03*
X704771Y179599D03*
Y171188D03*
Y167788D03*
X701927Y184252D03*
Y196063D03*
Y190157D03*
X704771Y182999D03*
Y194810D03*
Y191410D03*
X701927Y201968D03*
Y207874D03*
X704771Y206621D03*
Y203221D03*
X701927Y213779D03*
Y219685D03*
X704771Y218432D03*
Y215032D03*
X703486Y345507D03*
X699813Y344798D03*
X697400Y345761D03*
X706139Y345597D03*
X695500Y374362D03*
X699500D03*
X703500D03*
X696105Y364149D03*
X707500Y374362D03*
X707943Y360643D03*
X707500Y368862D03*
X696391Y368617D03*
X703477Y369409D03*
X695500Y382362D03*
X700300Y382502D03*
X707500Y382362D03*
Y386862D03*
X703700Y386832D03*
X695500Y386862D03*
X699500Y390862D03*
X695500D03*
X707500D03*
X703500Y401290D03*
Y390862D03*
X708584Y404868D03*
X699431Y513344D03*
X703774Y513463D03*
X707664Y513375D03*
X703788Y521817D03*
X696020Y521844D03*
X699800Y521760D03*
X708500Y517362D03*
X708210Y537816D03*
X696500Y529862D03*
X708500D03*
X704500D03*
X700790Y537732D03*
X704500Y537862D03*
X708500Y533862D03*
X696829Y533604D03*
X702657Y533695D03*
X697018Y537577D03*
X700500Y545862D03*
X704500Y555862D03*
Y545862D03*
X696283Y546530D03*
X710429Y545752D03*
X708500Y555451D03*
X701496Y580556D03*
X698996Y575081D03*
X704056D03*
X708056D03*
X704056Y583081D03*
X698996D03*
X697392Y601686D03*
X702806Y613264D03*
X696928Y613207D03*
X706387Y621686D03*
X705158Y645357D03*
X703781Y641805D03*
X704965Y638767D03*
X707833Y655325D03*
X704549Y655238D03*
X701233Y655355D03*
X708418Y650389D03*
X694812Y680188D03*
X698756Y676388D03*
X694837Y676412D03*
X701386Y679683D03*
X703584Y676544D03*
X708012Y676836D03*
X705697Y679533D03*
X697571Y730453D03*
X704598Y732288D03*
X700205Y733211D03*
X702553Y735811D03*
X702206Y766871D03*
X697483Y1297506D03*
Y1305206D03*
Y1300006D03*
Y1302606D03*
X697461Y1314008D03*
Y1320008D03*
Y1323008D03*
X702388Y1327127D03*
X699868D03*
X697461Y1317008D03*
X701771Y1342488D03*
X702388Y1337127D03*
Y1339627D03*
X699868Y1337127D03*
Y1339627D03*
X702388Y1329627D03*
X699868D03*
X702388Y1332127D03*
X699868D03*
X702388Y1334627D03*
X699868D03*
X701771Y1351988D03*
Y1349488D03*
Y1344988D03*
X699467Y1368710D03*
Y1363510D03*
Y1366110D03*
X705657Y1387027D03*
X701689Y1399545D03*
X697731Y1397513D03*
X706351Y1397588D03*
X705657Y1389568D03*
X695162Y1441350D03*
X694676Y1455112D03*
X697300Y1454140D03*
X696237Y1508149D03*
X699247Y1508062D03*
X699049Y1510892D03*
X696374Y1510846D03*
X696329Y1513818D03*
X696330Y1516584D03*
X699140Y1513772D03*
X707050Y1531700D03*
X709150Y1536250D03*
X706172Y1552082D03*
X703290Y1551700D03*
X707050Y1548400D03*
Y1541800D03*
X703290Y1545100D03*
X708500Y1560500D03*
X699500Y1559000D03*
X699610Y1568523D03*
Y1572523D03*
Y1576523D03*
Y1580523D03*
X708600Y1572523D03*
X710080Y1581683D03*
X699610Y1584523D03*
X699500Y1596500D03*
Y1588500D03*
X710360Y1589296D03*
X699000Y1604500D03*
X699500Y1599500D03*
Y1608500D03*
X709020Y1609101D03*
X706681Y1627361D03*
X699424Y1616627D03*
X695933Y1623460D03*
X709260Y1617903D03*
X701114Y1640345D03*
X705833Y1633568D03*
X702683Y1633715D03*
X706089Y1643411D03*
X705815Y1654918D03*
X703563Y1644116D03*
X702402Y1650469D03*
X703473Y1663001D03*
X700528Y1661468D03*
X697503Y1661331D03*
X703102Y1665554D03*
X695400Y1685887D03*
X705366Y1684064D03*
X698003Y1684692D03*
X723479Y-28508D03*
Y-19234D03*
Y-9234D03*
X716843Y23788D03*
X714471Y46670D03*
X724621Y40062D03*
X719821Y45862D03*
X714322Y56286D03*
X722581Y49182D03*
X717342Y57098D03*
X721163Y58588D03*
X714096Y73686D03*
X712717Y68541D03*
X719416Y68738D03*
Y74036D03*
X725016Y86952D03*
X720016D03*
X715745Y86300D03*
X712725Y84714D03*
X713420Y102060D03*
X712291Y106722D03*
X715934Y117488D03*
Y114588D03*
X712734Y117488D03*
Y114588D03*
X720434Y135088D03*
X717434D03*
X719934Y124488D03*
X723134D03*
X712341Y128093D03*
X719195Y172873D03*
Y177865D03*
X714203Y172873D03*
Y177865D03*
X710284Y169826D03*
X716699Y177087D03*
Y173687D03*
X719195Y196373D03*
X714203D03*
X719195Y184873D03*
Y189865D03*
X714203Y184873D03*
Y189865D03*
X716699Y189087D03*
Y185687D03*
X714203Y208207D03*
X719195D03*
Y201365D03*
X714203D03*
X716699Y200587D03*
Y197187D03*
Y209021D03*
X714203Y213199D03*
X719195D03*
X717021Y220862D03*
X716699Y212421D03*
X720328Y344824D03*
X714867Y344943D03*
X717712Y346103D03*
X715500Y374362D03*
X719500D03*
X723531Y368862D03*
X711500Y360862D03*
X719500D03*
X723500D03*
X711500Y374362D03*
X715500Y360862D03*
X719500Y368862D03*
X715500D03*
X711363Y369274D03*
X711500Y382362D03*
X723632Y386862D03*
X711500D03*
X715500D03*
X722500Y383162D03*
X723500Y390862D03*
X719500D03*
X715500D03*
X711500D03*
X716500Y521862D03*
X711617Y513531D03*
X724500Y517362D03*
X716500D03*
X720452Y513362D03*
X716716Y513368D03*
X720499Y533474D03*
X719841Y537348D03*
X712113Y537797D03*
X720500Y555862D03*
Y546211D03*
X712115Y541872D03*
X712409Y555413D03*
X710464Y557036D03*
X711556Y575081D03*
X722201Y579306D03*
X723483Y574890D03*
X714583Y587642D03*
Y590792D03*
X716181Y585562D03*
X715037Y603278D03*
Y606428D03*
X716313Y610134D03*
X719710Y612831D03*
X720787Y627907D03*
X716721D03*
X713280Y636897D03*
X713343Y633842D03*
X724000Y633906D03*
X725812Y654713D03*
X715371Y654726D03*
X712319Y654954D03*
X711702Y646533D03*
X711295Y665117D03*
X718129Y666725D03*
X722129D03*
X712164Y676912D03*
X712120Y680287D03*
X717515Y679833D03*
X720563Y679886D03*
X720613Y677040D03*
X723814Y736782D03*
X718349Y767300D03*
Y771100D03*
X721361Y1297546D03*
X711954D03*
X721361Y1305246D03*
Y1302646D03*
Y1300046D03*
X711954Y1305246D03*
Y1302646D03*
Y1300046D03*
X721339Y1314048D03*
X711839Y1314348D03*
X721339Y1323048D03*
Y1320048D03*
Y1317048D03*
X715828Y1327277D03*
X710488Y1327177D03*
X713008D03*
X711839Y1323348D03*
Y1320348D03*
Y1317348D03*
X713008Y1329877D03*
Y1332377D03*
Y1334877D03*
X715828Y1332877D03*
Y1330377D03*
X713008Y1337377D03*
Y1339877D03*
X715828Y1335377D03*
X710288Y1339677D03*
Y1337177D03*
X710221Y1342488D03*
X710288Y1334677D03*
Y1332177D03*
Y1329677D03*
X710221Y1351988D03*
Y1349488D03*
Y1344988D03*
X719186Y1403296D03*
X712419Y1398094D03*
X719861Y1400139D03*
X716373Y1398539D03*
X719111Y1397571D03*
X712419Y1400602D03*
X709430Y1394417D03*
X722141Y1405912D03*
X709551Y1406578D03*
X721916Y1414339D03*
Y1416939D03*
X722141Y1408412D03*
X712099Y1416973D03*
X714599D03*
X717099D03*
X712099Y1414473D03*
X714599D03*
X717099D03*
X709599Y1416973D03*
Y1414473D03*
X721916Y1428989D03*
Y1431589D03*
X717099Y1432773D03*
X712099D03*
X714599D03*
X717099Y1430273D03*
X712099D03*
X714599D03*
X709599Y1432773D03*
Y1427373D03*
Y1424873D03*
Y1430273D03*
Y1419873D03*
Y1422373D03*
X714259Y1447483D03*
X719471Y1467422D03*
X711671D03*
X714271D03*
X716871D03*
X720217Y1472287D03*
X717617D03*
X715017D03*
X720926Y1469814D03*
X718326D03*
X715726D03*
X713126D03*
X716067Y1474792D03*
X718667D03*
X721267D03*
X717358Y1477038D03*
X719958D03*
X716770Y1531459D03*
X715122Y1533378D03*
X716989Y1537249D03*
X713357Y1535212D03*
X715224Y1539083D03*
X713459Y1540917D03*
X714474Y1566333D03*
X724110Y1561825D03*
X714110Y1581475D03*
X714900Y1571273D03*
X721963Y1576932D03*
X719963Y1578932D03*
X721440Y1570963D03*
X719963Y1585790D03*
X721963Y1587790D03*
X723590Y1595323D03*
X718892Y1597152D03*
X714372Y1594679D03*
X723408Y1608740D03*
X722876Y1611343D03*
X720106Y1609542D03*
X717798Y1607335D03*
X713718Y1610235D03*
X717229Y1612376D03*
X718129Y1624330D03*
X722104Y1626253D03*
X715744Y1622842D03*
X722889Y1622491D03*
X711298Y1632534D03*
X718122Y1636332D03*
X718116Y1639129D03*
X717749Y1654921D03*
X709771Y1654927D03*
X713771D03*
X722480Y1657616D03*
X712354Y1682279D03*
X719117Y1682722D03*
X723181Y1688825D03*
X731743Y-30584D03*
X734996Y-30570D03*
X731758Y-28069D03*
X735011Y-28055D03*
X728718Y-29264D03*
X725925Y-25571D03*
Y-22171D03*
X731757Y-20090D03*
X735010Y-20104D03*
X728717Y-18895D03*
X734995Y-17589D03*
X731742Y-17575D03*
X735041Y-23025D03*
X735026Y-25540D03*
X735041Y-14717D03*
X735026Y-12202D03*
X734996Y-7172D03*
X728718Y-8478D03*
X735011Y-9687D03*
X731743Y-7158D03*
X731758Y-9673D03*
X738843Y23788D03*
X728981Y39872D03*
X736791Y39832D03*
X740101Y41162D03*
X736621Y45262D03*
X733315Y40862D03*
X728721Y43562D03*
X730131Y60757D03*
X736524Y58069D03*
X726789Y60562D03*
X738590Y59868D03*
X730785Y58068D03*
X728285Y58135D03*
X724645Y58362D03*
X734769Y60757D03*
X730958Y71014D03*
X738044Y71526D03*
X725769Y69737D03*
X736864Y74943D03*
X731864D03*
X727200Y73210D03*
X727944Y88972D03*
X731555Y83685D03*
X737009Y83169D03*
X729918Y90998D03*
X739824Y91052D03*
X734380Y80518D03*
X729380D03*
X727986Y101979D03*
X729900Y98090D03*
X727986Y105477D03*
X737624Y98858D03*
X734524Y98758D03*
X736650Y102350D03*
X735771Y94988D03*
X730660Y108484D03*
X735734Y111988D03*
X728734Y132088D03*
Y129288D03*
Y126388D03*
X724134Y141288D03*
X735500Y143000D03*
X724147Y345291D03*
X729211Y346379D03*
X726431Y346384D03*
X738773Y346716D03*
X734463Y346712D03*
X735500Y368862D03*
X734166Y360782D03*
X739500Y368862D03*
X727564D03*
X731500Y360862D03*
X731406Y374331D03*
X731500Y368862D03*
Y386862D03*
X739553Y388270D03*
X735500Y386862D03*
X727500D03*
X735500Y390862D03*
X727500D03*
X735500Y399330D03*
X738672Y494444D03*
X724500Y513362D03*
X732500D03*
X739185Y521394D03*
X728500Y521862D03*
X724500D03*
X728500Y513362D03*
X736609Y518426D03*
X728500Y529862D03*
X728576Y537476D03*
X736500Y537862D03*
X724336Y537527D03*
X728500Y533862D03*
X736500D03*
X732500D03*
X724433Y530870D03*
X732500Y529862D03*
X736647Y529772D03*
X732580Y537193D03*
X724697Y535053D03*
X728652Y545862D03*
X728695Y550943D03*
X736670Y545864D03*
X740500Y545862D03*
X724684Y545864D03*
X738260Y553625D03*
X724281Y553438D03*
X728714Y554190D03*
X732520Y545988D03*
X726720Y574910D03*
X736528Y576480D03*
Y579615D03*
X727253Y610689D03*
X724246Y627939D03*
X736362Y636854D03*
X724001Y636790D03*
X730770Y644218D03*
X733382Y633574D03*
X726952Y648667D03*
X729489Y666547D03*
X734442Y675695D03*
X730837Y678940D03*
X738486Y679139D03*
X724931Y678364D03*
X735316Y736742D03*
X725712Y734135D03*
X729391D03*
X727576Y736756D03*
X727448Y766871D03*
X735954Y1297546D03*
Y1305246D03*
Y1302646D03*
Y1300046D03*
X735739Y1314048D03*
Y1320048D03*
Y1317048D03*
X724788Y1327277D03*
X727501Y1327230D03*
X730021D03*
X735739Y1323048D03*
X727401Y1332430D03*
Y1329930D03*
Y1334930D03*
X724788Y1330377D03*
Y1332877D03*
X727401Y1339930D03*
Y1337430D03*
X724788Y1335377D03*
X730021Y1337230D03*
Y1339730D03*
Y1334730D03*
Y1329730D03*
Y1332230D03*
X730795Y1342444D03*
X727098Y1351977D03*
X730900Y1352131D03*
X727098Y1349077D03*
X730900Y1349231D03*
X730795Y1344944D03*
X734047Y1372880D03*
X731447D03*
X734047Y1370280D03*
Y1367680D03*
X731447D03*
Y1370280D03*
X732797Y1375380D03*
X738439Y1387127D03*
X728198Y1388026D03*
Y1385126D03*
X738230Y1402898D03*
X738439Y1389668D03*
X734767Y1396986D03*
Y1394086D03*
X732567Y1392586D03*
X732667Y1395586D03*
X730501Y1397216D03*
Y1394316D03*
X734767Y1391186D03*
X735418Y1426122D03*
Y1423122D03*
Y1420122D03*
X732418Y1426122D03*
Y1423122D03*
Y1420122D03*
X735453Y1525368D03*
X737551Y1524008D03*
X727325Y1563400D03*
X727571Y1558353D03*
X736782Y1555496D03*
X733782D03*
X727571Y1555353D03*
X733782Y1567496D03*
X736782D03*
X730782D03*
X733782Y1558496D03*
Y1561496D03*
X736782Y1558496D03*
Y1561496D03*
X733782Y1564496D03*
X736782D03*
X730782Y1558496D03*
Y1561496D03*
Y1564496D03*
X726475Y1571293D03*
X723963Y1578932D03*
X730782Y1570496D03*
X736782D03*
X733782D03*
X733380Y1577231D03*
X727780Y1582361D03*
Y1577231D03*
X723963Y1585790D03*
X726550Y1599358D03*
X733380Y1587491D03*
X727780D03*
X736998Y1597463D03*
X730998D03*
X733998D03*
X736998Y1594463D03*
X730998D03*
X733998D03*
X736998Y1600463D03*
X730998D03*
X733998D03*
Y1603663D03*
X736998D03*
X733998Y1606663D03*
X736998D03*
X730998Y1603663D03*
Y1606663D03*
X730647Y1623629D03*
X727320Y1623698D03*
X736723Y1623938D03*
X731119Y1647997D03*
X735642Y1648537D03*
X734925Y1657826D03*
X730302Y1658050D03*
X726302Y1658022D03*
X738370Y1677909D03*
X730347Y1682902D03*
X725638Y1682890D03*
X736001Y1695509D03*
X728454Y1690491D03*
X732434Y1690660D03*
X738550Y1693215D03*
X732852Y1695701D03*
X738030Y1723903D03*
Y1726903D03*
X738108Y1721157D03*
X738075Y1718082D03*
X742841Y39832D03*
X746101Y46262D03*
X745901Y40362D03*
X744477Y58373D03*
X744988Y49062D03*
X747488D03*
X752261Y59782D03*
X749478Y59902D03*
X746588Y59754D03*
X740817Y58503D03*
X745131Y69507D03*
X750090Y72820D03*
X747488Y71429D03*
X740537Y73564D03*
X750034Y89988D03*
X750701Y106642D03*
X754783Y96553D03*
X750034Y92888D03*
X741309Y108742D03*
X748034Y116288D03*
X748261Y112552D03*
X743050Y139182D03*
X751221Y137864D03*
X743547Y147703D03*
X744911Y166887D03*
X748915Y158608D03*
X745031Y161463D03*
X748125Y170618D03*
X751575Y184252D03*
X745712Y212760D03*
X746705Y315647D03*
X746522Y308804D03*
X750717Y319907D03*
X747594Y319106D03*
X747696Y332772D03*
X751337Y343849D03*
X748752Y343582D03*
X745132Y344964D03*
X752926Y361021D03*
X747500Y368862D03*
X751500D03*
X743500D03*
Y374362D03*
X749389Y360816D03*
X755135Y368907D03*
X754813Y374362D03*
X739500D03*
X747500D03*
X747454Y386817D03*
X751652Y386862D03*
X739652Y390862D03*
X743500D03*
X747500D03*
X751500D03*
X747629Y406163D03*
X753252Y495234D03*
X748381Y495244D03*
X752652Y504106D03*
X752500Y517362D03*
X744500Y513362D03*
X748661Y517060D03*
X740500Y513362D03*
X752500D03*
X748500D03*
X753951Y521801D03*
X748077Y521789D03*
X740500Y537862D03*
X752965Y537678D03*
X747637Y534874D03*
X748143Y530269D03*
X744916Y530268D03*
X752500Y529862D03*
X748000Y537862D03*
X741851Y553544D03*
X745645Y545880D03*
X752500Y545862D03*
X740638Y549900D03*
X745091Y553563D03*
X748500Y545862D03*
X752195Y554761D03*
X742278Y566667D03*
X748482Y557085D03*
X751731Y557714D03*
X739128Y566639D03*
X741624Y580707D03*
X741200Y577470D03*
X749131Y570340D03*
X750062Y655415D03*
X753309Y655515D03*
X750074Y648739D03*
X753483Y648749D03*
X751885Y666724D03*
X753231Y678679D03*
X753500Y675800D03*
X742579Y676093D03*
X746665Y678879D03*
X750168Y675833D03*
X748049Y767300D03*
Y771100D03*
X745475Y1297246D03*
Y1304946D03*
Y1302346D03*
Y1299746D03*
X745439Y1314048D03*
X748188Y1327317D03*
X745491Y1327124D03*
X742971D03*
X745439Y1323048D03*
Y1320048D03*
Y1317048D03*
X745691Y1332424D03*
Y1329924D03*
Y1334924D03*
X748188Y1333017D03*
Y1330517D03*
X745691Y1339924D03*
Y1337424D03*
X748188Y1335517D03*
X742971Y1337124D03*
Y1339624D03*
Y1334624D03*
Y1329624D03*
Y1332124D03*
X739501Y1342244D03*
X739500Y1352031D03*
Y1349131D03*
X739501Y1344744D03*
X751968Y1403396D03*
X739932Y1398042D03*
X745201Y1398194D03*
X752643Y1400239D03*
X749155Y1398639D03*
X751893Y1397671D03*
X745201Y1400702D03*
X742212Y1394517D03*
X739888Y1404849D03*
X739611Y1458211D03*
X750418Y1468893D03*
X750968Y1482349D03*
X746082Y1506931D03*
X746111Y1504125D03*
X745984Y1501052D03*
X745001Y1516471D03*
X750205Y1512307D03*
X750155Y1516451D03*
X739900Y1523152D03*
X748782Y1555496D03*
X742782D03*
X739782D03*
X745782D03*
X739782Y1558496D03*
Y1561496D03*
Y1564496D03*
X745782Y1558496D03*
X742782D03*
X745782Y1561496D03*
X742782D03*
X745782Y1564496D03*
X742782D03*
X739782Y1567496D03*
X742782D03*
X748782Y1558496D03*
Y1561496D03*
Y1564496D03*
X747110Y1575863D03*
X747150Y1583247D03*
X739782Y1570496D03*
X742782D03*
X738880Y1582361D03*
Y1577231D03*
X749167Y1591967D03*
X754635Y1592571D03*
X738880Y1587491D03*
X745998Y1597463D03*
X742998D03*
X745998Y1594463D03*
X742998D03*
X739998Y1597463D03*
Y1594463D03*
X745998Y1600463D03*
X742998D03*
X739998D03*
X745998Y1603663D03*
X742998D03*
X739998D03*
X745998Y1606663D03*
X742998D03*
X739998D03*
X749261Y1628208D03*
X743664Y1626945D03*
X753770Y1636083D03*
X751521Y1659158D03*
X743740Y1657327D03*
X743039Y1643326D03*
X751521Y1656008D03*
X739880Y1648046D03*
X742792Y1647982D03*
X751030Y1668583D03*
X745075Y1665675D03*
X754030Y1669256D03*
X748254Y1674771D03*
X752187Y1682994D03*
X748413Y1679367D03*
X746766Y1696036D03*
X740328Y1698376D03*
X747289Y1693063D03*
X752187Y1691058D03*
X741030Y1723903D03*
Y1726903D03*
X741160Y1721150D03*
X741025Y1718195D03*
X752596Y1737117D03*
X760843Y23788D03*
X757721Y62132D03*
X760221D03*
X762721D03*
X755621Y51602D03*
X758621D03*
X754621Y74562D03*
X757721Y64632D03*
X760221D03*
X763221Y65132D03*
X757188Y91829D03*
X754634Y105288D03*
X757694Y98108D03*
Y100653D03*
X760193Y106500D03*
X754634Y108288D03*
X757576Y112575D03*
X762173Y123898D03*
X762199Y126684D03*
Y129684D03*
X770073Y143438D03*
X756000Y145500D03*
X754825Y163397D03*
X756303Y158417D03*
X758111Y172636D03*
X765950Y190669D03*
X762300Y188910D03*
X765000Y186500D03*
X754737Y185469D03*
X756083Y220240D03*
X757629Y239295D03*
X754286Y266319D03*
X754291Y269322D03*
X756692Y278942D03*
X765285Y276374D03*
X757464Y284087D03*
X754556Y283976D03*
X761067Y280355D03*
X763384Y279231D03*
X763508Y284404D03*
X763463Y281840D03*
X760614Y284100D03*
X754759Y281007D03*
X755335Y295589D03*
X758510Y298620D03*
X760462Y295662D03*
X757937Y303908D03*
X758959Y319596D03*
X768130Y335363D03*
X753959Y343790D03*
X758245Y343763D03*
X764331Y374401D03*
X756347Y360851D03*
X764983Y368052D03*
X766304Y372862D03*
X768304Y374362D03*
X759652D03*
X755500Y386862D03*
X759500D03*
X767500D03*
X759500Y390791D03*
X755500Y390862D03*
X759500Y402098D03*
X767500Y401470D03*
Y390862D03*
X763500D03*
X757258Y408763D03*
X765975Y414414D03*
X769648Y430511D03*
X770530Y423460D03*
X768301Y438223D03*
X770918Y442510D03*
X770042Y446829D03*
X770590Y470940D03*
X762800Y493654D03*
X764500Y521862D03*
X756500Y513340D03*
X764500D03*
X756800Y517050D03*
X760500Y521189D03*
X756186Y529888D03*
X764500Y534424D03*
X760500Y534352D03*
X764500Y529862D03*
X760500Y529845D03*
X757860Y537859D03*
X760660Y537862D03*
X756500Y545862D03*
X764500D03*
X759568Y545867D03*
X768340Y563678D03*
X765809Y563410D03*
X758103Y556873D03*
X765041Y565867D03*
X762530Y565340D03*
X757745Y655353D03*
X755765Y666904D03*
X762656Y667835D03*
X756936Y676319D03*
X768565Y677573D03*
X760529Y677715D03*
X764401Y676968D03*
X762396Y732915D03*
X754532Y735859D03*
X760425Y736233D03*
X764568Y736183D03*
X761608Y766871D03*
X759854Y1297246D03*
Y1304946D03*
Y1302346D03*
Y1299746D03*
X759839Y1313948D03*
Y1319948D03*
X760204Y1327314D03*
X762754D03*
X759839Y1316948D03*
X757638Y1327317D03*
X759839Y1322948D03*
X760204Y1332514D03*
Y1330014D03*
Y1335014D03*
X757638Y1333017D03*
Y1330517D03*
X760194Y1340024D03*
Y1337524D03*
X757638Y1335517D03*
X762844Y1337324D03*
Y1339824D03*
X762754Y1334814D03*
Y1329814D03*
Y1332314D03*
X762261Y1343424D03*
X761800Y1352031D03*
Y1349131D03*
X762261Y1345924D03*
X764229Y1372880D03*
X766829D03*
Y1370380D03*
Y1367780D03*
X764229D03*
Y1370380D03*
X765579Y1375480D03*
X760980Y1385146D03*
Y1388046D03*
X767549Y1391286D03*
Y1397086D03*
Y1394186D03*
X765349Y1392686D03*
X765449Y1395686D03*
X763283Y1397316D03*
Y1394416D03*
X758179Y1482049D03*
X758163Y1490789D03*
Y1498663D03*
Y1494726D03*
Y1502600D03*
Y1506538D03*
Y1522286D03*
Y1510474D03*
X757826Y1514412D03*
X758056Y1518349D03*
X758163Y1526223D03*
X758179Y1534963D03*
X760650Y1570633D03*
Y1578733D03*
Y1574733D03*
X757610Y1576023D03*
X766212Y1568043D03*
X757650Y1580023D03*
X766950Y1581233D03*
X757610Y1584023D03*
X767750Y1584108D03*
X757610Y1589023D03*
X760650Y1587733D03*
X760521Y1595500D03*
X759723Y1626161D03*
X761510Y1638434D03*
X755261Y1628208D03*
X762030Y1668583D03*
X755408Y1672381D03*
X758030Y1668583D03*
X757557Y1684444D03*
X767381Y1676594D03*
X754839Y1678069D03*
X768463Y1687769D03*
X757161Y1696424D03*
X768733Y1694485D03*
X769475Y75360D03*
X781441Y118637D03*
X782819Y149471D03*
X780159Y146961D03*
X771356Y167518D03*
X772270Y153728D03*
X771427Y158026D03*
X773457Y249792D03*
X782712Y260466D03*
X777408Y256648D03*
X777421Y277962D03*
X779884Y281705D03*
X774485Y286879D03*
X773221Y296262D03*
X780618Y296345D03*
X769790Y296231D03*
X777468Y296315D03*
X769861Y302462D03*
X782641Y310888D03*
X779121Y306155D03*
X773944Y312588D03*
X779681Y313053D03*
X770190Y312563D03*
X779121Y303410D03*
Y308755D03*
X780046Y328268D03*
X772119Y333537D03*
X771964Y339716D03*
X781812Y341863D03*
X779118Y341749D03*
X769000Y364000D03*
X776500Y371000D03*
X784500Y367500D03*
X771512Y386862D03*
X775388Y390862D03*
X770000Y380787D03*
X777612Y403505D03*
X771512Y390862D03*
X780295Y403538D03*
X784498Y396353D03*
X782700Y415284D03*
X780808Y419865D03*
X773181Y415197D03*
X773233Y409154D03*
X783256Y409340D03*
X770159Y410257D03*
X783770Y422454D03*
X772610Y434690D03*
X780877Y427344D03*
X771718Y426804D03*
X780877Y423344D03*
X783821Y431534D03*
X780877Y431368D03*
X772677Y451374D03*
X780577Y435564D03*
X780877Y443344D03*
Y447344D03*
X780977Y459524D03*
X780877Y463344D03*
Y455344D03*
X783377Y451344D03*
X780877Y475344D03*
X780759Y479344D03*
X783877Y475344D03*
X772427D03*
X781242Y489574D03*
X780877Y483344D03*
X772390Y491047D03*
X772427Y487344D03*
X783358Y495344D03*
X783351Y499221D03*
X771039Y511292D03*
X775100Y502504D03*
X772427Y495344D03*
X777166Y504477D03*
X774998Y511306D03*
X774964Y514204D03*
X772100Y532700D03*
X777200Y530250D03*
X772000Y529862D03*
X781699Y536425D03*
X772000Y545862D03*
X776345Y545733D03*
X777754Y558740D03*
X773463Y563455D03*
X778747Y572269D03*
X779448Y632498D03*
X772459Y655290D03*
X771553Y677963D03*
X777750Y767300D03*
Y771100D03*
X769521Y1297199D03*
X783280Y1296009D03*
X778030Y1296259D03*
X780530D03*
X783280Y1298509D03*
X785520Y1292160D03*
X769521Y1304899D03*
Y1299699D03*
Y1302299D03*
X778030Y1310259D03*
X780530D03*
X769439Y1313948D03*
X783280Y1301009D03*
X769439Y1319948D03*
Y1322948D03*
Y1316948D03*
X779014Y1343262D03*
Y1340062D03*
X782014D03*
Y1337062D03*
Y1343262D03*
X770881Y1343344D03*
X782115Y1334173D03*
X770990Y1349091D03*
Y1351991D03*
X780000Y1353500D03*
X779014Y1346462D03*
Y1349862D03*
X782014Y1346462D03*
Y1349862D03*
X780000Y1357500D03*
X770881Y1345844D03*
X780000Y1363500D03*
Y1360500D03*
X773069Y1375500D03*
X770469D03*
X776010Y1380750D03*
X780111Y1405366D03*
X782758Y1405249D03*
X774646Y1516441D03*
X772906Y1522901D03*
X774616Y1520361D03*
X781850Y1556133D03*
Y1559133D03*
Y1562133D03*
Y1565133D03*
X778850Y1559133D03*
Y1562133D03*
Y1565133D03*
X771450Y1577333D03*
X781850Y1568133D03*
Y1571133D03*
X778850Y1568133D03*
Y1571133D03*
X779977Y1577233D03*
Y1582363D03*
X771550Y1587133D03*
X774420Y1587284D03*
X779977Y1587493D03*
X779550Y1594533D03*
X782550D03*
X776550Y1597533D03*
Y1594533D03*
X779550Y1597533D03*
X782550D03*
Y1600533D03*
X776550D03*
X779550D03*
Y1606533D03*
X782550Y1603533D03*
X779550D03*
X776550Y1606533D03*
Y1603533D03*
X782550Y1606533D03*
X773974Y1731920D03*
X787456Y49379D03*
X785181Y120947D03*
X792681D03*
X790181D03*
X787681D03*
X783941Y118637D03*
X786441D03*
X788941D03*
X791341Y264848D03*
X785529Y270459D03*
X798205Y279146D03*
X797594Y282233D03*
X797444Y271469D03*
X795668Y298801D03*
X793855Y305316D03*
X798493Y301377D03*
X795921Y312662D03*
X787500Y328362D03*
X799226Y328467D03*
X791726D03*
X783726D03*
X785674Y342279D03*
X788806Y342236D03*
X791403Y342262D03*
X793951Y342224D03*
X795685Y357498D03*
X792302Y357537D03*
X798312Y372571D03*
X792488Y377452D03*
X796021Y395924D03*
X797000Y404000D03*
X786571Y403455D03*
X785923Y419194D03*
X787000Y407500D03*
X796283Y415344D03*
Y419344D03*
X786877Y427344D03*
X796283Y423344D03*
Y431344D03*
X783877Y427344D03*
X796283D03*
X786999Y435476D03*
X797252Y443344D03*
X786877D03*
X796333Y439344D03*
Y435344D03*
X786203Y447054D03*
X783877Y435444D03*
X797197Y447344D03*
X786887Y451344D03*
X797252Y459344D03*
Y451344D03*
X797322Y463344D03*
X786825Y459518D03*
X786755Y455524D03*
X797252Y455344D03*
Y471344D03*
X797326Y479344D03*
X786877Y471344D03*
X797463Y476159D03*
X786877Y475344D03*
X786440Y480769D03*
X797405Y487464D03*
X797326Y483344D03*
X787092Y490681D03*
X786358Y483566D03*
X786102Y507536D03*
X787446Y495344D03*
X787279Y499238D03*
X790503Y501826D03*
X799450Y511801D03*
X800674Y504130D03*
X789125Y529425D03*
X800500Y540500D03*
X794425Y541425D03*
X794059Y553559D03*
X794357Y559996D03*
X791500Y560000D03*
X785000Y563500D03*
X785919Y559660D03*
X792782Y565323D03*
X791723Y574946D03*
X799742Y628983D03*
X789135Y617097D03*
X783653Y631671D03*
X787591Y631785D03*
X788537Y734410D03*
X793131Y734310D03*
X784543Y734510D03*
X791308Y766871D03*
X789020Y1292160D03*
X792520D03*
X796020D03*
X786030Y1310259D03*
X794030D03*
X796530D03*
X788530D03*
X795421Y1331257D03*
X785014Y1350862D03*
X794273Y1354600D03*
Y1357600D03*
Y1364500D03*
Y1361500D03*
X784669Y1462178D03*
X784261Y1482049D03*
X796955Y1487468D03*
X788710Y1488821D03*
X784277Y1504569D03*
Y1500632D03*
Y1508506D03*
Y1512443D03*
X784261Y1534963D03*
X784277Y1528191D03*
X791823Y1527404D03*
X791867Y1524254D03*
X784850Y1556133D03*
X796850D03*
X790850D03*
X787850D03*
X793850D03*
X784850Y1559133D03*
Y1562133D03*
Y1565133D03*
X796850Y1559133D03*
Y1562133D03*
Y1565133D03*
X787850Y1559133D03*
Y1562133D03*
Y1565133D03*
X793850Y1559133D03*
X790850D03*
X793850Y1562133D03*
X790850D03*
X793850Y1565133D03*
X790850D03*
X799150Y1581379D03*
X784850Y1568133D03*
Y1571133D03*
X787850Y1568133D03*
Y1571133D03*
X793850Y1568133D03*
X790850D03*
X793850Y1571133D03*
X790850D03*
X791077Y1577233D03*
X785577D03*
X791077Y1582363D03*
X796650Y1583347D03*
X785577Y1587493D03*
X791077D03*
X791550Y1597533D03*
X785550Y1594533D03*
X788550D03*
X791550D03*
X785550Y1597533D03*
X788550D03*
X785550Y1600533D03*
X788550D03*
X791550D03*
Y1606533D03*
X788550D03*
X785550D03*
X791550Y1603533D03*
X788550D03*
X785550D03*
X795926Y1731918D03*
X809456Y49379D03*
X806984Y265653D03*
X812867Y278860D03*
X804330Y281380D03*
X801341Y279141D03*
X799935Y286823D03*
X799113Y297733D03*
X803893Y301969D03*
X798621Y312773D03*
X805871Y304812D03*
X806461Y310610D03*
X803264Y330102D03*
X808617D03*
X806117D03*
X808401Y341670D03*
X812070Y341590D03*
X803410Y341572D03*
X803500Y366000D03*
X811569Y387674D03*
X802660Y381020D03*
X802462Y387756D03*
X807564Y403805D03*
X811224Y395974D03*
X803412Y403978D03*
X813148Y403908D03*
X805425Y395502D03*
X813175Y422687D03*
X813252Y427060D03*
X802270Y435372D03*
X802459Y443218D03*
X810360Y442079D03*
X813208Y435344D03*
X812895Y449802D03*
X802533D03*
X802752Y455344D03*
X812983Y463578D03*
X813114Y459344D03*
X802752D03*
X813114Y455344D03*
X812983Y471344D03*
Y476159D03*
X801874Y471344D03*
X802752Y480159D03*
X812983D03*
X813000Y484862D03*
X801762Y495344D03*
X802752Y487344D03*
X801753Y491344D03*
X813187Y498362D03*
X812500Y504000D03*
X813114Y495344D03*
X802250Y500504D03*
X801857Y508031D03*
X805940Y534500D03*
X805341Y578059D03*
X805199Y620347D03*
X804863Y626789D03*
X805150Y623843D03*
X807451Y767299D03*
X807127Y770958D03*
X799280Y1296009D03*
X802030Y1296259D03*
X804530D03*
X807601Y1299241D03*
X799280Y1298509D03*
X802030Y1310259D03*
X804530D03*
X807601Y1307191D03*
X799280Y1301009D03*
X804099Y1333835D03*
X801171Y1343278D03*
X801614Y1339062D03*
X808469Y1356745D03*
Y1359245D03*
X810246Y1351988D03*
X811771Y1355488D03*
X799071Y1350088D03*
X810986Y1361684D03*
X807866Y1369177D03*
X805366Y1367093D03*
X802866D03*
X807866Y1366677D03*
X811272Y1382752D03*
X811767Y1388154D03*
X808714Y1490376D03*
Y1487376D03*
Y1506784D03*
Y1519784D03*
Y1509784D03*
Y1516784D03*
X802150Y1570633D03*
Y1578633D03*
Y1582833D03*
X810150Y1574633D03*
X813150Y1579410D03*
Y1570633D03*
X810050Y1584033D03*
X802150Y1594633D03*
X810850Y1587733D03*
X810150Y1590633D03*
X813049D03*
X802700Y1587183D03*
X810150Y1602633D03*
Y1598633D03*
X802150Y1606633D03*
X822699Y56712D03*
X819321Y56961D03*
X819115Y115223D03*
X823115D03*
X821119Y134632D03*
X825699Y139062D03*
X824499Y145198D03*
X820901Y147112D03*
X814571Y145952D03*
X814532Y139851D03*
X822635Y165468D03*
X825332Y166862D03*
X813676Y266065D03*
X816322Y284369D03*
X823067Y273225D03*
X823038Y276301D03*
X819828Y288063D03*
X827621Y302962D03*
X820405Y311830D03*
X822689Y305148D03*
X826915Y311842D03*
X822252Y309973D03*
X818677Y356405D03*
X826765Y356334D03*
X817780Y366905D03*
X823778Y376378D03*
X816991Y395337D03*
X820018Y403710D03*
X816281Y403814D03*
X828286Y401567D03*
X824653Y405347D03*
X817497Y415344D03*
X827341Y419344D03*
X817497D03*
X827341Y415344D03*
X826665Y423425D03*
X817497Y427060D03*
X826474Y431344D03*
X816239Y435344D03*
X817497Y431060D03*
X826474Y435344D03*
X816117Y443552D03*
X822878Y446425D03*
X816109Y455344D03*
X826912Y475989D03*
X816409Y467568D03*
X817393Y491594D03*
X817426Y487232D03*
X830212Y483892D03*
X826472Y483896D03*
X827000Y489055D03*
X817996Y496219D03*
X828259Y501027D03*
X824500Y514500D03*
X817441Y517941D03*
X824380Y517595D03*
X822559Y530876D03*
X827237Y550771D03*
X817849Y550871D03*
X826552Y543612D03*
X820620Y550846D03*
X824366Y552444D03*
X827832Y554269D03*
X823777Y560988D03*
X814489Y558082D03*
X825200Y580300D03*
X815287Y580401D03*
X820617Y641273D03*
X816732Y629198D03*
X815753Y644219D03*
X817900Y649012D03*
X822579Y760169D03*
X822218Y756979D03*
X822794Y767511D03*
X825390Y770020D03*
X822794Y777511D03*
X816550Y766871D03*
X822625Y763529D03*
X822794Y772511D03*
Y775011D03*
X825061Y764884D03*
X822864Y783262D03*
X822772Y788359D03*
X822790Y785838D03*
X822883Y780334D03*
X822982Y791245D03*
X822555Y807409D03*
X822794Y797511D03*
Y800011D03*
Y795011D03*
X822494Y802941D03*
X823927Y907676D03*
X823958Y936140D03*
X826958D03*
X823958Y939140D03*
X826958D03*
X827088Y933387D03*
X824036Y933394D03*
X826953Y930432D03*
X824003Y930319D03*
X828109Y1234504D03*
X826728Y1246315D03*
X824444Y1249420D03*
X826112Y1269546D03*
X828246Y1266501D03*
X814296Y1384045D03*
Y1387445D03*
X824714Y1490376D03*
Y1487376D03*
X816690Y1490376D03*
Y1487376D03*
X824714Y1500376D03*
Y1497376D03*
Y1506784D03*
X816717Y1500388D03*
X816729Y1497364D03*
X816693Y1506784D03*
X824714Y1519784D03*
Y1509784D03*
Y1516784D03*
X816706Y1519820D03*
X816693Y1516784D03*
X816694Y1509796D03*
X824714Y1529784D03*
Y1526784D03*
X816714Y1529784D03*
Y1526784D03*
X823850Y1556133D03*
X826850D03*
X820850Y1565133D03*
Y1562133D03*
Y1559133D03*
X826850Y1565133D03*
X823850D03*
X826850Y1562133D03*
Y1559133D03*
X823850Y1562133D03*
Y1559133D03*
X820850Y1571133D03*
Y1568133D03*
X826850Y1571133D03*
Y1568133D03*
X823850Y1571133D03*
Y1568133D03*
X821977Y1577233D03*
X827577D03*
X821977Y1582363D03*
X816150Y1587284D03*
X821977Y1587493D03*
X827577D03*
X821550Y1594533D03*
X827550Y1597533D03*
Y1594533D03*
X824550Y1597533D03*
Y1594533D03*
X821550Y1597533D03*
Y1600533D03*
X827550D03*
X824550D03*
X815550Y1606533D03*
X818550D03*
X821550Y1603533D03*
X818550D03*
X827550Y1606533D03*
X824550D03*
X821550D03*
X827550Y1603533D03*
X824550D03*
X817974Y1731920D03*
X833421Y-36647D03*
X839699Y-35341D03*
X833406Y-34132D03*
X836674Y-36661D03*
X836659Y-34146D03*
X833391Y-31617D03*
X833376Y-29102D03*
X836644Y-31631D03*
X836629Y-29116D03*
X842320Y-21711D03*
Y-18311D03*
X833407Y-26181D03*
X836660Y-26167D03*
Y-16167D03*
X833407Y-16181D03*
X839700Y-14972D03*
X833422Y-13666D03*
X836675Y-13652D03*
X833412Y-19948D03*
X836674D03*
X836675Y-23652D03*
X833422Y-23666D03*
X839700Y-24972D03*
X833412Y52D03*
X836674D03*
X833412Y-9948D03*
X836674D03*
X836675Y-3652D03*
X833422Y-3666D03*
X839700Y-4972D03*
X833407Y-6181D03*
X836660Y-6167D03*
X836675Y16348D03*
X833422Y16334D03*
X839700Y15028D03*
X833407Y13819D03*
X836660Y13833D03*
X836674Y10052D03*
X833412D03*
X836675Y6348D03*
X833422Y6334D03*
X839700Y5028D03*
X833407Y3819D03*
X836660Y3833D03*
X842320Y18289D03*
Y21689D03*
X836659Y24250D03*
X836674Y26765D03*
X833406Y24236D03*
X839699Y25445D03*
X833421Y26751D03*
X833376Y19206D03*
X833391Y21721D03*
X831456Y49379D03*
X828601Y61752D03*
X836780Y68008D03*
X836127Y62681D03*
X839899Y87248D03*
X841585Y94181D03*
X837792Y85186D03*
X837251Y93221D03*
X831298Y104206D03*
X834616Y94324D03*
X842865Y110296D03*
X831115Y115223D03*
X839361Y114862D03*
X835115Y115223D03*
X845221Y135862D03*
Y129362D03*
X829115Y150273D03*
Y147123D03*
X838221Y163862D03*
X835221D03*
X842721Y181362D03*
X837161Y213207D03*
X844527Y204968D03*
X838821Y206872D03*
X837161Y218212D03*
X830340Y228143D03*
X837501Y229642D03*
X832525Y268579D03*
X836305Y268624D03*
X836163Y279355D03*
X829572Y296511D03*
X840288Y287593D03*
X829167Y288063D03*
X830418Y311865D03*
X837754Y335345D03*
X832686Y331028D03*
X829800Y331013D03*
X840457Y335368D03*
X842257Y350376D03*
X829344Y356224D03*
X833219Y375992D03*
X840357Y382813D03*
X836840Y382003D03*
X841862Y390441D03*
X833097Y393000D03*
X837912Y401545D03*
X834426Y401504D03*
X833000Y409500D03*
X838500D03*
X837847Y405347D03*
X834430Y434634D03*
X833807Y423257D03*
X841809Y423219D03*
X838000Y423362D03*
X829106Y439279D03*
X842825Y448739D03*
X828979Y449802D03*
X834106Y439279D03*
X828714Y443552D03*
X833800Y444700D03*
X828751Y455344D03*
X834251Y459578D03*
X828751Y463578D03*
X834251Y455578D03*
X828751Y459344D03*
X832224Y450328D03*
X831381Y455167D03*
X833751Y463578D03*
X842825Y452739D03*
X828751Y471344D03*
X835425Y477890D03*
X828751Y467568D03*
X838575Y477554D03*
X839200Y467900D03*
X830046Y476031D03*
X838561Y484071D03*
X830743Y500740D03*
X833000Y503500D03*
X831798Y515314D03*
X838342Y514610D03*
X839061Y555808D03*
X841660Y558200D03*
X835519Y580056D03*
X831018Y583076D03*
X835059Y660940D03*
X837391Y659820D03*
X831505Y897291D03*
X831582Y905153D03*
X832347Y1251703D03*
X844250Y1266759D03*
X835554Y1281324D03*
X832274Y1277301D03*
X832342Y1274626D03*
X835682Y1285472D03*
X836670Y1291355D03*
X836587Y1295333D03*
X842500Y1310000D03*
Y1306000D03*
Y1302000D03*
X833756Y1330156D03*
X834017Y1333584D03*
X834071Y1342457D03*
X834017Y1336252D03*
X833963Y1339464D03*
X838963Y1345974D03*
X839188Y1348937D03*
X833853Y1345833D03*
X841039Y1358082D03*
X839244Y1352094D03*
X841203Y1361376D03*
X841472Y1365050D03*
X838670Y1518558D03*
X841310Y1518608D03*
X838630Y1521538D03*
X841270Y1521588D03*
X835850Y1556133D03*
X829850D03*
X832850D03*
X838850D03*
X832850Y1565133D03*
X835850D03*
X832850Y1562133D03*
X835850D03*
X832850Y1559133D03*
X835850D03*
X829850Y1565133D03*
Y1562133D03*
Y1559133D03*
X838850Y1565133D03*
Y1562133D03*
Y1559133D03*
X841150Y1581379D03*
X832850Y1571133D03*
X835850D03*
X832850Y1568133D03*
X835850D03*
X829850Y1571133D03*
Y1568133D03*
X833077Y1577233D03*
Y1582363D03*
X838650Y1583347D03*
X833077Y1587493D03*
X830550Y1597533D03*
X833550D03*
X830550Y1594533D03*
X833550D03*
X830550Y1600533D03*
X833550D03*
X830550Y1603533D03*
X836550Y1606533D03*
Y1603533D03*
X833550D03*
X830550Y1606533D03*
X833550D03*
X839974Y1731920D03*
X844766Y-24648D03*
Y-15374D03*
Y-5374D03*
Y5352D03*
Y15352D03*
Y24626D03*
X853456Y49379D03*
X850016Y87341D03*
X854108Y91232D03*
X843856Y87711D03*
X847473Y94754D03*
X854578Y99651D03*
X854221Y135862D03*
Y129362D03*
X854201Y143062D03*
X851895Y160141D03*
X848745Y160137D03*
X845721Y181362D03*
X856213Y191545D03*
X849711Y212062D03*
X845221Y216532D03*
X855859Y212425D03*
X855934Y215375D03*
X854707Y229878D03*
X852207D03*
X847581Y232222D03*
X853800Y265057D03*
X847939Y265092D03*
X853621Y269057D03*
X853829Y262057D03*
X846189Y281419D03*
X854334Y276117D03*
X854225Y280027D03*
Y283527D03*
X857334Y276117D03*
X856244Y286447D03*
X852780Y291559D03*
X852801Y288562D03*
X853201Y297462D03*
X843504Y287602D03*
X855481Y299692D03*
X856701Y304862D03*
X860071Y304850D03*
X856397Y339751D03*
Y344669D03*
X846275Y335575D03*
X843308Y335550D03*
X857187Y342210D03*
X848030Y338461D03*
X850155Y335042D03*
X852303Y337488D03*
X852177Y341882D03*
X848425Y378089D03*
X854552Y381000D03*
X849750Y401280D03*
X854190Y404035D03*
X855722Y416606D03*
X846000Y418862D03*
X854239Y412911D03*
X851517Y411745D03*
X846000Y423362D03*
X845986Y429413D03*
X857942Y448575D03*
X845100Y440100D03*
X857887Y459847D03*
X848500Y452128D03*
X852240Y470946D03*
X847686Y475915D03*
X847303Y485788D03*
X846104Y494661D03*
X847518Y490905D03*
X846411Y482128D03*
X849772Y494585D03*
X852209Y507211D03*
X855497Y507205D03*
X848097Y503315D03*
X855837Y519713D03*
X847941Y538325D03*
X849126Y530138D03*
X845126D03*
X845094Y535110D03*
X844741Y543864D03*
X843655Y555683D03*
X847435Y555496D03*
X856647Y616786D03*
X848660Y651127D03*
X854484Y647436D03*
X848999Y644995D03*
X846725Y1269785D03*
X846931Y1291468D03*
X846895Y1295981D03*
X845801Y1287776D03*
X851500Y1302000D03*
X851400Y1305499D03*
X852811Y1313450D03*
X850684Y1310000D03*
X852955Y1320320D03*
X856500Y1321500D03*
X853100Y1331688D03*
X856500Y1330500D03*
X852780Y1338365D03*
X856500Y1339500D03*
Y1348500D03*
X847007Y1521458D03*
X844367Y1521408D03*
Y1518784D03*
X847007Y1518834D03*
X855853Y1521308D03*
X853213Y1521258D03*
X850146Y1521261D03*
Y1518637D03*
X853213Y1518634D03*
X855853Y1518684D03*
X844150Y1578633D03*
Y1570633D03*
Y1582833D03*
X852150Y1574633D03*
X855150Y1579410D03*
Y1570633D03*
X852050Y1584033D03*
X844150Y1594633D03*
X852850Y1587733D03*
X852150Y1590633D03*
X855049D03*
X844700Y1587183D03*
X852150Y1602633D03*
Y1598633D03*
X844150Y1606633D03*
X857550Y1606533D03*
X858630Y60293D03*
X861351Y61672D03*
X863343Y90021D03*
X865912Y89252D03*
X870892Y131868D03*
X874295Y163862D03*
X871145D03*
X863488Y176332D03*
X875170Y185113D03*
X867529Y231788D03*
X858528Y262382D03*
X863104Y273103D03*
X868104D03*
X867701Y267537D03*
X860834Y276817D03*
X863934Y276917D03*
X863230Y280001D03*
X866619Y286801D03*
X862044Y290047D03*
X870672Y295485D03*
X870008Y302273D03*
X872508D03*
X860152Y328399D03*
X865132D03*
X871099Y323000D03*
X861377Y339751D03*
X865132Y333317D03*
X860152D03*
X861377Y344669D03*
X864342Y330858D03*
X860942D03*
X860587Y342210D03*
X860372Y375195D03*
X866168Y374774D03*
X871190Y382230D03*
X862075Y398537D03*
X858925D03*
X872020Y413300D03*
X864826Y411557D03*
X870220Y430424D03*
X870826Y423423D03*
X870064Y427703D03*
X859500Y429362D03*
X863420D03*
X859469Y425293D03*
X860541Y446089D03*
X860328Y475162D03*
X858288Y467048D03*
X860280Y488636D03*
X860299Y491620D03*
X864361Y493001D03*
X860508Y497772D03*
X860341Y503154D03*
X860658Y515961D03*
X867356Y558714D03*
X867733Y575522D03*
X867590Y642420D03*
X864590D03*
X870590D03*
X866727Y650739D03*
X866549Y748027D03*
X869406Y753541D03*
X872986Y753451D03*
X869275Y750472D03*
X873175D03*
X868539Y790882D03*
X870591Y785437D03*
X865466Y790581D03*
Y785581D03*
Y788081D03*
Y783081D03*
X865394Y801244D03*
X865466Y793081D03*
Y795581D03*
Y798081D03*
X865569Y806045D03*
Y808545D03*
X864700Y836100D03*
X863369Y827461D03*
X863344Y824713D03*
X863372Y833469D03*
Y830718D03*
X867651Y836820D03*
X867646Y833388D03*
X863671Y839062D03*
X865601Y841219D03*
X865109Y850795D03*
X864768Y844815D03*
X864140Y856052D03*
X864020Y859972D03*
X864106Y863534D03*
X864003Y866609D03*
X866005Y941554D03*
X863055Y941441D03*
X863010Y947262D03*
X866010D03*
X863010Y950262D03*
X866010D03*
X866140Y944509D03*
X863088Y944516D03*
X862044Y1249687D03*
X866294Y1255903D03*
X859446Y1284288D03*
X874989Y1410441D03*
X863745Y1444560D03*
X871214Y1466542D03*
X858581Y1518568D03*
X858567Y1521416D03*
X865850Y1556133D03*
X871850D03*
X868850D03*
X865850Y1565133D03*
Y1562133D03*
Y1559133D03*
X862850Y1565133D03*
Y1562133D03*
Y1559133D03*
X868850Y1565133D03*
X871850D03*
X868850Y1562133D03*
X871850D03*
X868850Y1559133D03*
X871850D03*
X865850Y1571133D03*
Y1568133D03*
X862850Y1571133D03*
Y1568133D03*
X868850Y1571133D03*
X871850D03*
X868850Y1568133D03*
X871850D03*
X863977Y1577233D03*
Y1582363D03*
X869577Y1577233D03*
X858150Y1587284D03*
X863977Y1587493D03*
X869577D03*
X863550Y1597533D03*
X866550Y1594533D03*
Y1597533D03*
X869550Y1594533D03*
Y1597533D03*
X863550Y1594533D03*
X872550D03*
Y1597533D03*
X866550Y1600533D03*
X869550D03*
X863550D03*
X872550D03*
Y1606533D03*
Y1603533D03*
X863550Y1606533D03*
X866550D03*
X869550D03*
X860550D03*
X869550Y1603533D03*
X866550D03*
X863550D03*
X860550D03*
X861974Y1731920D03*
X875345Y51595D03*
X876133Y73580D03*
Y95580D03*
Y117580D03*
X877462Y139540D03*
X876696Y176862D03*
Y171362D03*
X887521D03*
Y176862D03*
X889351Y195489D03*
X878221Y192055D03*
X878328Y183169D03*
X878221Y187449D03*
X887130Y183169D03*
X884986Y198829D03*
X881354Y267407D03*
X880944Y283347D03*
X884004Y278712D03*
Y274482D03*
X885764Y284361D03*
X877448Y284825D03*
X884004Y271332D03*
X880944Y286347D03*
X874244Y287047D03*
X873172Y295485D03*
X888000Y293000D03*
X875447Y301500D03*
X884740Y316000D03*
X874500Y328000D03*
X877640Y315789D03*
X873884Y447991D03*
Y453383D03*
Y450491D03*
X885916Y653912D03*
X883731Y651690D03*
X884410Y794332D03*
X883633Y790336D03*
X883776Y786814D03*
X877459Y802356D03*
X875412Y797350D03*
X882582Y1075083D03*
X879582D03*
X876582D03*
X873582D03*
X882582Y1061983D03*
X879582D03*
X876582D03*
Y1071533D03*
Y1068533D03*
Y1065533D03*
X873582D03*
Y1068533D03*
Y1071533D03*
Y1061983D03*
X874617Y1084657D03*
X877817D03*
Y1088057D03*
X874617D03*
X881217Y1084657D03*
Y1088057D03*
X874617Y1100957D03*
X877817D03*
Y1097557D03*
X874617D03*
X881217Y1100957D03*
Y1097557D03*
X886707Y1229920D03*
Y1232920D03*
X881807Y1238920D03*
X876923Y1239520D03*
X886707Y1235920D03*
X881694Y1229763D03*
Y1232763D03*
Y1235763D03*
X876907Y1235586D03*
Y1232586D03*
Y1229586D03*
X886707Y1254742D03*
Y1251742D03*
X881807Y1248920D03*
Y1245920D03*
X881937Y1251857D03*
X877480Y1248844D03*
X881807Y1241920D03*
X886707Y1257742D03*
X885000Y1307500D03*
X877936Y1312336D03*
X877000Y1340241D03*
X883379Y1417881D03*
X875039Y1407246D03*
X886362Y1428973D03*
X884399Y1431507D03*
X879424Y1425001D03*
X883279Y1421726D03*
X884462Y1446974D03*
X876044Y1444317D03*
X883562Y1440356D03*
X881987Y1449608D03*
X887519Y1444625D03*
X877226Y1441585D03*
X887117Y1436735D03*
X877850Y1556133D03*
X874850D03*
X880850D03*
X874850Y1565133D03*
X877850D03*
X880850D03*
X874850Y1562133D03*
X877850D03*
X880850D03*
X874850Y1559133D03*
X877850D03*
X880850D03*
X886150Y1578633D03*
Y1570633D03*
Y1582833D03*
X883150Y1581379D03*
X874850Y1571133D03*
X877850D03*
X874850Y1568133D03*
X877850D03*
X875077Y1577233D03*
Y1582363D03*
X886150Y1594633D03*
X880650Y1583347D03*
X886700Y1587183D03*
X875077Y1587493D03*
X875550Y1597533D03*
Y1594533D03*
X886150Y1606633D03*
X875550Y1600533D03*
Y1606533D03*
X878550D03*
Y1603533D03*
X875550D03*
X883974Y1731920D03*
X898720Y145206D03*
X891621Y207162D03*
X888930Y206823D03*
X891621Y209662D03*
X888930Y209323D03*
X896621Y207162D03*
X894121D03*
Y209662D03*
X896621D03*
X888560Y469527D03*
X892376Y466430D03*
X899000Y481038D03*
X888372Y547518D03*
X902376Y594657D03*
Y590172D03*
X903556Y614062D03*
X899678Y601043D03*
X900323Y604377D03*
X900301Y828248D03*
Y831221D03*
X899500Y853000D03*
X901000Y909000D03*
X901842Y936863D03*
X903925Y948500D03*
X889057Y1053133D03*
X898000Y1112336D03*
Y1109736D03*
Y1116544D03*
Y1119144D03*
Y1130160D03*
Y1132760D03*
Y1123352D03*
Y1125952D03*
X889273Y1134470D03*
X891648Y1137843D03*
X900723Y1146553D03*
X902382Y1137558D03*
X891996Y1149707D03*
X900280Y1150769D03*
X902482Y1140558D03*
X897754Y1156119D03*
X888247Y1219520D03*
Y1222520D03*
X891247D03*
Y1219520D03*
X888247Y1225520D03*
X896974Y1232869D03*
Y1235869D03*
X896907Y1238920D03*
X896974Y1229869D03*
X891247Y1225520D03*
X896107Y1254742D03*
Y1251742D03*
X896907Y1245920D03*
Y1248920D03*
Y1241920D03*
X896107Y1257742D03*
X892000Y1307500D03*
X888854Y1337936D03*
X890620Y1342990D03*
X900885Y1435041D03*
X900808Y1437798D03*
X902377Y1456465D03*
X894150Y1574633D03*
X897150Y1579410D03*
Y1570633D03*
X894050Y1584033D03*
X894150Y1590633D03*
X894850Y1587733D03*
X897049Y1590633D03*
X900150Y1587284D03*
X894150Y1602633D03*
Y1598633D03*
X899550Y1606533D03*
X902550Y1603533D03*
Y1606533D03*
X917386Y179500D03*
Y177000D03*
Y169500D03*
Y172000D03*
Y174500D03*
Y167000D03*
X909298Y195925D03*
X917387Y184114D03*
X908621Y188899D03*
X909161Y203012D03*
X909320Y210098D03*
Y217185D03*
Y224271D03*
Y231358D03*
X910267Y242658D03*
X910093Y246015D03*
X916268Y269859D03*
Y277859D03*
X909023Y294734D03*
X910752Y286141D03*
X913512Y486743D03*
X903340Y505105D03*
X917582Y549564D03*
X914575Y560027D03*
X906597Y579695D03*
X909747D03*
X911980Y585280D03*
X907035Y590172D03*
X910731Y590251D03*
X905526Y594657D03*
X906597Y628426D03*
X906734Y619373D03*
X910535Y619251D03*
X906706Y614062D03*
X909747Y628426D03*
X915334Y639166D03*
X908823Y655116D03*
X906274Y654921D03*
X906570Y663930D03*
X909320D03*
X907207Y667646D03*
X906345Y742414D03*
X904535Y744639D03*
X906387Y818471D03*
Y821221D03*
Y815721D03*
X906313Y825095D03*
X903149Y825094D03*
X917000Y853000D03*
X903941Y874000D03*
X917622Y887545D03*
X909000Y909000D03*
X905000D03*
X907000Y899777D03*
X913000Y909000D03*
X917000D03*
Y918500D03*
X905000D03*
X911500Y931000D03*
X908500Y927500D03*
X915575Y948500D03*
X910000Y954500D03*
X912425Y948500D03*
X907075D03*
X910000Y957500D03*
X912500Y963309D03*
X907500D03*
X916763Y972343D03*
X909000Y974000D03*
Y982000D03*
X911041Y979459D03*
X909000Y977491D03*
X916880Y1138969D03*
X906473Y1158574D03*
X919779Y1155658D03*
X915053Y1219520D03*
Y1222520D03*
X912053D03*
Y1219520D03*
Y1225520D03*
X915053D03*
X910707Y1229920D03*
Y1232920D03*
X905007Y1238920D03*
X910707Y1235920D03*
X905008Y1229940D03*
Y1232940D03*
Y1235940D03*
X910707Y1254742D03*
Y1251742D03*
X905007Y1248920D03*
Y1245920D03*
X905074Y1252177D03*
X905007Y1241920D03*
X910707Y1257742D03*
X903980Y1268420D03*
X917112Y1266300D03*
X904024Y1272692D03*
X903947Y1276968D03*
X903899Y1281203D03*
X917127Y1275251D03*
X917396Y1271025D03*
X917158Y1279451D03*
X917341Y1283775D03*
X903945Y1285420D03*
X903923Y1289630D03*
X903651Y1293853D03*
X903690Y1298027D03*
X916895Y1292330D03*
X916945Y1296713D03*
X917034Y1288235D03*
X912500Y1310000D03*
X914333Y1322700D03*
X914462Y1329351D03*
X914355Y1340726D03*
X914276Y1347550D03*
X913270Y1440429D03*
X910041Y1440536D03*
X907031Y1457231D03*
X909473Y1448779D03*
X910850Y1556133D03*
X907850D03*
X916850D03*
X913850D03*
X907850Y1559133D03*
Y1562133D03*
X910850Y1559133D03*
Y1562133D03*
X907850Y1565133D03*
X910850D03*
X904850Y1559133D03*
Y1562133D03*
Y1565133D03*
X913850Y1559133D03*
Y1562133D03*
Y1565133D03*
X916850Y1559133D03*
Y1562133D03*
Y1565133D03*
X907850Y1568133D03*
Y1571133D03*
X910850Y1568133D03*
Y1571133D03*
X904850Y1568133D03*
Y1571133D03*
X913850Y1568133D03*
Y1571133D03*
X916850Y1568133D03*
Y1571133D03*
X905977Y1577233D03*
Y1582363D03*
X911577Y1577233D03*
X917077D03*
Y1582363D03*
X905977Y1587493D03*
X911577D03*
X917077D03*
X914550Y1597533D03*
Y1594533D03*
X905550D03*
X911550Y1597533D03*
Y1594533D03*
X908550Y1597533D03*
Y1594533D03*
X905550Y1597533D03*
X917550D03*
Y1594533D03*
X914550Y1600533D03*
X905550D03*
X911550D03*
X908550D03*
X917550D03*
X914550Y1603533D03*
Y1606533D03*
X905550Y1603533D03*
X908550D03*
X911550D03*
Y1606533D03*
X908550D03*
X905550D03*
X917550Y1603533D03*
Y1606533D03*
X915991Y1667328D03*
X905974Y1731920D03*
X920720Y145206D03*
X919886Y167000D03*
Y169500D03*
Y172000D03*
Y174500D03*
Y177000D03*
Y179500D03*
X922128Y182486D03*
X923386Y193563D03*
X927134Y189386D03*
X925321Y203399D03*
X932129Y244103D03*
X928224Y264072D03*
X922341Y263875D03*
X923103Y362852D03*
X924724Y372211D03*
X919294Y374503D03*
X921318Y372475D03*
X920018Y362877D03*
X921430Y507156D03*
X921367Y503407D03*
X924430Y507156D03*
X924367Y503407D03*
X922591Y496671D03*
X926730Y540897D03*
X921318Y549357D03*
X920031Y577846D03*
X926449Y577806D03*
X930406Y577308D03*
X923747Y584945D03*
X926983Y604751D03*
X920989Y614132D03*
X925643Y616620D03*
X927127Y619251D03*
X920989Y617692D03*
X924987Y622523D03*
X930926Y664791D03*
X932000Y850500D03*
X920234Y843349D03*
X927777Y843416D03*
X918500Y856925D03*
X930925Y860925D03*
X930575Y864075D03*
X918500Y860075D03*
X920897Y881879D03*
X929603Y879000D03*
Y889000D03*
X920000Y895500D03*
X923000D03*
X925500Y907500D03*
X921000Y921925D03*
X925500Y916500D03*
X929500D03*
X918000Y928000D03*
X932500Y941500D03*
X919500D03*
X928500D03*
X923500D03*
X926000Y949500D03*
Y946500D03*
X919272Y989932D03*
Y986782D03*
X925200Y1110443D03*
Y1107843D03*
Y1117443D03*
Y1114843D03*
Y1124443D03*
Y1121843D03*
Y1131443D03*
Y1128843D03*
X921477Y1134647D03*
X925525Y1135172D03*
X919880Y1146569D03*
Y1139969D03*
Y1143369D03*
Y1149769D03*
X922880Y1146569D03*
Y1139969D03*
Y1143369D03*
Y1149769D03*
X919077Y1136521D03*
X923125Y1137046D03*
X919880Y1152769D03*
X920107Y1235920D03*
Y1232920D03*
Y1238920D03*
Y1229920D03*
Y1251742D03*
Y1254742D03*
Y1248920D03*
Y1245920D03*
Y1241920D03*
Y1257742D03*
X928751Y1266347D03*
X928901Y1270408D03*
X928852Y1274591D03*
X928979Y1278713D03*
X928827Y1283048D03*
X928928Y1287193D03*
X928906Y1291676D03*
X928983Y1295957D03*
X924000Y1310000D03*
X924500Y1306000D03*
Y1302000D03*
X918000Y1312500D03*
X920738Y1321363D03*
X927869Y1317417D03*
X918000Y1321500D03*
X925459Y1315352D03*
X925500Y1319000D03*
X922000Y1324000D03*
Y1328000D03*
X931326Y1328467D03*
X931216Y1323050D03*
X923680Y1339520D03*
X918000Y1330500D03*
Y1339500D03*
X922000Y1342000D03*
X925500Y1333000D03*
Y1337000D03*
X919758Y1348990D03*
X922000Y1346000D03*
X922850Y1556133D03*
X919850D03*
X922850Y1559133D03*
Y1562133D03*
Y1565133D03*
X919850Y1559133D03*
Y1562133D03*
Y1565133D03*
X925650Y1581379D03*
X919850Y1568133D03*
Y1571133D03*
X922650Y1583347D03*
X920550Y1603533D03*
Y1606533D03*
X931798Y1660762D03*
X923798D03*
X921289Y1663187D03*
Y1666337D03*
X927798Y1660762D03*
X927974Y1731920D03*
X945721Y173389D03*
X943221D03*
Y176389D03*
X945721D03*
X935551Y173329D03*
X938161Y173389D03*
Y176389D03*
X935591Y176049D03*
X940721Y173389D03*
Y176389D03*
X935497Y195925D03*
X939271Y191419D03*
X935771D03*
X944520Y182094D03*
X936454Y184015D03*
X937267Y189010D03*
X945120Y193264D03*
X935497Y210098D03*
Y203012D03*
Y224272D03*
Y217185D03*
X938570Y233152D03*
X945380Y233962D03*
X935497Y231358D03*
X942763Y272340D03*
X942779Y277731D03*
X949181Y280131D03*
X939938Y386423D03*
X933390Y386405D03*
X944112Y386593D03*
X941764Y420403D03*
X944264D03*
X933390Y559943D03*
X939613Y562031D03*
X934302Y578318D03*
X937310Y580755D03*
X941764Y587884D03*
X944264D03*
X935766Y587692D03*
X945006Y593609D03*
X935649Y590751D03*
X939511Y597073D03*
X939391Y600571D03*
X935746Y611573D03*
X935783Y631192D03*
Y634051D03*
X937580Y655946D03*
X945602Y664653D03*
X946366Y668811D03*
X934539Y664648D03*
X934339Y668533D03*
X941478Y668648D03*
X939216Y664767D03*
X948644Y811190D03*
X938000Y862620D03*
X943000Y862823D03*
X944057Y882886D03*
X934925Y891425D03*
X945075Y891500D03*
X938500Y907500D03*
X946500Y915988D03*
X938500Y916500D03*
X934500D03*
X942500Y916340D03*
X933021Y933979D03*
X942631Y943162D03*
X936960Y942898D03*
X935368Y939182D03*
X944515Y939850D03*
X940000Y973500D03*
Y986500D03*
Y982500D03*
Y977500D03*
X941000Y1110557D03*
Y1107957D03*
Y1117557D03*
Y1114957D03*
Y1124557D03*
Y1121957D03*
Y1131557D03*
Y1128957D03*
X937148Y1134343D03*
X938507Y1137843D03*
X933234Y1145058D03*
X936393Y1148087D03*
X947305Y1150769D03*
X944820Y1156119D03*
X943101Y1219520D03*
Y1222520D03*
X946101D03*
Y1219520D03*
X943101Y1225520D03*
X946101D03*
X945691Y1229920D03*
Y1232920D03*
X940791Y1238920D03*
X935907Y1239520D03*
X945691Y1235920D03*
X940678Y1229763D03*
Y1232763D03*
Y1235763D03*
X935891Y1235586D03*
Y1232586D03*
Y1229586D03*
X945691Y1254742D03*
Y1251742D03*
X940791Y1248920D03*
Y1245920D03*
X940921Y1251857D03*
X936464Y1248844D03*
X940791Y1241920D03*
X945691Y1257742D03*
X940994Y1265636D03*
X941011Y1269499D03*
X941500Y1278059D03*
X941033Y1282115D03*
X946730Y1293219D03*
Y1290719D03*
X940919Y1290152D03*
X940937Y1294191D03*
X941083Y1286156D03*
X947135Y1287403D03*
X938000Y1309500D03*
Y1301500D03*
Y1304500D03*
X945872Y1304541D03*
Y1301500D03*
X945617Y1309500D03*
X935028Y1313769D03*
X933586Y1325501D03*
X933041Y1315920D03*
X935300Y1317525D03*
X939071Y1448219D03*
X949216Y1448337D03*
X944105Y1448317D03*
X936693Y1462328D03*
X939507Y1462497D03*
X945195Y1459453D03*
X942056Y1459650D03*
X939416Y1459600D03*
Y1456976D03*
X942056Y1457026D03*
X945195Y1456829D03*
X946402Y1491204D03*
X943902D03*
X936402D03*
X938902D03*
X941402D03*
X933778D03*
X946402Y1501204D03*
Y1498704D03*
Y1496204D03*
Y1493704D03*
X943902D03*
Y1496204D03*
Y1498704D03*
Y1501204D03*
X936402Y1493704D03*
Y1496204D03*
Y1498704D03*
Y1501204D03*
X938902Y1493704D03*
Y1496204D03*
Y1498704D03*
Y1501204D03*
X941402Y1493704D03*
Y1496204D03*
Y1498704D03*
Y1501204D03*
X933778Y1493704D03*
Y1496204D03*
Y1498704D03*
Y1501204D03*
X944406Y1532791D03*
X936150Y1582233D03*
Y1578233D03*
Y1590233D03*
Y1586233D03*
X939798Y1660762D03*
X943798D03*
X957421Y157699D03*
X960421D03*
X962243Y179917D03*
X948401Y176499D03*
X961407Y205125D03*
X950950Y284662D03*
X947821Y386567D03*
X958158Y449020D03*
X958049Y453912D03*
X958101Y457846D03*
X958255Y465811D03*
X959033Y487289D03*
X957380Y515233D03*
X960054Y516982D03*
X962035Y518988D03*
X954757Y593045D03*
X948156Y593912D03*
X955529Y614017D03*
X952497Y614080D03*
X951102Y628662D03*
X951099Y632206D03*
X954362Y633314D03*
Y630061D03*
X954259Y657371D03*
X958299Y659886D03*
X954361Y660215D03*
X957462Y668700D03*
X951886Y804495D03*
X951839Y812730D03*
X951895Y808163D03*
X951466Y816400D03*
X961592Y821737D03*
X949000Y850500D03*
X951000Y855425D03*
X958000Y865500D03*
Y862000D03*
X952425Y876575D03*
X949500Y870500D03*
Y886500D03*
X953925Y900500D03*
X951169Y910425D03*
X957075Y906500D03*
X960925D03*
X954500Y915988D03*
X950500Y916150D03*
X951500Y930925D03*
X948500Y937000D03*
X947748Y1146553D03*
X949407Y1137558D03*
X949507Y1140558D03*
X953498Y1158574D03*
X955958Y1232869D03*
Y1235869D03*
X955891Y1238920D03*
X955958Y1229869D03*
X955091Y1254742D03*
Y1251742D03*
X955891Y1245920D03*
Y1248920D03*
Y1241920D03*
X955000Y1267000D03*
X955091Y1257742D03*
X964669Y1271000D03*
X955000D03*
Y1275000D03*
Y1279000D03*
Y1283000D03*
Y1287000D03*
X947650Y1314500D03*
Y1319000D03*
Y1323500D03*
Y1328000D03*
Y1337000D03*
Y1332500D03*
Y1341500D03*
Y1346000D03*
X960313Y1362654D03*
X958306Y1448056D03*
X954541Y1448307D03*
X961566Y1448341D03*
X956693Y1459805D03*
X953630Y1456760D03*
X958383Y1462447D03*
X950902Y1459500D03*
X948262Y1459450D03*
X953616Y1459608D03*
X948262Y1456826D03*
X950902Y1456876D03*
X953902Y1491204D03*
X951402D03*
X948902D03*
X956402D03*
X958902D03*
X961402D03*
X953902Y1501204D03*
Y1498704D03*
Y1496204D03*
Y1493704D03*
X951402Y1501204D03*
Y1498704D03*
Y1496204D03*
Y1493704D03*
X948902Y1501204D03*
Y1498704D03*
Y1496204D03*
Y1493704D03*
X956402D03*
X958902D03*
X961402D03*
X963402Y1501204D03*
X958402D03*
X955350Y1532760D03*
X961350D03*
X958350D03*
X959584Y1550824D03*
X953520Y1567570D03*
X950520D03*
X959520D03*
X956520D03*
X953520Y1582570D03*
X950520D03*
Y1579570D03*
X953520D03*
Y1576570D03*
X950520D03*
X953520Y1573570D03*
X950520D03*
Y1570570D03*
X953520D03*
X959520Y1582570D03*
X956520D03*
Y1579570D03*
X959520D03*
Y1576570D03*
X956520D03*
X959520Y1573570D03*
X956520D03*
Y1570570D03*
X959520D03*
X953520Y1588570D03*
X950520D03*
Y1585570D03*
X953520D03*
X959520Y1588570D03*
X956520D03*
Y1585570D03*
X959520D03*
X960518Y1656185D03*
X957758D03*
X949195Y1655145D03*
X957848Y1659375D03*
X960608D03*
X960558Y1662015D03*
X957798D03*
X947798Y1660762D03*
X951798D03*
X949974Y1731920D03*
X964720Y145206D03*
X975689Y156950D03*
Y153950D03*
X975691Y161220D03*
X964743Y179917D03*
X963985Y177154D03*
X962673Y170263D03*
Y167763D03*
X967943Y204813D03*
X971943D03*
X975749Y202049D03*
X977221Y205399D03*
X964807Y205125D03*
X971192Y219589D03*
X968692D03*
X973616Y317648D03*
X973997Y320848D03*
X966278Y556736D03*
X964114Y554704D03*
X976528Y801041D03*
Y803541D03*
Y806041D03*
Y808541D03*
X963500Y854719D03*
X973562Y859767D03*
X963134Y882936D03*
X964075Y900500D03*
X977150Y1052684D03*
X968919Y1116177D03*
Y1118777D03*
Y1109177D03*
Y1111777D03*
X968800Y1130046D03*
Y1132646D03*
X968919Y1123177D03*
Y1125777D03*
X967315Y1135550D03*
X972109Y1135149D03*
X966905Y1146569D03*
X969905D03*
X966905Y1139969D03*
Y1143369D03*
X969905Y1139969D03*
Y1143369D03*
X966905Y1149769D03*
X969905D03*
X963012Y1139511D03*
X964915Y1137424D03*
X969709Y1137023D03*
X966905Y1152769D03*
X966804Y1155658D03*
X969907Y1219520D03*
Y1222520D03*
X966907D03*
Y1219520D03*
Y1225520D03*
X969907D03*
X969691Y1229920D03*
Y1232920D03*
X963991Y1238920D03*
X969691Y1235920D03*
X963992Y1229940D03*
Y1232940D03*
Y1235940D03*
X979091Y1229920D03*
X969691Y1254742D03*
Y1251742D03*
X963991Y1248920D03*
Y1245920D03*
X964058Y1252177D03*
X963991Y1241920D03*
X969691Y1257742D03*
X964000Y1267000D03*
X966441Y1278145D03*
X968594Y1288193D03*
X975000Y1307500D03*
X966000Y1300000D03*
X968500D03*
X971000D03*
X972408Y1312557D03*
X967500Y1340241D03*
X973650Y1431424D03*
X969785Y1447987D03*
X967002Y1448013D03*
X964503Y1448097D03*
X969519Y1452784D03*
X973255Y1456714D03*
X975703Y1451367D03*
X967268Y1491204D03*
X969768D03*
X972268D03*
X974768D03*
X977268D03*
X963902D03*
X967268Y1501204D03*
Y1498704D03*
Y1496204D03*
Y1493704D03*
X969768D03*
Y1496204D03*
Y1498704D03*
Y1501204D03*
X972268Y1493704D03*
Y1496204D03*
Y1498704D03*
Y1501204D03*
X974768Y1493704D03*
Y1496204D03*
Y1498704D03*
Y1501204D03*
X977268Y1493704D03*
Y1496204D03*
Y1498704D03*
Y1501204D03*
X963902Y1493704D03*
X963120Y1520080D03*
Y1523080D03*
X967350Y1532760D03*
X964350D03*
X963120Y1526080D03*
X962584Y1550824D03*
X965520Y1567570D03*
X962520D03*
X968520D03*
X965520Y1582570D03*
X962520D03*
Y1579570D03*
X965520D03*
Y1576570D03*
X962520D03*
X965520Y1573570D03*
X962520D03*
Y1570570D03*
X965520D03*
X968520Y1582570D03*
Y1579570D03*
Y1576570D03*
Y1573570D03*
Y1570570D03*
X965520Y1588570D03*
X962520D03*
Y1585570D03*
X965520D03*
X968520Y1588570D03*
Y1585570D03*
X976858Y1656185D03*
X976898Y1662015D03*
X976948Y1659375D03*
X971974Y1731920D03*
X986720Y145206D03*
X990579Y155248D03*
X981112Y161204D03*
X988751Y167541D03*
X986447Y158209D03*
X989605Y175400D03*
X985922Y171861D03*
X988593Y189347D03*
X981445Y185389D03*
X985445D03*
X986021Y195099D03*
X979849Y202049D03*
X983879Y202162D03*
X990221Y199699D03*
X987321Y198599D03*
Y202099D03*
X990221Y206699D03*
Y203199D03*
X987321Y205599D03*
X991553Y216809D03*
X980406Y218283D03*
X980377Y215740D03*
X982455Y264781D03*
X978269Y264929D03*
X982455Y260781D03*
Y271443D03*
Y275443D03*
X978827Y303412D03*
X984509Y303623D03*
X989582Y303563D03*
X988460Y354725D03*
Y358405D03*
X993460D03*
X984272Y349293D03*
X980346Y353527D03*
X981019Y349387D03*
X992233Y373679D03*
X992460Y370659D03*
X985668Y389311D03*
X980690Y387784D03*
X989227Y389311D03*
X984605Y408480D03*
X987581Y408332D03*
X988190Y424626D03*
X983358Y449026D03*
X991664Y446372D03*
X993650Y465315D03*
X988650D03*
X991270Y470212D03*
X992037Y485369D03*
X990292Y494420D03*
X988125Y485193D03*
X986790Y480140D03*
X987440Y504742D03*
X982806Y498606D03*
X986056Y516014D03*
X994056Y521014D03*
Y516014D03*
Y526074D03*
X991031Y528574D03*
X994056Y531074D03*
X992125Y1061434D03*
X989125D03*
X986125D03*
X983125D03*
X992125Y1064984D03*
Y1067984D03*
X989125D03*
Y1064984D03*
X992125Y1074534D03*
Y1070984D03*
X989125D03*
Y1074534D03*
X986125D03*
X983125D03*
X986356Y1087508D03*
X983156D03*
Y1084108D03*
X986356D03*
X989556Y1087508D03*
Y1084108D03*
X986356Y1097008D03*
X983156D03*
Y1100408D03*
X986356D03*
X989556Y1097008D03*
Y1100408D03*
X979091Y1235920D03*
Y1232920D03*
Y1238920D03*
Y1251742D03*
Y1254742D03*
Y1248920D03*
Y1245920D03*
Y1241920D03*
Y1257742D03*
X985396Y1268154D03*
X982665Y1265474D03*
X978318Y1263128D03*
X979228Y1297918D03*
X982000Y1307500D03*
X978026Y1459998D03*
X980779Y1451545D03*
X990634Y1491204D03*
X979768D03*
X982268D03*
X984768D03*
X987268D03*
X990634Y1493704D03*
Y1496204D03*
Y1498704D03*
Y1501204D03*
X979768Y1493704D03*
X982268D03*
X984768D03*
X987268D03*
X986768Y1501204D03*
X981768D03*
X986486Y1523080D03*
Y1520080D03*
Y1526080D03*
X991280Y1532760D03*
X988280D03*
X991196Y1550840D03*
X988160Y1567710D03*
X991160D03*
X985160D03*
X988160Y1582710D03*
X991160D03*
X985160D03*
Y1579710D03*
X991160D03*
X988160D03*
X991160Y1570710D03*
X988160D03*
Y1573710D03*
X991160D03*
X988160Y1576710D03*
X991160D03*
X985160Y1570710D03*
Y1573710D03*
Y1576710D03*
X988160Y1588710D03*
X991160D03*
X985160D03*
Y1585710D03*
X991160D03*
X988160D03*
X985318Y1656105D03*
X988078D03*
X979618Y1656185D03*
X985358Y1661935D03*
X988118D03*
X985408Y1659295D03*
X988168D03*
X979658Y1662015D03*
X979708Y1659375D03*
X1002736Y157943D03*
X999736D03*
X1006221Y164799D03*
X1002721D03*
X1005307Y155043D03*
X995181Y157689D03*
X999580Y154895D03*
X994257D03*
X993306Y174953D03*
X993206Y178053D03*
X1006436Y176843D03*
X996416Y176579D03*
X1002921Y178799D03*
X1002827Y172479D03*
X999916Y184548D03*
X996416D03*
X992506Y184553D03*
X999221Y189299D03*
X1002721D03*
X1006161Y189019D03*
X1008918Y192994D03*
X1008121Y203525D03*
X1000611Y215039D03*
X1005641Y214969D03*
X1001196Y223898D03*
X997300Y234876D03*
X995189Y263340D03*
Y274002D03*
X992915Y280389D03*
X1006468Y301857D03*
X993460Y354725D03*
X998460D03*
X1003460Y358405D03*
X998460D03*
X994409Y349813D03*
X1007083Y363461D03*
X997488Y370287D03*
X1000460Y369535D03*
X996889Y374156D03*
X1007080Y367087D03*
X999320Y394480D03*
X1006763Y396206D03*
X996232Y424440D03*
X1003651Y433426D03*
X998859Y437141D03*
X998359Y451675D03*
X994900Y446192D03*
X998359Y462675D03*
Y457175D03*
X1003909Y454662D03*
Y460162D03*
X998359Y479175D03*
Y468175D03*
Y473675D03*
X996320Y470364D03*
X998359Y484675D03*
X1007077Y484937D03*
X998326Y499675D03*
X995530Y500034D03*
X998056Y518214D03*
Y523874D03*
X1006206Y510304D03*
X1002056Y521014D03*
Y516014D03*
Y526074D03*
X999031Y528574D03*
X1002056Y531074D03*
X1004527Y541924D03*
Y553224D03*
X1005270Y625710D03*
X1003090Y1037329D03*
X999894Y1267126D03*
X999303Y1285693D03*
X999350Y1310500D03*
Y1315000D03*
Y1319420D03*
Y1323840D03*
Y1328260D03*
Y1332740D03*
Y1341580D03*
Y1337160D03*
Y1346000D03*
X995500Y1368000D03*
X998000Y1365500D03*
X995000Y1362000D03*
X1000634Y1491204D03*
X998134D03*
X995634D03*
X993134D03*
X1003134D03*
X1005634D03*
X993134Y1496204D03*
Y1493704D03*
X1003134D03*
X1005634D03*
X1000634Y1501204D03*
Y1498704D03*
Y1496204D03*
Y1493704D03*
X998134Y1501204D03*
Y1498704D03*
Y1496204D03*
Y1493704D03*
X995634Y1501204D03*
Y1498704D03*
Y1496204D03*
Y1493704D03*
X993134Y1501204D03*
Y1498704D03*
X1005134Y1501204D03*
X994280Y1532760D03*
X997280D03*
X1000280D03*
X994196Y1550840D03*
X994160Y1567710D03*
X997160D03*
X1000160D03*
X994160Y1582710D03*
X997160D03*
Y1579710D03*
X994160D03*
X997160Y1570710D03*
X994160D03*
Y1573710D03*
X997160D03*
X994160Y1576710D03*
X997160D03*
X1000160Y1582710D03*
Y1579710D03*
Y1570710D03*
Y1573710D03*
Y1576710D03*
X994160Y1588710D03*
X997160D03*
Y1585710D03*
X994160D03*
X1000160Y1588710D03*
Y1585710D03*
X1004418Y1656105D03*
X1007178D03*
X1004508Y1659295D03*
X1004458Y1661935D03*
X993974Y1731920D03*
X1021899Y61590D03*
Y127590D03*
X1008720Y145206D03*
X1020661Y146580D03*
X1009721Y164799D03*
X1013221D03*
X1014301Y179699D03*
X1017201D03*
X1019901Y179799D03*
X1023221Y191574D03*
X1011358Y195324D03*
X1011991Y189019D03*
X1014901Y189299D03*
X1017701Y189059D03*
X1011120Y198114D03*
X1020521Y194499D03*
X1008068Y198387D03*
X1019936Y207333D03*
Y210463D03*
X1011068Y207667D03*
X1019803Y218099D03*
X1019356Y222423D03*
X1010909Y213708D03*
X1011721Y233699D03*
X1019531Y230423D03*
X1021220Y243638D03*
X1012220D03*
X1018220D03*
X1015220D03*
X1009220D03*
X1007669Y268884D03*
Y258222D03*
X1014828Y268427D03*
Y258970D03*
X1013396Y280806D03*
X1011423Y282889D03*
X1023110Y287311D03*
X1017870Y294386D03*
X1017835Y291236D03*
X1023000Y298311D03*
X1016764Y350082D03*
X1010252Y363440D03*
X1009618Y396125D03*
X1021425Y404925D03*
X1009815Y404896D03*
X1020748Y420902D03*
X1013365Y433426D03*
X1020748Y425902D03*
X1023420Y462921D03*
X1017220Y464155D03*
X1023515Y454397D03*
X1019205Y457687D03*
X1023420Y468039D03*
X1017350Y472155D03*
X1022874Y474545D03*
X1019210Y480155D03*
X1008789Y488642D03*
Y493655D03*
X1014206Y510304D03*
X1013306Y518146D03*
Y526146D03*
Y528942D03*
Y532501D03*
X1012211Y547574D03*
X1015061D03*
X1017718Y541201D03*
X1019161Y554757D03*
X1024161D03*
X1017961Y545074D03*
X1009611Y550074D03*
Y545074D03*
X1015961Y554432D03*
X1021425Y568614D03*
X1012925Y558000D03*
X1011602Y568473D03*
X1016000Y563107D03*
X1019261Y571324D03*
X1007703Y759012D03*
X1007587Y761546D03*
Y767480D03*
Y769980D03*
Y772480D03*
Y775880D03*
Y764946D03*
Y780880D03*
Y778380D03*
Y789484D03*
Y791984D03*
Y783482D03*
Y786882D03*
Y800384D03*
Y802884D03*
Y805418D03*
Y794484D03*
Y797884D03*
Y811352D03*
Y813852D03*
Y822252D03*
Y816352D03*
Y819752D03*
Y808818D03*
Y824752D03*
Y833356D03*
Y835856D03*
Y827354D03*
Y830754D03*
Y844256D03*
Y838356D03*
Y841756D03*
X1010894Y1271743D03*
X1010865Y1275768D03*
X1010944Y1279751D03*
X1021908Y1289124D03*
X1019314Y1289159D03*
X1017069Y1290346D03*
X1013500Y1312500D03*
X1013000Y1306500D03*
X1010650Y1310500D03*
X1016000Y1303000D03*
X1009905Y1305500D03*
X1009896Y1301500D03*
X1013500Y1325500D03*
X1013605Y1316050D03*
X1013529Y1318950D03*
X1012500Y1322500D03*
Y1328500D03*
X1011500Y1335000D03*
X1012500Y1341580D03*
X1013500Y1332740D03*
Y1337160D03*
Y1344500D03*
X1016000Y1361000D03*
X1012500Y1347500D03*
X1021500Y1491204D03*
X1019000D03*
X1016500D03*
X1014000D03*
X1008134D03*
X1010634D03*
X1021500Y1501204D03*
Y1498704D03*
Y1496204D03*
Y1493704D03*
X1019000Y1501204D03*
Y1498704D03*
Y1496204D03*
Y1493704D03*
X1016500Y1501204D03*
Y1498704D03*
Y1496204D03*
Y1493704D03*
X1014000D03*
Y1496204D03*
Y1498704D03*
Y1501204D03*
X1008134Y1493704D03*
X1010634D03*
X1010134Y1501204D03*
X1009852Y1523080D03*
Y1520080D03*
Y1526080D03*
X1019440Y1532930D03*
X1022796Y1550840D03*
X1016750Y1567710D03*
X1019750D03*
X1016750Y1576710D03*
Y1573710D03*
Y1570710D03*
X1019750Y1576710D03*
Y1573710D03*
Y1570710D03*
Y1579710D03*
X1016750D03*
Y1582710D03*
X1019750D03*
Y1585710D03*
X1016750D03*
Y1588710D03*
X1019750D03*
X1007268Y1659295D03*
X1007218Y1661935D03*
X1015974Y1731920D03*
X1023187Y146580D03*
X1022801Y179799D03*
X1027690Y237902D03*
X1024220Y243638D03*
X1033590Y298311D03*
Y287311D03*
X1029200Y351614D03*
X1022674Y357848D03*
X1028146Y355960D03*
X1034214Y351601D03*
X1027724Y397726D03*
X1030525Y391362D03*
X1029601Y394387D03*
X1034855Y411704D03*
X1034409Y429618D03*
X1024443Y424051D03*
X1034899Y444404D03*
X1025830Y449022D03*
X1027760Y451832D03*
X1023320Y451112D03*
X1035860Y485976D03*
X1027504Y485637D03*
X1024509Y500168D03*
X1024546Y511254D03*
X1037254Y521014D03*
X1036708Y514883D03*
X1037254Y526074D03*
X1032354Y538201D03*
X1022686D03*
X1025631Y540104D03*
X1036021Y534990D03*
X1027520Y552724D03*
X1030000Y554500D03*
X1034412Y567416D03*
X1022461Y558932D03*
X1027579D03*
X1032579Y559934D03*
X1031000Y568500D03*
X1028500Y563000D03*
X1024000D03*
X1029431Y587342D03*
X1032055Y587260D03*
X1028540Y621000D03*
X1035269Y735474D03*
X1032736Y735320D03*
X1030190Y735023D03*
X1025493Y758819D03*
Y761819D03*
X1035026Y756009D03*
X1025493Y768719D03*
X1035645Y773582D03*
X1036427Y770532D03*
X1038867Y774960D03*
X1025493Y765719D03*
X1033236Y1279287D03*
X1033184Y1275996D03*
X1036411Y1275658D03*
X1036463Y1278949D03*
X1024000Y1491204D03*
X1026500D03*
X1029000D03*
X1031500D03*
X1034000D03*
X1024000Y1501204D03*
Y1498704D03*
Y1496204D03*
Y1493704D03*
X1026500D03*
X1029000D03*
X1031500D03*
X1034000D03*
X1033500Y1501204D03*
X1028500D03*
X1033218Y1523080D03*
Y1520080D03*
X1025440Y1532930D03*
X1022440D03*
X1033218Y1526080D03*
X1031440Y1532930D03*
X1028440D03*
X1025796Y1550840D03*
X1022750Y1567710D03*
X1025750D03*
X1031750D03*
X1028750D03*
X1022750Y1576710D03*
X1025750D03*
X1022750Y1573710D03*
X1025750D03*
Y1570710D03*
X1022750D03*
X1025750Y1579710D03*
X1022750D03*
Y1582710D03*
X1025750D03*
X1028750Y1576710D03*
Y1573710D03*
Y1570710D03*
Y1579710D03*
Y1582710D03*
X1031750Y1576710D03*
Y1573710D03*
Y1570710D03*
Y1579710D03*
Y1582710D03*
X1025750Y1585710D03*
X1022750D03*
Y1588710D03*
X1025750D03*
X1028750Y1585710D03*
Y1588710D03*
X1031750Y1585710D03*
Y1588710D03*
X1033798Y1656675D03*
X1033748Y1659315D03*
X1040199Y49379D03*
X1044012Y268659D03*
X1051495Y265133D03*
X1046384Y269814D03*
X1049451Y266747D03*
X1040060Y313528D03*
X1051873Y305482D03*
X1040891Y406586D03*
X1049573D03*
X1045100Y427059D03*
X1042015Y444404D03*
X1047515D03*
X1045015D03*
X1043377Y452740D03*
X1040836Y510894D03*
X1045254Y521074D03*
X1041254Y523874D03*
X1037212Y510940D03*
X1045254Y516014D03*
X1040097Y529508D03*
X1045254Y534074D03*
Y526074D03*
X1043991Y540979D03*
X1043180Y547027D03*
X1047335Y549574D03*
X1047200Y543090D03*
X1037301Y539685D03*
X1039407Y547723D03*
X1039000Y555000D03*
X1039718Y563268D03*
X1042628Y556845D03*
X1050956Y591090D03*
X1040626Y668441D03*
X1042389Y733426D03*
X1040890Y735717D03*
X1044056Y736188D03*
X1040915Y766870D03*
X1037566Y1047135D03*
X1037895Y1251517D03*
X1039546Y1275474D03*
X1039598Y1278765D03*
X1042855Y1275552D03*
X1042649Y1279152D03*
X1047366Y1491204D03*
X1044866D03*
X1037366D03*
X1042366D03*
X1039866D03*
X1049866D03*
X1047366Y1498704D03*
Y1496204D03*
Y1493704D03*
X1044866Y1496204D03*
Y1493704D03*
X1037366D03*
Y1496204D03*
Y1498704D03*
X1047366Y1501204D03*
X1044866D03*
Y1498704D03*
X1042366Y1501204D03*
Y1498704D03*
Y1496204D03*
Y1493704D03*
X1039866Y1501204D03*
Y1498704D03*
Y1496204D03*
Y1493704D03*
X1037366Y1501204D03*
X1049866Y1493704D03*
X1051866Y1501204D03*
X1051110Y1532850D03*
X1048219Y1567883D03*
X1051219D03*
X1048219Y1576883D03*
Y1573883D03*
Y1570883D03*
X1051219Y1576883D03*
Y1573883D03*
Y1570883D03*
Y1579883D03*
X1048219D03*
Y1582883D03*
X1051219D03*
Y1585883D03*
X1048219D03*
Y1588883D03*
X1051219D03*
X1050866Y1659548D03*
X1053290Y1652082D03*
X1045545Y1663089D03*
X1037974Y1731920D03*
X1062199Y49379D03*
X1066231Y165078D03*
Y167578D03*
X1054355Y258698D03*
X1062704Y270875D03*
X1056941Y259176D03*
X1054613Y261586D03*
X1065552Y271441D03*
X1062923Y295053D03*
X1063356Y318297D03*
X1055934Y385488D03*
Y388988D03*
X1068143Y380188D03*
X1055934Y381988D03*
X1061456Y406560D03*
X1052505Y406576D03*
X1057798Y427059D03*
Y429618D03*
X1062642Y444859D03*
X1062640Y449155D03*
X1062741Y457959D03*
X1057276Y458155D03*
X1062173Y479655D03*
X1059055Y492537D03*
X1062873Y490180D03*
X1055905Y492537D03*
X1062250Y484672D03*
X1056960Y482262D03*
X1057450Y509242D03*
X1058231Y523238D03*
X1056517Y512787D03*
X1061837Y519703D03*
X1060719Y512359D03*
X1063614Y733409D03*
X1061817Y736362D03*
X1065154Y736282D03*
X1057057Y767299D03*
Y771099D03*
X1060721Y1313954D03*
X1055171Y1307203D03*
Y1311203D03*
X1058143Y1433809D03*
X1065732Y1491204D03*
X1063232D03*
X1060732D03*
X1052366D03*
X1054866D03*
X1057366D03*
X1065732Y1501204D03*
Y1498704D03*
Y1496204D03*
Y1493704D03*
X1063232Y1501204D03*
Y1498704D03*
Y1496204D03*
Y1493704D03*
X1060732D03*
Y1496204D03*
Y1498704D03*
Y1501204D03*
X1052366Y1493704D03*
X1054866D03*
X1057366D03*
X1056866Y1501204D03*
X1056584Y1523080D03*
Y1520080D03*
X1057110Y1532850D03*
X1054110D03*
X1056584Y1526080D03*
X1063110Y1532850D03*
X1060110D03*
X1057396Y1550840D03*
X1054396D03*
X1054219Y1567883D03*
X1057219D03*
X1060219D03*
X1063219D03*
X1066219D03*
X1054219Y1576883D03*
X1057219D03*
X1054219Y1573883D03*
X1057219D03*
Y1570883D03*
X1054219D03*
X1057219Y1579883D03*
X1054219D03*
Y1582883D03*
X1057219D03*
X1060219Y1576883D03*
Y1573883D03*
Y1570883D03*
Y1579883D03*
Y1582883D03*
X1063219Y1576883D03*
Y1573883D03*
Y1570883D03*
X1066219Y1576883D03*
Y1573883D03*
Y1570883D03*
Y1579883D03*
X1063219D03*
Y1582883D03*
X1066219D03*
X1057219Y1585883D03*
X1054219D03*
Y1588883D03*
X1057219D03*
X1060219Y1585883D03*
Y1588883D03*
X1066219Y1585883D03*
X1063219D03*
Y1588883D03*
X1066219D03*
X1063751Y1653834D03*
X1064221Y1662726D03*
X1068221Y1662778D03*
X1061974Y1731920D03*
X1071698Y270702D03*
X1078823Y269400D03*
X1071656Y366726D03*
X1068143Y383688D03*
X1068827Y389734D03*
X1073204Y383417D03*
X1078400Y391226D03*
X1074654Y380188D03*
X1078400Y383226D03*
X1074249Y387795D03*
X1082866Y403068D03*
X1074800Y391262D03*
X1074736Y396929D03*
X1072135Y396908D03*
X1077418Y411322D03*
Y416763D03*
X1072738Y411322D03*
Y416763D03*
Y421922D03*
X1077418D03*
X1072673Y428791D03*
X1081133Y461516D03*
X1077873Y463444D03*
X1080453Y457959D03*
X1071239Y479655D03*
X1071470Y475525D03*
X1080640Y467000D03*
X1080574Y471500D03*
X1071667D03*
Y467000D03*
X1080416Y482772D03*
X1080420Y487782D03*
X1071710Y483655D03*
Y488782D03*
X1081730Y509172D03*
X1081632Y648854D03*
X1078499Y648202D03*
X1072232Y667749D03*
X1068378Y736795D03*
X1070616Y766870D03*
X1076903Y1300361D03*
Y1302861D03*
X1079403D03*
Y1300361D03*
X1074403Y1302861D03*
Y1300361D03*
X1076903Y1305361D03*
X1079403D03*
X1074403D03*
Y1307861D03*
Y1310361D03*
Y1312861D03*
X1079403Y1307861D03*
Y1310361D03*
Y1312861D03*
X1076903D03*
Y1310361D03*
Y1307861D03*
X1079403Y1315361D03*
X1076903D03*
Y1317861D03*
X1079403D03*
X1074403D03*
Y1315361D03*
X1070949Y1337752D03*
X1067929Y1337702D03*
X1069839Y1368999D03*
Y1371540D03*
X1073733Y1388198D03*
X1076601Y1382574D03*
X1071332Y1379914D03*
X1076601Y1380066D03*
X1080555Y1380511D03*
X1073612Y1376389D03*
X1081005Y1425458D03*
X1071117Y1445005D03*
X1077031Y1451498D03*
X1070312Y1452028D03*
X1073307Y1451931D03*
X1070732Y1491204D03*
X1068232D03*
X1073232D03*
X1075732D03*
X1078232D03*
X1080732D03*
X1070732Y1501204D03*
Y1498704D03*
Y1496204D03*
Y1493704D03*
X1068232Y1501204D03*
Y1498704D03*
Y1496204D03*
Y1493704D03*
X1073232D03*
X1075732D03*
X1078232D03*
X1080732D03*
X1080232Y1501204D03*
X1075232D03*
X1068094Y1654099D03*
X1072134Y1647920D03*
X1081011Y1685499D03*
X1078011D03*
X1081011Y1682499D03*
X1078011D03*
X1077172Y1676686D03*
X1077881Y1688252D03*
X1080933Y1688245D03*
X1078016Y1691207D03*
X1080966Y1691320D03*
X1084199Y49379D03*
X1087421Y149716D03*
X1081857Y269856D03*
X1083819Y353094D03*
X1086714Y353515D03*
X1086936Y370532D03*
X1090086Y370417D03*
X1083583Y395195D03*
X1093722Y427960D03*
X1090061Y428019D03*
X1087963Y440605D03*
Y446105D03*
X1084840Y438234D03*
Y443515D03*
X1087963Y462605D03*
Y457105D03*
X1087940Y452110D03*
X1084840Y460005D03*
X1085851Y465978D03*
X1087000Y477500D03*
X1087963Y468105D03*
X1095448Y479426D03*
X1084000Y477500D03*
X1090000D03*
X1096473Y484391D03*
Y489391D03*
X1087963Y484605D03*
Y494641D03*
Y489641D03*
X1083434Y481500D03*
X1085730Y509362D03*
X1091730D03*
X1088730D03*
X1095730D03*
X1082622Y520652D03*
X1082438Y524033D03*
X1085438D03*
X1085622Y520652D03*
X1083281Y651601D03*
X1091270Y668286D03*
X1086758Y767299D03*
Y771099D03*
X1090203Y1307861D03*
Y1310361D03*
Y1312861D03*
X1092703D03*
Y1310361D03*
Y1307861D03*
Y1300361D03*
Y1302861D03*
X1090203D03*
Y1300361D03*
X1095203Y1302861D03*
Y1300361D03*
X1092703Y1305361D03*
X1090203D03*
X1095203D03*
Y1307861D03*
Y1310361D03*
Y1312861D03*
X1090203Y1315361D03*
X1092703D03*
Y1317861D03*
X1090203D03*
X1095203D03*
Y1315361D03*
X1095809Y1337824D03*
X1095629Y1352252D03*
Y1349652D03*
Y1354852D03*
X1092889Y1367278D03*
Y1370178D03*
X1083368Y1385268D03*
X1084043Y1382111D03*
X1083293Y1379543D03*
X1094683Y1379188D03*
Y1376288D03*
X1091598Y1491204D03*
X1089098D03*
X1086598D03*
X1084098D03*
X1091598Y1501204D03*
Y1498704D03*
Y1496204D03*
Y1493704D03*
X1089098Y1501204D03*
Y1498704D03*
Y1496204D03*
Y1493704D03*
X1086598Y1501204D03*
Y1498704D03*
Y1496204D03*
Y1493704D03*
X1084098D03*
Y1498704D03*
Y1501204D03*
Y1496204D03*
X1090300Y1532660D03*
X1087300D03*
X1096300D03*
X1093300D03*
X1089934Y1550784D03*
X1092934D03*
X1094399Y1568043D03*
X1091399D03*
X1085399D03*
X1088399D03*
X1091399Y1580043D03*
X1094399D03*
Y1571043D03*
Y1574043D03*
Y1577043D03*
X1091399Y1571043D03*
Y1574043D03*
Y1577043D03*
X1088399Y1580043D03*
X1085399D03*
X1088399Y1571043D03*
X1085399D03*
Y1574043D03*
X1088399D03*
X1085399Y1577043D03*
X1088399D03*
X1094399Y1583043D03*
X1091399D03*
X1085399D03*
X1088399D03*
X1094399Y1589043D03*
X1091399D03*
Y1586043D03*
X1094399D03*
X1085399Y1589043D03*
X1088399D03*
Y1586043D03*
X1085399D03*
X1097000Y1629500D03*
X1096469Y1643468D03*
X1096500Y1639000D03*
X1096768Y1635080D03*
X1090143Y1643625D03*
X1091026Y1653031D03*
X1090958Y1646528D03*
Y1649928D03*
X1084629Y1673002D03*
X1087141Y1688914D03*
X1089030Y1691229D03*
X1092980Y1696029D03*
Y1699179D03*
X1092030Y1715841D03*
X1095489Y1708519D03*
X1089030Y1717841D03*
X1081974Y1731920D03*
X1092030Y1725991D03*
Y1720841D03*
X1089030Y1722841D03*
X1106199Y49379D03*
X1099500Y318000D03*
X1111001Y361272D03*
X1101942Y395361D03*
X1107300Y456944D03*
X1111076Y464388D03*
X1108076Y646774D03*
X1104443Y646983D03*
X1100316Y766870D03*
X1109503Y1302861D03*
X1107003D03*
Y1300361D03*
X1109503Y1305361D03*
X1107003D03*
Y1307861D03*
Y1310361D03*
Y1312861D03*
X1109503Y1307861D03*
Y1310361D03*
Y1312861D03*
Y1300361D03*
Y1315361D03*
Y1317861D03*
X1107003D03*
Y1315361D03*
X1103529Y1337792D03*
X1109289Y1337752D03*
X1098409Y1337824D03*
X1098229Y1352252D03*
Y1349652D03*
X1096979Y1357352D03*
X1098229Y1354852D03*
X1102439Y1368999D03*
Y1371540D03*
X1098949Y1373158D03*
X1103888Y1386721D03*
X1102230Y1384770D03*
X1109201Y1382574D03*
X1103932Y1379914D03*
X1109201Y1380066D03*
X1106212Y1376389D03*
X1098949Y1378958D03*
X1096849Y1377558D03*
X1098949Y1376058D03*
X1096749Y1374558D03*
X1099098Y1501204D03*
X1102248Y1496186D03*
X1106700Y1526591D03*
X1112529Y1547661D03*
X1111701Y1558640D03*
X1097399Y1568043D03*
Y1580043D03*
Y1571043D03*
Y1574043D03*
Y1577043D03*
Y1583043D03*
Y1589043D03*
Y1586043D03*
X1107181Y1615917D03*
X1109811D03*
X1098549Y1625749D03*
X1100961Y1622543D03*
X1109000Y1671107D03*
X1105000Y1682132D03*
X1105148Y1696029D03*
X1099108Y1691229D03*
X1100998Y1715841D03*
X1109521Y1724109D03*
X1100998Y1725991D03*
X1103351Y1737117D03*
X1119676Y54132D03*
X1124834Y56805D03*
X1124270Y404640D03*
X1121628Y401915D03*
X1113943Y452055D03*
X1121077Y511498D03*
X1125077D03*
X1118435Y625307D03*
X1114467Y640802D03*
X1120321Y635832D03*
X1116540Y651070D03*
X1112190Y651962D03*
X1116459Y767299D03*
Y771099D03*
X1112003Y1302861D03*
Y1300361D03*
Y1305361D03*
X1122803Y1307861D03*
X1125303D03*
Y1310361D03*
Y1312861D03*
X1122803D03*
Y1310361D03*
X1112003Y1312861D03*
Y1310361D03*
Y1307861D03*
X1125303Y1300361D03*
Y1302861D03*
X1122803D03*
Y1300361D03*
X1125303Y1305361D03*
X1122803D03*
X1125303Y1315361D03*
X1122803D03*
X1112003D03*
Y1317861D03*
X1125303D03*
X1122803D03*
X1125469Y1367108D03*
Y1370008D03*
X1115968Y1385268D03*
X1116643Y1382111D03*
X1113155Y1380511D03*
X1115893Y1379543D03*
X1124375Y1423488D03*
X1124415Y1426168D03*
Y1428668D03*
Y1431168D03*
Y1433668D03*
X1115098Y1468871D03*
Y1472271D03*
X1124875Y1490042D03*
X1125498Y1487292D03*
X1116917Y1506823D03*
X1119912Y1506936D03*
X1116917Y1509898D03*
X1119912Y1509891D03*
Y1515644D03*
X1116917D03*
X1119912Y1512644D03*
X1116917D03*
X1114617Y1526318D03*
X1119067Y1551457D03*
X1113887Y1543447D03*
X1119459Y1556343D03*
X1118326Y1594118D03*
X1118004Y1584908D03*
X1118133Y1587998D03*
Y1591398D03*
X1113785Y1601462D03*
X1117263Y1601526D03*
X1115027Y1598788D03*
X1117247Y1604554D03*
X1113847D03*
X1115394Y1620306D03*
X1124532Y1634915D03*
X1114286Y1630507D03*
X1117136Y1630441D03*
X1113490Y1651862D03*
X1116000Y1671029D03*
X1125732Y1666072D03*
X1112500Y1671107D03*
X1125784Y1662705D03*
X1124394Y1658967D03*
X1120595D03*
X1120303Y1682055D03*
X1126000Y1672419D03*
X1122610Y1677976D03*
X1124091Y1683983D03*
X1114414Y1698859D03*
X1114394Y1695936D03*
X1113948Y1714244D03*
X1119361Y1713734D03*
X1113948Y1711244D03*
X1112001Y1718991D03*
X1125351Y1737117D03*
X1128199Y49379D03*
X1142830Y53186D03*
X1126902Y60805D03*
X1142144Y63186D03*
X1139200Y380533D03*
Y385698D03*
X1127471Y404788D03*
X1132340Y468202D03*
Y471702D03*
X1134567Y513870D03*
X1139360Y516031D03*
X1129387Y615658D03*
X1138387D03*
X1132855Y609373D03*
X1132387Y615658D03*
X1135387D03*
X1130017Y766870D03*
X1127803Y1302861D03*
Y1300361D03*
Y1305361D03*
Y1307861D03*
Y1310361D03*
Y1312861D03*
X1139703Y1302861D03*
Y1300361D03*
Y1305361D03*
Y1307861D03*
Y1310361D03*
Y1312861D03*
X1127803Y1317861D03*
Y1315361D03*
X1139703Y1317861D03*
Y1315361D03*
X1136219Y1337794D03*
X1133619D03*
X1130829Y1352252D03*
Y1349652D03*
Y1354852D03*
X1128229Y1352252D03*
Y1349652D03*
X1129579Y1357352D03*
X1128229Y1354852D03*
X1135139Y1368999D03*
Y1371540D03*
X1131549Y1373158D03*
X1136588Y1386721D03*
X1134930Y1384770D03*
X1136632Y1379914D03*
X1138912Y1376389D03*
X1127283Y1379188D03*
X1129449Y1377558D03*
X1127283Y1376288D03*
X1129349Y1374558D03*
X1131549Y1378958D03*
Y1376058D03*
X1129965Y1403877D03*
X1127465D03*
X1129965Y1401377D03*
X1127465D03*
X1132465Y1403877D03*
Y1401377D03*
X1129925Y1398737D03*
X1127425D03*
X1134925D03*
X1132425D03*
X1137425D03*
X1137465Y1401377D03*
X1134965D03*
Y1403877D03*
X1137465D03*
X1137275Y1424138D03*
X1134775D03*
X1132275D03*
X1126875Y1423488D03*
X1129775Y1424138D03*
X1140175Y1423488D03*
X1140215Y1428668D03*
Y1426168D03*
X1134815Y1433668D03*
X1137315D03*
X1140215D03*
Y1431168D03*
X1132315Y1433668D03*
X1137315Y1426818D03*
X1134815D03*
X1137345Y1431058D03*
X1134845D03*
X1132315Y1426818D03*
X1132345Y1431058D03*
X1126915Y1428668D03*
Y1426168D03*
X1129815Y1433668D03*
X1126915D03*
Y1431168D03*
X1129815Y1426818D03*
X1129845Y1431058D03*
X1137846Y1453487D03*
X1131478Y1485427D03*
X1134183Y1483926D03*
X1126951Y1484646D03*
X1140960Y1489434D03*
Y1491934D03*
X1141045Y1534952D03*
Y1537452D03*
Y1544952D03*
Y1542452D03*
Y1539952D03*
X1135043Y1553371D03*
X1135033Y1556112D03*
X1142639Y1562789D03*
X1133765Y1572102D03*
X1137523Y1579453D03*
X1136173Y1573638D03*
X1133765Y1568952D03*
X1140655Y1569256D03*
X1137755Y1569543D03*
X1138480Y1576364D03*
X1140422Y1595455D03*
X1139037Y1611383D03*
X1131790Y1597984D03*
X1131832Y1607245D03*
X1131824Y1600593D03*
Y1603993D03*
X1140325Y1598697D03*
X1132168Y1620860D03*
X1138752Y1624627D03*
X1139037Y1614153D03*
X1139142Y1618859D03*
X1139188Y1621603D03*
X1132981Y1634531D03*
X1141084Y1646672D03*
Y1643272D03*
X1137542Y1647925D03*
X1140117Y1671421D03*
X1132209Y1672033D03*
X1129230Y1666174D03*
X1134207Y1669230D03*
X1129184Y1662705D03*
X1132406Y1658967D03*
X1137492Y1685240D03*
X1136575Y1676239D03*
X1141356Y1676542D03*
X1133206Y1675383D03*
X1128934Y1688600D03*
X1132176Y1690038D03*
X1150199Y49379D03*
X1155577Y73939D03*
X1142643Y74738D03*
X1151679Y72258D03*
X1150118Y207344D03*
X1155268D03*
Y212344D03*
X1150118D03*
X1155890Y478812D03*
X1150577Y478840D03*
X1147813Y492319D03*
X1144663D03*
Y500319D03*
X1143060Y516476D03*
X1154145Y583339D03*
Y586339D03*
X1146160Y767299D03*
Y771099D03*
X1155282Y766806D03*
X1142203Y1300361D03*
Y1302861D03*
X1144703D03*
Y1300361D03*
X1142203Y1305361D03*
X1144703D03*
X1155503Y1312861D03*
Y1310361D03*
Y1307861D03*
X1142203D03*
Y1310361D03*
Y1312861D03*
X1144703D03*
Y1310361D03*
Y1307861D03*
X1155503Y1302861D03*
Y1300361D03*
Y1305361D03*
Y1315361D03*
X1142203D03*
X1144703D03*
X1142203Y1317861D03*
X1144703D03*
X1155503D03*
X1154839Y1337834D03*
X1145819D03*
X1143219D03*
X1148668Y1385268D03*
X1141901Y1382574D03*
Y1380066D03*
X1149343Y1382111D03*
X1145855Y1380511D03*
X1148593Y1379543D03*
X1150458Y1433146D03*
X1142675Y1423488D03*
X1145715Y1423555D03*
X1145755Y1426235D03*
Y1428735D03*
Y1431235D03*
Y1433735D03*
X1142715Y1426168D03*
Y1428668D03*
Y1431168D03*
Y1433668D03*
X1144118Y1449628D03*
X1150718Y1462792D03*
X1153724Y1462695D03*
X1154824Y1471134D03*
X1145960Y1491934D03*
X1148460D03*
X1150960D03*
X1153460D03*
X1155960D03*
X1145960Y1489434D03*
X1148460D03*
X1150960D03*
X1153460D03*
X1155960D03*
X1143460D03*
Y1491934D03*
X1153545Y1534952D03*
X1151045D03*
X1148545D03*
X1146045D03*
X1143545D03*
X1153545Y1537452D03*
X1151045D03*
X1148545D03*
X1146045D03*
X1143545D03*
X1151045Y1544952D03*
X1148545D03*
X1146045D03*
X1143545D03*
X1153545D03*
X1143545Y1542452D03*
X1146045D03*
X1148545D03*
X1151045D03*
X1153545D03*
Y1539952D03*
X1151045D03*
X1148545D03*
X1146045D03*
X1143545D03*
X1151384Y1556029D03*
X1155253Y1559176D03*
X1147814Y1562823D03*
X1154336Y1555979D03*
X1143063Y1580334D03*
X1152186Y1570567D03*
X1149467Y1568988D03*
X1149278Y1589453D03*
X1145060Y1588837D03*
X1142917Y1583314D03*
Y1586714D03*
X1141645Y1640017D03*
X1146316Y1649422D03*
X1143127Y1649068D03*
X1155180Y1655534D03*
X1146501Y1655608D03*
Y1652208D03*
X1158343Y1658514D03*
X1152198Y1669629D03*
X1144107Y1671118D03*
X1146477Y1658441D03*
X1151985Y1666685D03*
X1151707Y1663655D03*
X1152114Y1672517D03*
X1154500Y1677000D03*
X1142033Y1682412D03*
X1152211Y1682373D03*
X1168687Y74202D03*
X1162086Y76509D03*
X1163113Y481691D03*
X1162144Y487630D03*
X1158764Y489516D03*
X1165589Y569118D03*
X1162067Y570050D03*
X1166131Y580602D03*
X1157038Y583298D03*
Y586298D03*
X1166026Y669006D03*
X1159718Y766870D03*
X1158003Y1307861D03*
Y1310361D03*
Y1312861D03*
Y1300361D03*
Y1302861D03*
Y1305361D03*
X1160503Y1302861D03*
Y1300361D03*
Y1305361D03*
Y1307861D03*
Y1310361D03*
Y1312861D03*
X1158003Y1315361D03*
Y1317861D03*
X1160503D03*
Y1315361D03*
X1167509Y1337884D03*
X1164909D03*
X1157439Y1337834D03*
X1160929Y1352252D03*
X1163529D03*
X1160929Y1349652D03*
X1163529D03*
X1162279Y1357352D03*
X1163529Y1354852D03*
X1168039Y1368999D03*
Y1371540D03*
X1158059Y1367018D03*
Y1369918D03*
X1164249Y1373158D03*
X1169488Y1386721D03*
X1167830Y1384770D03*
X1169532Y1379914D03*
X1164249Y1376058D03*
X1159983Y1376288D03*
X1162049Y1374558D03*
X1164249Y1378958D03*
X1159983Y1379188D03*
X1162149Y1377558D03*
X1160163Y1445627D03*
X1163422Y1445000D03*
X1166350Y1454234D03*
X1160750Y1463250D03*
X1164300Y1463300D03*
X1159283Y1471132D03*
X1158460Y1491934D03*
Y1489434D03*
X1170986Y1519190D03*
Y1510590D03*
X1168386Y1517280D03*
Y1512500D03*
X1170986Y1516590D03*
Y1513190D03*
Y1532490D03*
X1168386Y1534300D03*
X1170986Y1534990D03*
X1168386Y1539080D03*
X1170986Y1540990D03*
X1161311Y1548204D03*
X1170986Y1538390D03*
X1169061Y1543800D03*
X1170061Y1551040D03*
X1163485Y1546195D03*
X1161492Y1551175D03*
X1164528Y1565578D03*
X1170404Y1556331D03*
Y1559731D03*
X1166873Y1561431D03*
X1157255Y1556000D03*
X1172523Y1573250D03*
X1160031Y1591163D03*
X1170539Y1595621D03*
X1168023Y1586251D03*
X1170539Y1588751D03*
X1168023D03*
X1170539Y1586251D03*
Y1583751D03*
Y1600621D03*
Y1598121D03*
X1170339Y1603121D03*
X1165806Y1658934D03*
X1162144Y1658042D03*
X1159741Y1669759D03*
X1159688Y1665427D03*
X1169098Y1666278D03*
X1169187Y1687117D03*
X1159703Y1673000D03*
X1159500Y1679000D03*
Y1682500D03*
X1180124Y-35569D03*
X1183149Y-34249D03*
X1183164Y-36764D03*
X1177404Y-21711D03*
Y-18311D03*
X1174958Y-24648D03*
Y-15374D03*
X1183139Y-26179D03*
X1183050Y-20074D03*
X1180099Y-14984D03*
X1183124Y-13664D03*
X1183139Y-16179D03*
X1183124Y-23664D03*
X1180099Y-24984D03*
X1174958Y-5374D03*
X1183050Y-10074D03*
Y-74D03*
X1183139Y-6179D03*
X1183124Y-3664D03*
X1180099Y-4984D03*
X1174958Y5352D03*
Y15352D03*
X1180099Y15016D03*
X1183124Y16336D03*
X1183139Y13821D03*
X1183050Y9926D03*
X1180099Y5016D03*
X1183124Y6336D03*
X1183139Y3821D03*
X1177404Y18289D03*
Y21689D03*
X1174958Y24626D03*
X1183140Y24187D03*
X1183125Y26702D03*
X1180100Y25382D03*
X1184194Y57015D03*
Y61515D03*
X1183354Y77685D03*
X1185913Y93634D03*
X1176972Y86788D03*
X1177429Y89556D03*
Y93556D03*
X1174031Y403519D03*
X1181000Y402500D03*
X1185952Y432202D03*
Y440202D03*
Y448202D03*
X1175181Y447841D03*
Y442341D03*
X1185952Y444202D03*
Y436202D03*
X1178340Y447734D03*
Y442234D03*
X1176000Y436500D03*
X1180000Y436000D03*
X1185707Y465272D03*
Y460202D03*
X1175181Y458841D03*
Y464341D03*
Y453341D03*
X1185952Y452202D03*
X1178340Y458734D03*
X1178254Y453142D03*
X1178340Y461615D03*
X1185707Y470392D03*
X1175181Y469841D03*
X1186040Y481691D03*
X1178340Y467165D03*
X1175181Y481691D03*
X1182950Y577030D03*
X1185117Y571807D03*
X1178000Y572602D03*
X1182594Y587759D03*
X1181445Y592868D03*
X1178000Y592673D03*
X1183811Y640682D03*
X1182256Y632368D03*
X1182713Y733815D03*
X1175860Y767299D03*
Y771099D03*
X1184960Y766870D03*
X1172603Y1302861D03*
Y1300361D03*
Y1305361D03*
Y1307861D03*
Y1310361D03*
Y1312861D03*
X1175103Y1300361D03*
Y1302861D03*
X1177603D03*
Y1300361D03*
X1175103Y1305361D03*
X1177603D03*
X1175103Y1307861D03*
Y1310361D03*
Y1312861D03*
X1177603D03*
Y1310361D03*
Y1307861D03*
X1175103Y1315361D03*
X1177603D03*
X1172603Y1317861D03*
Y1315361D03*
X1175103Y1317861D03*
X1177603D03*
X1181568Y1385268D03*
X1174801Y1382574D03*
Y1380066D03*
X1182243Y1382111D03*
X1178755Y1380511D03*
X1181493Y1379543D03*
X1171812Y1376389D03*
X1185000Y1396500D03*
Y1401000D03*
X1184100Y1410000D03*
X1185000Y1405500D03*
X1178400Y1433000D03*
X1184900Y1428500D03*
X1183000Y1422900D03*
X1184175Y1435600D03*
X1176500Y1457071D03*
X1180200Y1457100D03*
X1181324Y1485895D03*
X1183234Y1483295D03*
Y1488495D03*
X1181314Y1492995D03*
X1176534D03*
X1183924Y1485895D03*
X1183224Y1495595D03*
X1174624D03*
X1181314Y1498195D03*
X1176534D03*
X1180624Y1495595D03*
X1177224D03*
X1173586Y1517280D03*
Y1512500D03*
Y1534300D03*
X1180047Y1533247D03*
X1173586Y1539080D03*
X1181361Y1543800D03*
Y1547420D03*
Y1551040D03*
X1181853Y1561731D03*
X1172523Y1562350D03*
X1172603Y1554561D03*
X1178039Y1595621D03*
X1175539D03*
X1173039D03*
X1180923Y1588751D03*
Y1586251D03*
X1173039Y1588751D03*
X1175539D03*
X1178039D03*
Y1586251D03*
X1175539D03*
X1173039D03*
X1178039Y1583751D03*
X1175539D03*
X1173039D03*
X1178039Y1600621D03*
X1175539D03*
X1173039D03*
X1178039Y1598121D03*
X1175539D03*
X1173039D03*
X1175339Y1603121D03*
X1172839D03*
X1177839D03*
X1179187Y1666429D03*
X1175454Y1668046D03*
X1184362Y1670254D03*
X1181385Y1670312D03*
X1178932Y1686698D03*
X1175726Y1686726D03*
X1185676Y1697249D03*
X1186402Y-34263D03*
X1186417Y-36778D03*
X1186448Y-31442D03*
X1186433Y-28927D03*
X1186392Y-26193D03*
X1186312Y-20074D03*
X1186377Y-13678D03*
X1186392Y-16193D03*
X1186377Y-23678D03*
X1186312Y-10074D03*
Y-74D03*
X1186392Y-6193D03*
X1186377Y-3678D03*
Y16322D03*
X1186392Y13807D03*
X1186312Y9926D03*
X1186377Y6322D03*
X1186392Y3807D03*
X1186423Y19143D03*
X1186408Y21658D03*
X1186393Y24173D03*
X1186378Y26688D03*
X1194199Y49379D03*
X1198694Y57015D03*
X1191488Y87125D03*
Y91125D03*
X1188472Y80165D03*
X1200518Y100875D03*
X1195488Y93550D03*
X1190587Y99694D03*
X1199756Y128748D03*
X1200037Y164987D03*
Y160987D03*
X1189727Y164987D03*
Y160987D03*
Y177187D03*
X1189701Y173187D03*
X1200037Y177187D03*
X1200012Y181187D03*
Y185187D03*
X1186821Y185430D03*
Y181930D03*
X1201157Y431875D03*
X1195767Y460202D03*
Y470392D03*
Y465272D03*
X1193040Y481691D03*
X1189540D03*
X1191087Y573809D03*
X1199370Y578154D03*
X1195236Y581407D03*
X1188267Y571807D03*
X1188192Y589263D03*
X1191646Y589567D03*
X1195729Y591022D03*
X1199392Y590500D03*
X1195336Y586606D03*
X1200923Y601734D03*
Y606134D03*
X1199539Y638492D03*
X1197039D03*
X1194539D03*
X1192039D03*
X1195108Y668148D03*
X1198456Y668138D03*
X1190903Y1307861D03*
Y1310361D03*
Y1312861D03*
X1188403D03*
Y1310361D03*
Y1307861D03*
Y1302861D03*
Y1300361D03*
Y1305361D03*
X1190903Y1300361D03*
Y1302861D03*
X1193403D03*
Y1300361D03*
X1190903Y1305361D03*
X1193403D03*
Y1307861D03*
Y1310361D03*
Y1312861D03*
X1196159Y1326549D03*
X1193659Y1326589D03*
Y1324049D03*
X1196259D03*
X1193659Y1321549D03*
X1196259D03*
X1190903Y1315361D03*
X1188403D03*
Y1317861D03*
X1190903D03*
X1193403D03*
Y1315361D03*
X1199899Y1338065D03*
X1193829Y1352252D03*
X1196429D03*
X1193829Y1349652D03*
X1196429D03*
X1193829Y1354852D03*
X1195179Y1357352D03*
X1196429Y1354852D03*
X1200839Y1368999D03*
Y1371540D03*
X1191049Y1367188D03*
Y1370088D03*
X1197149Y1373158D03*
X1200690Y1384572D03*
X1192883Y1379188D03*
X1195049Y1377558D03*
X1197149Y1378958D03*
X1192883Y1376288D03*
X1194949Y1374558D03*
X1197149Y1376058D03*
X1194296Y1396500D03*
X1194000Y1401000D03*
Y1418000D03*
X1187925Y1417000D03*
X1194000Y1414500D03*
X1203242Y1417440D03*
X1194366Y1405500D03*
X1193929Y1410000D03*
X1202548Y1407453D03*
X1202857Y1412454D03*
X1191000Y1425900D03*
X1194000Y1428500D03*
Y1433000D03*
X1198800Y1421500D03*
X1202411Y1427410D03*
X1194000Y1424000D03*
X1203117Y1422452D03*
X1202475Y1432468D03*
X1188000Y1419800D03*
X1187925Y1440400D03*
X1194000Y1437500D03*
X1203040D03*
X1194000Y1442500D03*
Y1447500D03*
X1189924Y1485895D03*
X1188014Y1483295D03*
Y1488495D03*
X1187324Y1485895D03*
X1194724Y1505295D03*
X1196634Y1502695D03*
Y1507895D03*
X1200724Y1505295D03*
X1197324D03*
X1200824Y1593498D03*
X1188960Y1609135D03*
X1186455Y1608390D03*
Y1602590D03*
Y1605490D03*
X1195050Y1620040D03*
X1190174Y1615418D03*
X1192903Y1666276D03*
X1190616Y1670641D03*
X1190314Y1661630D03*
X1192612Y1680410D03*
X1197980Y1688270D03*
X1199299Y1675517D03*
X1197746Y1680914D03*
X1199272Y1683025D03*
X1189263Y1682551D03*
X1190830Y1675710D03*
X1199612Y1700334D03*
X1189462Y1691366D03*
X1197612Y1703334D03*
X1192612D03*
X1199612Y1691366D03*
X1189462Y1700334D03*
X1194478Y1699936D03*
X1196767Y1712261D03*
X1199294Y1721143D03*
X1196814Y1726261D03*
X1189407Y1717518D03*
X1191351Y1737117D03*
X1215581Y91346D03*
X1202711Y87651D03*
X1205929Y86872D03*
X1215581Y94846D03*
X1206580D03*
X1208431Y133866D03*
Y128748D03*
X1215528Y172395D03*
X1214094Y258633D03*
Y269008D03*
X1214156Y292066D03*
X1205625Y313758D03*
X1210698Y313671D03*
X1207447Y341381D03*
X1202508Y341424D03*
X1214856Y421018D03*
X1213866Y455376D03*
X1212700Y475712D03*
X1206590Y481403D03*
X1203269Y481237D03*
X1212051Y559827D03*
X1208733Y585986D03*
X1205900Y582443D03*
X1208400Y591631D03*
X1206191Y588400D03*
X1205679Y594148D03*
X1201440Y668138D03*
X1207177Y668115D03*
X1209796D03*
X1204334Y668138D03*
X1205630Y766600D03*
X1207903Y1300361D03*
Y1302861D03*
X1210403D03*
Y1300361D03*
X1207903Y1305361D03*
X1210403D03*
X1207903Y1307861D03*
Y1310361D03*
Y1312861D03*
X1210403D03*
Y1310361D03*
Y1307861D03*
X1205403Y1302861D03*
Y1300361D03*
Y1305361D03*
Y1307861D03*
Y1310361D03*
Y1312861D03*
X1205189Y1321492D03*
Y1323992D03*
X1202689Y1321492D03*
Y1324032D03*
X1207903Y1315361D03*
X1210403D03*
X1205403Y1317861D03*
Y1315361D03*
X1207903Y1317861D03*
X1210403D03*
X1211299Y1338105D03*
X1202399D03*
X1214368Y1385268D03*
X1202288Y1386721D03*
X1202332Y1379914D03*
X1207601Y1380066D03*
X1215043Y1382111D03*
X1211555Y1380511D03*
X1214293Y1379543D03*
X1207601Y1382574D03*
X1204612Y1376389D03*
X1202484Y1402467D03*
X1211000Y1392125D03*
X1211075Y1395200D03*
X1213355Y1412564D03*
Y1427564D03*
Y1420064D03*
X1210100Y1436500D03*
X1213000Y1435000D03*
X1210400Y1440000D03*
X1214900Y1439800D03*
X1203334Y1492995D03*
X1208114D03*
X1210034Y1483295D03*
X1214814D03*
X1208124Y1485895D03*
X1210034Y1488495D03*
X1214814D03*
X1214124Y1485895D03*
X1210724D03*
X1203324Y1505295D03*
X1210024Y1495595D03*
X1201424D03*
X1203334Y1498195D03*
X1208114D03*
X1201414Y1502695D03*
Y1507895D03*
X1207424Y1495595D03*
X1204024D03*
X1207954Y1680419D03*
X1213072Y1682899D03*
X1202697Y1673059D03*
X1205604Y1685400D03*
Y1682200D03*
Y1679000D03*
Y1675800D03*
X1204804Y1691375D03*
X1214954Y1700343D03*
X1209879Y1700359D03*
X1212954Y1703343D03*
X1214954Y1691375D03*
X1204804Y1700343D03*
X1207954Y1703343D03*
X1204447Y1707143D03*
X1207770Y1717011D03*
Y1706861D03*
Y1731011D03*
Y1720861D03*
X1213351Y1737117D03*
X1205638Y1732766D03*
X1216199Y49379D03*
X1223455Y91346D03*
X1230312Y88635D03*
X1227803Y94210D03*
X1221411Y134230D03*
X1221512Y128239D03*
X1220931Y131307D03*
X1215931Y141530D03*
X1218431D03*
X1231118Y142125D03*
X1222094Y258633D03*
X1230094D03*
Y269008D03*
X1222094D03*
X1226094Y297066D03*
X1230156Y292066D03*
X1222094Y286948D03*
Y297066D03*
X1230094Y314216D03*
X1226094Y305216D03*
X1222094Y314216D03*
X1218430Y421012D03*
X1219325Y438151D03*
X1216300Y475682D03*
X1228372Y688501D03*
X1221203Y1312861D03*
Y1310361D03*
Y1307861D03*
X1223703D03*
Y1310361D03*
Y1312861D03*
Y1300361D03*
Y1302861D03*
Y1305361D03*
X1221203Y1302861D03*
Y1300361D03*
Y1305361D03*
Y1315361D03*
X1223703D03*
Y1317861D03*
X1221203D03*
X1219463Y1338122D03*
X1229809Y1338105D03*
X1226629Y1352252D03*
X1229229D03*
X1226629Y1349652D03*
X1229229D03*
X1227979Y1357352D03*
X1226629Y1354852D03*
X1229229D03*
X1223889Y1367188D03*
Y1370088D03*
X1229949Y1373158D03*
X1228800Y1391300D03*
X1225683Y1379188D03*
X1227849Y1377558D03*
X1225683Y1376288D03*
X1227749Y1374558D03*
X1229949Y1378958D03*
Y1376058D03*
X1227000Y1401300D03*
X1219650Y1392050D03*
X1219500Y1398900D03*
X1228355Y1412564D03*
X1220855D03*
X1227000Y1404500D03*
X1228355Y1427564D03*
Y1420064D03*
X1220855Y1427564D03*
X1219500Y1436000D03*
X1229661Y1442000D03*
X1226200Y1444300D03*
X1222700Y1446300D03*
X1220200Y1449100D03*
X1230134Y1492995D03*
X1216724Y1485895D03*
X1228224Y1495595D03*
X1230124Y1505295D03*
X1221524D03*
X1230134Y1498195D03*
X1228214Y1502695D03*
X1223434D03*
Y1507895D03*
X1228214D03*
X1227524Y1505295D03*
X1224124D03*
X1230824Y1495595D03*
X1216875Y1705826D03*
X1219738Y1717011D03*
Y1713861D03*
Y1708861D03*
X1216738Y1717011D03*
Y1720861D03*
X1219738Y1731011D03*
Y1722861D03*
Y1727861D03*
X1216738Y1731011D03*
X1236844Y-34348D03*
X1236829Y-36863D03*
X1236798Y-31476D03*
X1236813Y-28961D03*
X1240097Y-34334D03*
X1243122Y-35654D03*
X1240082Y-36849D03*
X1236877Y-26227D03*
X1236932Y-19948D03*
X1236942Y-13666D03*
X1236927Y-16181D03*
X1236892Y-23712D03*
X1240130Y-26213D03*
X1240194Y-19948D03*
X1240195Y-13652D03*
X1243220Y-14972D03*
X1240180Y-16167D03*
X1240145Y-23698D03*
X1243170Y-25018D03*
X1236932Y-9948D03*
Y52D03*
X1236942Y-3666D03*
X1236927Y-6181D03*
X1240194Y-9948D03*
Y52D03*
X1240195Y-3652D03*
X1243220Y-4972D03*
X1240180Y-6167D03*
X1236927Y13819D03*
X1236942Y16334D03*
X1236932Y10052D03*
X1236942Y6334D03*
X1236927Y3819D03*
X1240180Y13833D03*
X1243220Y15028D03*
X1240195Y16348D03*
X1240194Y10052D03*
X1240195Y6348D03*
X1243220Y5028D03*
X1240180Y3833D03*
X1236911Y21721D03*
X1236896Y19206D03*
X1236941Y26751D03*
X1236926Y24236D03*
X1243219Y25445D03*
X1240194Y26765D03*
X1240179Y24250D03*
X1238199Y49379D03*
X1235546Y75293D03*
X1238769Y75320D03*
X1232812Y88635D03*
X1239218Y128239D03*
Y137239D03*
Y132739D03*
Y123739D03*
X1233668Y132739D03*
Y128239D03*
X1247834Y159844D03*
X1238094Y258633D03*
X1246094Y269008D03*
X1238094D03*
Y280573D03*
X1233345Y300157D03*
X1234000Y385500D03*
X1233468Y419742D03*
X1242429Y431255D03*
Y427255D03*
Y443255D03*
Y447255D03*
Y435255D03*
X1236879Y449755D03*
X1242429Y439255D03*
X1232081Y460580D03*
X1242692Y483435D03*
X1236100Y773844D03*
X1233084Y772582D03*
X1235215Y777213D03*
X1231397Y769667D03*
X1243207Y779428D03*
X1241057Y782278D03*
X1244986Y787578D03*
X1244127Y784598D03*
X1238257Y779728D03*
X1243294Y1269197D03*
Y1266697D03*
Y1261697D03*
Y1264197D03*
X1243308Y1271754D03*
X1240899Y1315460D03*
X1238830Y1322853D03*
Y1325394D03*
X1240240Y1339578D03*
X1232409Y1338105D03*
X1240323Y1333768D03*
X1245592Y1333920D03*
Y1336428D03*
X1242603Y1330243D03*
X1235400Y1391200D03*
X1238500Y1400900D03*
X1234900Y1404400D03*
X1238200Y1395500D03*
X1244300Y1403500D03*
X1235679Y1418908D03*
X1239242Y1418462D03*
X1242500Y1430075D03*
X1238731Y1422362D03*
X1237100Y1442500D03*
X1242500Y1437075D03*
X1239550Y1437050D03*
X1243524Y1485895D03*
X1234924D03*
X1241614Y1483295D03*
X1236834D03*
X1241614Y1488495D03*
X1236834D03*
X1234914Y1492995D03*
X1240924Y1485895D03*
X1237524D03*
X1236824Y1495595D03*
X1234914Y1498195D03*
X1234224Y1495595D03*
X1235351Y1737117D03*
X1248286Y-34648D03*
X1245840Y-18311D03*
Y-21711D03*
X1248286Y-15374D03*
Y-25374D03*
X1245840Y1689D03*
Y-1711D03*
X1248286Y-4648D03*
Y5352D03*
Y14626D03*
X1260199Y49379D03*
X1252561Y72675D03*
X1249152Y72895D03*
X1253152Y84895D03*
X1255661Y90470D03*
X1256064Y101100D03*
X1253152Y95525D03*
X1259472Y92864D03*
X1252693Y124739D03*
X1255185Y140053D03*
Y142553D03*
X1255175Y137553D03*
X1249431Y137739D03*
X1249065Y241594D03*
Y236594D03*
Y251594D03*
Y246594D03*
X1246094Y258633D03*
X1254094D03*
X1262094Y269008D03*
X1254094D03*
X1246094Y280573D03*
X1254094Y286948D03*
X1245825Y305275D03*
X1250285Y303307D03*
X1259659Y389456D03*
X1260107Y399125D03*
X1260227Y407128D03*
Y411128D03*
Y415128D03*
X1256137Y459182D03*
Y453872D03*
X1248902Y470733D03*
X1257016Y467253D03*
X1245752Y470733D03*
X1250975Y474945D03*
X1246490Y483302D03*
X1248130Y783354D03*
X1251177Y784488D03*
X1246748Y785752D03*
X1254981Y787578D03*
X1256447Y798828D03*
X1259297Y798784D03*
X1251177Y794878D03*
X1257527Y808938D03*
X1260427Y809008D03*
X1259194Y1251697D03*
Y1246697D03*
Y1254197D03*
Y1249197D03*
X1248294Y1259197D03*
Y1256697D03*
X1245794Y1259197D03*
X1259194Y1269215D03*
Y1261715D03*
Y1264215D03*
Y1266715D03*
X1245894Y1269215D03*
X1248394D03*
X1245894Y1261715D03*
Y1264215D03*
Y1266715D03*
X1248394D03*
Y1264215D03*
Y1261715D03*
X1259194Y1256697D03*
Y1259197D03*
X1248308Y1271754D03*
X1245808D03*
X1259108D03*
X1257450Y1291721D03*
X1260050D03*
X1249650D03*
X1247050D03*
X1258121Y1342686D03*
X1252359Y1339122D03*
X1253034Y1335965D03*
X1249546Y1334365D03*
X1252284Y1333397D03*
X1249600Y1403425D03*
X1252315Y1417085D03*
X1254905Y1417026D03*
X1257594Y1417000D03*
X1253100Y1413500D03*
X1256224Y1430075D03*
X1256600Y1434500D03*
X1256934Y1492995D03*
X1256924Y1505295D03*
X1255024Y1495595D03*
X1248324Y1505295D03*
X1256934Y1498195D03*
X1255014Y1502695D03*
X1250234D03*
X1255014Y1507895D03*
X1250234D03*
X1254324Y1505295D03*
X1250924D03*
X1257624Y1495595D03*
X1257351Y1737117D03*
X1275981Y85114D03*
X1263472Y92864D03*
X1266146Y121022D03*
X1269146D03*
X1263146D03*
X1263582Y164051D03*
Y160051D03*
Y180551D03*
Y176051D03*
Y172051D03*
Y168051D03*
X1267037Y180565D03*
Y175030D03*
X1263582Y185051D03*
X1268941Y206017D03*
X1269360Y219632D03*
X1261969Y219505D03*
X1262094Y258633D03*
X1270094D03*
Y269008D03*
Y286948D03*
X1262156Y292066D03*
X1268174Y395125D03*
X1275585Y393597D03*
X1269840Y411128D03*
X1270483Y433148D03*
Y435648D03*
X1265227Y454372D03*
X1262457Y798814D03*
X1266677Y802988D03*
X1266568Y809078D03*
X1275177Y808963D03*
X1263647Y809118D03*
X1271177Y808963D03*
X1261694Y1251697D03*
X1264194D03*
Y1246697D03*
X1261694D03*
Y1254197D03*
X1264194D03*
X1261694Y1249197D03*
X1264194D03*
X1261694Y1269215D03*
Y1266715D03*
Y1264215D03*
Y1261715D03*
X1264194Y1269197D03*
Y1256697D03*
Y1259197D03*
Y1261697D03*
X1261694Y1256697D03*
Y1259197D03*
X1264194Y1264197D03*
Y1266697D03*
X1264108Y1271754D03*
X1261608D03*
X1270670Y1291624D03*
X1268070D03*
X1267220Y1306106D03*
Y1308706D03*
Y1303506D03*
X1265970Y1311206D03*
X1264620Y1303506D03*
Y1306106D03*
Y1308706D03*
X1273869Y1315300D03*
X1271726Y1322825D03*
Y1325366D03*
X1262050Y1320878D03*
Y1323778D03*
X1267940Y1327012D03*
X1265740Y1328412D03*
X1273175Y1340547D03*
X1271517Y1338596D03*
X1273219Y1333740D03*
X1275499Y1330215D03*
X1267940Y1332812D03*
Y1329912D03*
X1265840Y1331412D03*
X1263674Y1330142D03*
Y1333042D03*
X1271042Y1418748D03*
X1266996Y1423617D03*
X1262310Y1428303D03*
X1270324Y1485895D03*
X1275124D03*
X1261724D03*
X1263634Y1483295D03*
X1268414D03*
X1263634Y1488495D03*
X1268414D03*
X1261714Y1492995D03*
X1267724Y1485895D03*
X1264324D03*
X1263624Y1495595D03*
X1261714Y1498195D03*
X1261024Y1495595D03*
X1275195Y1552250D03*
X1275170Y1579519D03*
X1269310Y1583170D03*
X1282199Y49379D03*
X1287486Y134165D03*
X1278111Y150030D03*
X1285391Y142553D03*
X1278050Y152912D03*
X1278137Y166051D03*
X1278211Y161030D03*
Y156030D03*
X1278137Y180565D03*
Y176051D03*
Y171551D03*
Y184987D03*
X1279447Y213292D03*
X1277732Y236594D03*
Y246594D03*
Y241594D03*
Y251594D03*
X1286094Y258633D03*
X1278094D03*
Y269008D03*
X1286094D03*
Y286948D03*
X1278156Y292066D03*
X1278094Y287948D03*
X1277598Y404428D03*
X1290127Y401125D03*
X1282165Y408987D03*
X1288202Y405741D03*
X1290127Y410635D03*
X1289352Y418550D03*
Y421950D03*
X1278677Y808988D03*
X1281190Y1254112D03*
X1276190D03*
X1278690D03*
X1281190Y1249112D03*
Y1251612D03*
X1276190D03*
X1278690D03*
X1276190Y1249112D03*
X1278690D03*
X1281190Y1246612D03*
X1276190D03*
X1278690D03*
X1276190Y1269112D03*
Y1266612D03*
X1281190Y1259112D03*
Y1256612D03*
X1276190D03*
Y1259112D03*
Y1261612D03*
Y1264112D03*
X1278690Y1256612D03*
Y1259112D03*
X1278790Y1269130D03*
X1281290D03*
X1278790Y1261630D03*
Y1264130D03*
Y1266630D03*
X1281290D03*
Y1264130D03*
Y1261630D03*
X1281204Y1271669D03*
X1278704D03*
X1276204D03*
X1285255Y1339094D03*
X1278488Y1333892D03*
X1285930Y1335937D03*
X1282442Y1334337D03*
X1285180Y1333369D03*
X1278488Y1336400D03*
X1287600Y1423100D03*
Y1427600D03*
X1276500Y1432000D03*
X1279525D03*
X1287700Y1431700D03*
X1283724Y1485895D03*
X1277034Y1483295D03*
X1281814D03*
X1277034Y1488495D03*
X1281814D03*
X1277724Y1485895D03*
X1281124D03*
X1288494Y1511082D03*
Y1519682D03*
X1285894Y1512992D03*
Y1517772D03*
X1288494Y1517082D03*
Y1513682D03*
Y1533082D03*
Y1524482D03*
X1285894Y1531172D03*
Y1526392D03*
X1288494Y1530482D03*
Y1527082D03*
X1283958Y1542654D03*
X1287961Y1542469D03*
X1287372Y1552845D03*
X1287647Y1545220D03*
Y1549120D03*
X1277017Y1544953D03*
Y1547453D03*
Y1549953D03*
X1281470Y1552845D03*
X1281347Y1549120D03*
Y1545220D03*
X1284497Y1549120D03*
Y1545220D03*
X1284510Y1556953D03*
X1278593Y1564073D03*
X1281093D03*
X1283593D03*
X1284510Y1554436D03*
X1277702D03*
X1278012Y1581563D03*
X1287945Y1569763D03*
X1285445D03*
X1289919Y1582295D03*
Y1574795D03*
Y1579795D03*
Y1577295D03*
X1287419Y1582295D03*
Y1579795D03*
X1284919D03*
Y1582295D03*
X1282419D03*
Y1579795D03*
X1279351Y1737117D03*
X1304199Y49379D03*
X1299196Y76209D03*
X1305685Y74748D03*
X1296200Y66911D03*
X1304705Y79807D03*
X1300668Y125739D03*
Y133739D03*
Y129739D03*
X1305091Y123680D03*
Y127830D03*
Y131750D03*
X1306431Y149330D03*
X1300668Y145739D03*
X1292082Y166051D03*
Y162051D03*
X1301582Y166051D03*
X1301743Y162055D03*
X1292082Y171551D03*
X1301582D03*
X1292082Y184051D03*
X1301582D03*
X1302094Y258633D03*
X1294094D03*
Y269008D03*
X1302094D03*
Y298066D03*
Y286948D03*
X1294156Y292066D03*
X1302069Y303184D03*
X1299026Y389355D03*
X1302226D03*
X1295519Y389561D03*
X1293277Y401125D03*
X1296228Y408125D03*
X1304347Y523237D03*
X1299076Y530023D03*
X1303266Y533713D03*
Y530413D03*
X1302160Y524916D03*
X1304566Y525743D03*
X1301642Y537299D03*
X1295532Y539513D03*
X1293581Y542716D03*
X1301666Y555413D03*
X1294938Y561331D03*
X1297487Y590607D03*
X1300200Y590600D03*
X1300400Y599413D03*
X1297400D03*
X1298000Y657500D03*
X1303250Y655149D03*
X1295000Y655200D03*
X1292297Y657206D03*
X1302500Y664500D03*
X1305100Y662100D03*
X1301900Y660699D03*
X1294590Y1254112D03*
X1297090D03*
X1292090D03*
Y1249112D03*
X1294590D03*
X1297090D03*
X1292090Y1251612D03*
X1294590D03*
X1297090D03*
X1292090Y1246612D03*
X1297090D03*
X1294590D03*
X1292090Y1269130D03*
X1294590D03*
X1292090Y1261630D03*
Y1264130D03*
Y1266630D03*
X1294590D03*
Y1264130D03*
Y1261630D03*
X1297090Y1269112D03*
Y1256612D03*
Y1259112D03*
Y1261612D03*
X1294590Y1256612D03*
Y1259112D03*
X1297090Y1264112D03*
Y1266612D03*
X1292090Y1256612D03*
Y1259112D03*
X1297004Y1271669D03*
X1292004D03*
X1294504D03*
X1302890Y1291759D03*
X1298350Y1291721D03*
X1295750D03*
X1300116Y1306078D03*
Y1303478D03*
Y1308678D03*
X1298866Y1311178D03*
X1297516Y1306078D03*
Y1303478D03*
Y1308678D03*
X1304630Y1322768D03*
Y1325309D03*
X1294956Y1320934D03*
Y1323834D03*
X1300836Y1326984D03*
X1298636Y1328384D03*
X1304421Y1338539D03*
X1296570Y1330114D03*
Y1333014D03*
X1298736Y1331384D03*
X1300836Y1329884D03*
Y1332784D03*
X1302365Y1418702D03*
X1296000Y1427700D03*
X1292522Y1421596D03*
X1303943Y1430729D03*
X1301900Y1427700D03*
X1295700Y1421800D03*
X1300800D03*
X1291700Y1431700D03*
X1304596Y1492995D03*
X1302686Y1495595D03*
X1304596Y1498195D03*
X1305286Y1495595D03*
X1299048Y1519190D03*
Y1510590D03*
X1296448Y1517280D03*
Y1512500D03*
X1301648Y1517280D03*
Y1512500D03*
X1291094Y1512992D03*
Y1517772D03*
X1299048Y1516590D03*
Y1513190D03*
Y1532490D03*
X1296448Y1534300D03*
X1301648D03*
X1291094Y1531172D03*
Y1526392D03*
X1299048Y1534990D03*
X1302390Y1530430D03*
X1297490Y1526910D03*
X1297620Y1529534D03*
X1296448Y1539080D03*
X1301648D03*
X1299048Y1540990D03*
Y1538390D03*
X1291897Y1545076D03*
X1290461Y1542469D03*
X1291897Y1547576D03*
X1299466Y1562402D03*
Y1564902D03*
X1291819Y1563595D03*
X1294319D03*
X1292673Y1559750D03*
X1300560Y1554261D03*
X1302915Y1563596D03*
X1298466Y1556331D03*
Y1559731D03*
X1299492Y1572106D03*
Y1569606D03*
X1292419Y1582295D03*
Y1579795D03*
Y1574795D03*
Y1577295D03*
X1294919D03*
Y1574795D03*
X1294387Y1571682D03*
X1291887D03*
X1301789Y1574795D03*
X1304289D03*
X1301789Y1577295D03*
X1304289D03*
Y1579795D03*
X1301789D03*
X1304289Y1582295D03*
X1301789D03*
X1299289Y1574795D03*
Y1582295D03*
Y1579795D03*
Y1577295D03*
X1295877Y1581199D03*
X1298382Y1584844D03*
X1295877Y1584099D03*
X1293459Y1584844D03*
X1301351Y1737117D03*
X1309185Y74748D03*
X1320020Y66979D03*
X1308110Y66911D03*
X1319667Y87587D03*
Y105227D03*
X1306449Y92185D03*
X1307857Y103353D03*
X1313951Y104739D03*
X1311045D03*
X1307857Y111353D03*
X1313011Y135820D03*
Y139845D03*
X1306431Y152830D03*
X1306300Y203917D03*
X1318094Y258633D03*
X1310094D03*
Y269008D03*
X1318094D03*
X1310156Y292066D03*
X1305426Y389355D03*
X1308926Y524111D03*
X1306815Y522726D03*
X1307117Y525897D03*
X1309870Y552788D03*
X1316266Y564514D03*
X1307766Y563013D03*
X1309776Y559831D03*
X1308700Y590300D03*
X1317266Y589522D03*
Y592522D03*
X1308700Y587800D03*
X1317266Y597213D03*
X1310544Y613100D03*
X1313544Y610100D03*
X1310544D03*
X1313544Y607100D03*
X1310544D03*
X1313544Y604100D03*
X1310544D03*
X1307544Y610100D03*
Y613100D03*
Y604100D03*
Y607100D03*
X1317266Y600213D03*
X1309166Y601713D03*
X1308776Y599181D03*
X1313544Y613100D03*
X1310544Y616100D03*
X1313544D03*
X1307544D03*
X1308800Y619200D03*
Y622200D03*
Y625200D03*
X1318300D03*
Y622200D03*
Y619200D03*
Y640000D03*
Y643000D03*
Y649000D03*
Y646000D03*
X1307700Y664600D03*
X1309600Y667700D03*
X1313109Y1195398D03*
Y1200898D03*
X1311715Y1221042D03*
X1318776Y1219566D03*
X1311594Y1251612D03*
X1309094D03*
X1311594Y1254112D03*
X1309094D03*
X1311594Y1246612D03*
X1309094D03*
X1311594Y1249112D03*
X1309094D03*
X1314094Y1246612D03*
Y1251612D03*
Y1249112D03*
Y1254112D03*
X1309090Y1269169D03*
Y1266669D03*
Y1261669D03*
Y1264169D03*
X1314194Y1269130D03*
Y1266630D03*
Y1264130D03*
Y1261630D03*
X1311694Y1269130D03*
Y1261630D03*
Y1264130D03*
Y1266630D03*
X1311594Y1259112D03*
Y1256612D03*
X1309094Y1259112D03*
Y1256612D03*
X1314094D03*
Y1259112D03*
X1309090Y1271669D03*
X1311590D03*
X1314090D03*
X1305600Y1291759D03*
X1306799Y1315440D03*
X1318159Y1339037D03*
X1306079Y1340490D03*
X1306123Y1333683D03*
X1311392Y1333835D03*
X1318834Y1335880D03*
X1315346Y1334280D03*
X1318084Y1333312D03*
X1311392Y1336343D03*
X1308403Y1330158D03*
X1318363Y1411404D03*
X1314580Y1425240D03*
X1310580D03*
X1318580D03*
X1317986Y1485895D03*
X1309386D03*
X1311296Y1483295D03*
X1316076D03*
X1311296Y1488495D03*
X1316076D03*
X1309376Y1492995D03*
X1315386Y1485895D03*
X1311986D03*
X1311286Y1495595D03*
X1309376Y1498195D03*
X1308686Y1495595D03*
X1308900Y1525510D03*
X1308290Y1533380D03*
X1309423Y1543800D03*
Y1547420D03*
Y1551040D03*
X1309915Y1561731D03*
X1312700Y1579596D03*
X1306789Y1574795D03*
Y1582295D03*
Y1579795D03*
Y1577295D03*
X1310914Y1577299D03*
X1319349Y1585567D03*
X1326199Y49379D03*
X1331930Y66945D03*
X1327541Y105227D03*
X1337399Y98084D03*
X1333399D03*
X1334094Y258633D03*
X1326094D03*
Y269008D03*
X1334094D03*
X1334156Y292066D03*
X1326094Y286948D03*
X1328427Y349452D03*
X1330820Y525165D03*
X1330758Y521749D03*
X1330820Y518265D03*
X1330658Y538749D03*
X1330758Y528649D03*
X1330773Y531776D03*
X1330758Y535449D03*
X1329673Y552509D03*
X1332673D03*
X1326673Y544909D03*
X1329673Y545909D03*
Y549309D03*
X1330658Y542949D03*
X1332673Y545909D03*
Y549309D03*
X1329673Y558709D03*
Y555709D03*
X1332673D03*
X1329585Y561806D03*
X1325366Y589522D03*
Y592522D03*
Y597213D03*
Y600213D03*
X1321300Y619200D03*
Y622200D03*
Y625200D03*
Y643000D03*
Y640000D03*
Y649000D03*
Y646000D03*
X1326636Y656800D03*
X1322420Y656867D03*
X1332812Y856383D03*
X1330277Y857388D03*
X1325543Y871161D03*
X1329244D03*
X1334301Y867765D03*
X1328992Y1209788D03*
X1327029Y1206788D03*
X1331202Y1206478D03*
X1323169Y1208995D03*
X1329477Y1222158D03*
X1331202Y1211488D03*
X1326433Y1214334D03*
X1333977Y1222158D03*
X1325137Y1210653D03*
X1324901Y1216419D03*
X1322141Y1217365D03*
X1327494Y1246612D03*
Y1251612D03*
Y1249112D03*
Y1254112D03*
X1324994Y1246612D03*
Y1251612D03*
Y1249112D03*
Y1254112D03*
X1329994Y1246612D03*
Y1251612D03*
Y1249112D03*
Y1254112D03*
X1324994Y1269130D03*
Y1261630D03*
Y1264130D03*
Y1266630D03*
X1327494Y1269130D03*
Y1266630D03*
Y1264130D03*
Y1261630D03*
Y1259112D03*
Y1256612D03*
X1324994Y1259112D03*
Y1256612D03*
X1329994Y1259112D03*
Y1256612D03*
Y1266612D03*
Y1264112D03*
Y1261612D03*
Y1269112D03*
X1327490Y1271669D03*
X1324990D03*
X1329990D03*
X1332680Y1291861D03*
X1330080D03*
X1333020Y1308621D03*
X1331770Y1311121D03*
X1333020Y1306021D03*
Y1303421D03*
X1330420Y1306021D03*
Y1303421D03*
Y1308621D03*
X1327876Y1320934D03*
Y1323834D03*
X1333740Y1326927D03*
X1331540Y1328327D03*
X1333740Y1329827D03*
Y1332727D03*
X1331640Y1331327D03*
X1329474Y1330057D03*
Y1332957D03*
X1322539Y1411278D03*
X1322499Y1413788D03*
X1325499D03*
X1325539Y1411278D03*
Y1416446D03*
X1322539D03*
X1328539Y1411278D03*
X1328499Y1413788D03*
X1328539Y1416446D03*
X1331509Y1416486D03*
X1334509D03*
X1331509Y1408818D03*
X1334509Y1411318D03*
X1334469Y1413828D03*
X1334509Y1408818D03*
X1331469Y1413828D03*
X1331509Y1411318D03*
X1334580Y1425240D03*
X1330580D03*
X1326580D03*
X1322580D03*
X1325579Y1418976D03*
X1322579D03*
X1325609Y1421496D03*
X1322609D03*
X1328579Y1418976D03*
X1328609Y1421496D03*
X1331579Y1421536D03*
X1331549Y1419016D03*
X1334579Y1421536D03*
X1334549Y1419016D03*
X1331396Y1492995D03*
X1331386Y1505295D03*
X1322786D03*
X1329486Y1495595D03*
X1331396Y1498195D03*
X1324696Y1502695D03*
X1329476D03*
X1324696Y1507895D03*
X1329476D03*
X1328786Y1505295D03*
X1325386D03*
X1332086Y1495595D03*
X1323351Y1737117D03*
X1348199Y49379D03*
X1351750Y72826D03*
X1339840Y72860D03*
X1343840Y66911D03*
X1344958Y85358D03*
X1341399Y98084D03*
X1348199D03*
X1335260Y236594D03*
Y246594D03*
Y241594D03*
Y251594D03*
X1342094Y258633D03*
Y269008D03*
X1350094D03*
X1342094Y286948D03*
X1340257Y677765D03*
Y675111D03*
X1336812Y856383D03*
X1339347Y857388D03*
X1341301Y867765D03*
X1337801D03*
X1341301Y871265D03*
X1344801D03*
X1348301D03*
X1337975Y1177999D03*
X1340948Y1177681D03*
X1338142Y1181642D03*
X1342507Y1187848D03*
X1340948Y1181681D03*
X1339488Y1202295D03*
X1340483Y1209006D03*
X1349012Y1204971D03*
X1336861Y1222119D03*
X1348611Y1212963D03*
Y1218463D03*
X1341590Y1254169D03*
Y1251669D03*
Y1249169D03*
Y1246669D03*
X1344090Y1254169D03*
Y1251669D03*
Y1249169D03*
Y1246669D03*
X1346590Y1254169D03*
Y1249169D03*
Y1251669D03*
Y1246669D03*
X1341690Y1269269D03*
Y1264269D03*
Y1266769D03*
Y1261769D03*
X1341590Y1256669D03*
Y1259169D03*
X1344190Y1269187D03*
X1346690D03*
X1344190Y1261687D03*
Y1264187D03*
Y1266687D03*
X1346690D03*
Y1264187D03*
Y1261687D03*
X1344090Y1256669D03*
Y1259169D03*
X1346590D03*
Y1256669D03*
X1341690Y1271769D03*
X1346690D03*
X1344190D03*
X1338440Y1291949D03*
X1335670Y1291899D03*
X1339429Y1315570D03*
X1337430Y1322968D03*
Y1325509D03*
X1338879Y1340690D03*
X1337221Y1338739D03*
X1338923Y1333883D03*
X1344192Y1334035D03*
X1348146Y1334480D03*
X1344192Y1336543D03*
X1341203Y1330358D03*
X1340556Y1383674D03*
Y1386674D03*
X1337556D03*
Y1383674D03*
X1346556Y1386674D03*
Y1383674D03*
X1343556Y1386674D03*
Y1383674D03*
X1349556D03*
Y1386674D03*
X1337555Y1389658D03*
X1343712Y1389804D03*
X1348712D03*
X1346212D03*
X1341212D03*
X1348823Y1409626D03*
X1348853Y1413866D03*
X1346323Y1409626D03*
X1346353Y1413866D03*
X1343823Y1409626D03*
X1343853Y1413866D03*
X1346509Y1416486D03*
X1349509D03*
X1343509D03*
X1341323Y1409626D03*
X1341353Y1413866D03*
X1337509Y1416486D03*
Y1411318D03*
X1337469Y1413828D03*
X1337509Y1408818D03*
X1340509Y1416486D03*
X1346580Y1425240D03*
X1342580D03*
X1338580D03*
X1349579Y1421536D03*
X1349549Y1419016D03*
X1346579Y1421536D03*
X1346549Y1419016D03*
X1343549D03*
X1343579Y1421536D03*
X1337579D03*
X1337549Y1419016D03*
X1340579Y1421536D03*
X1340549Y1419016D03*
X1336176Y1492995D03*
X1338096Y1483295D03*
X1342876D03*
X1336186Y1485895D03*
X1344786D03*
X1338096Y1488495D03*
X1342876D03*
X1342186Y1485895D03*
X1338786D03*
X1349586Y1505295D03*
X1338086Y1495595D03*
X1336176Y1498195D03*
X1335486Y1495595D03*
X1345351Y1737117D03*
X1361550Y67264D03*
X1355750Y66886D03*
X1356868Y85324D03*
X1360109Y98050D03*
X1352199D03*
X1364369Y120380D03*
X1360629D03*
X1358094Y258633D03*
X1350094D03*
X1358094Y269008D03*
X1366094D03*
X1350156Y292066D03*
X1358094Y286948D03*
X1354397Y623374D03*
Y626274D03*
X1356597Y624874D03*
X1358663Y623144D03*
X1356497Y621874D03*
X1354397Y620474D03*
X1358663Y620244D03*
X1356367Y642080D03*
X1352527Y638278D03*
X1360964Y629514D03*
Y632414D03*
X1357717Y647180D03*
Y649780D03*
X1355117D03*
Y647180D03*
X1357717Y644580D03*
X1355117D03*
X1364317Y661368D03*
X1357057Y661328D03*
X1354257Y675765D03*
X1358461Y684151D03*
Y686651D03*
X1360961Y684073D03*
Y686573D03*
X1363461D03*
Y684073D03*
X1363435Y681573D03*
X1358435D03*
X1360935D03*
X1358461Y694151D03*
X1363461D03*
X1360961D03*
X1358461Y689151D03*
Y691651D03*
X1363461Y696651D03*
X1360961D03*
X1363461Y699151D03*
X1360961Y691573D03*
X1363461D03*
X1360961Y689073D03*
X1363461D03*
X1355222Y1200561D03*
X1364239Y1207949D03*
X1350809Y1202323D03*
X1361285Y1206718D03*
X1355641Y1210674D03*
X1362810Y1211071D03*
X1357490Y1254169D03*
Y1249169D03*
Y1251669D03*
Y1246669D03*
X1359990Y1254169D03*
X1362490D03*
X1359990Y1249169D03*
X1362490D03*
X1359990Y1251669D03*
X1362490D03*
Y1246669D03*
X1359990D03*
Y1269187D03*
Y1266687D03*
Y1264187D03*
Y1261687D03*
X1357490Y1269187D03*
Y1261687D03*
Y1264187D03*
Y1266687D03*
Y1256669D03*
Y1259169D03*
X1362490Y1269269D03*
Y1261769D03*
Y1266769D03*
Y1264269D03*
Y1256669D03*
Y1259169D03*
X1359990Y1256669D03*
Y1259169D03*
X1357490Y1271769D03*
X1362490D03*
X1359990D03*
X1364490Y1293694D03*
X1361830Y1291809D03*
X1363220Y1308821D03*
X1364570Y1311321D03*
X1363220Y1306221D03*
Y1303621D03*
X1360724Y1321184D03*
Y1324084D03*
X1364340Y1328527D03*
X1350959Y1339237D03*
X1351634Y1336080D03*
X1350884Y1333512D03*
X1364440Y1337527D03*
Y1331527D03*
Y1334527D03*
X1362274Y1330257D03*
Y1333157D03*
Y1336057D03*
X1352226Y1386804D03*
Y1383804D03*
X1352225Y1389788D03*
X1358509Y1416486D03*
Y1413818D03*
Y1411318D03*
Y1408818D03*
X1352509Y1416486D03*
Y1411318D03*
Y1413818D03*
Y1408818D03*
X1355509Y1416486D03*
Y1411318D03*
Y1413818D03*
Y1408818D03*
X1362580Y1425240D03*
X1358580D03*
X1354580D03*
X1350580D03*
X1352579Y1421536D03*
X1352549Y1419016D03*
X1355549D03*
X1362986Y1485895D03*
X1364896Y1483295D03*
Y1488495D03*
X1358196Y1492995D03*
X1362976D03*
X1364886Y1495595D03*
X1356286D03*
X1358186Y1505295D03*
X1358196Y1498195D03*
X1362976D03*
X1356276Y1502695D03*
X1351496D03*
X1356276Y1507895D03*
X1351496D03*
X1355586Y1505295D03*
X1362286Y1495595D03*
X1352186Y1505295D03*
X1358886Y1495595D03*
X1370199Y49379D03*
X1367950Y66886D03*
X1369808Y87587D03*
X1377682D03*
X1371259Y98000D03*
X1368109D03*
X1366094Y258633D03*
X1366156Y292066D03*
X1377862Y485552D03*
X1373862D03*
Y511052D03*
X1381457Y511050D03*
X1377862Y511052D03*
X1382123Y614130D03*
X1369978Y614164D03*
X1376757Y619497D03*
X1369303Y617321D03*
X1372791Y618921D03*
X1370053Y619889D03*
X1376745Y616858D03*
X1379734Y623043D03*
X1371847Y661328D03*
X1376761Y686573D03*
Y684073D03*
X1374261D03*
Y686573D03*
X1374245Y681573D03*
X1376745D03*
X1376761Y694151D03*
X1374261D03*
X1376761Y696651D03*
X1374261D03*
X1376761Y699151D03*
X1374261D03*
X1376761Y701651D03*
X1374261D03*
X1376761Y691573D03*
Y689073D03*
X1374261Y691573D03*
Y689073D03*
X1376761Y706651D03*
Y704151D03*
X1374261Y706651D03*
Y704151D03*
X1368137Y1222298D03*
Y1227798D03*
X1374476Y1266143D03*
X1376976D03*
X1379476D03*
X1374476Y1268643D03*
X1376976D03*
X1379476D03*
X1374476Y1273643D03*
Y1271143D03*
X1374576Y1283743D03*
Y1281243D03*
X1374476Y1276143D03*
Y1278643D03*
X1376976Y1273643D03*
Y1271143D03*
X1379476Y1273643D03*
Y1271143D03*
X1377076Y1281161D03*
Y1283661D03*
X1379576D03*
Y1281161D03*
X1376976Y1276143D03*
Y1278643D03*
X1379476D03*
Y1276143D03*
X1379576Y1288661D03*
X1377076Y1286161D03*
X1379576D03*
X1377076Y1288661D03*
X1379576Y1291243D03*
X1377076D03*
X1374576Y1288743D03*
Y1286243D03*
Y1291243D03*
X1368305Y1307340D03*
X1365820Y1308821D03*
X1368305Y1309840D03*
X1365820Y1306221D03*
Y1303621D03*
X1370012Y1342299D03*
X1371422Y1359024D03*
X1368922D03*
X1371505Y1353214D03*
X1376774Y1353366D03*
X1370012Y1344840D03*
X1376774Y1355874D03*
X1373785Y1349689D03*
X1379101Y1418621D03*
X1368299Y1425240D03*
X1372164Y1423810D03*
X1375341Y1421268D03*
X1371586Y1485895D03*
X1369676Y1483295D03*
Y1488495D03*
X1368986Y1485895D03*
X1365586D03*
X1376386Y1505295D03*
X1378296Y1502695D03*
Y1507895D03*
X1378986Y1505295D03*
X1382045Y1700038D03*
X1367351Y1737117D03*
X1379804Y1733118D03*
X1392199Y49379D03*
X1383715Y236594D03*
Y241594D03*
X1381457Y485550D03*
X1382014Y619518D03*
X1383507Y627892D03*
Y630433D03*
X1387097Y656274D03*
X1389297Y657774D03*
X1391363Y656044D03*
X1387097Y653374D03*
X1389197Y654774D03*
X1391363Y653144D03*
X1380306Y664816D03*
X1380256Y667466D03*
X1387097Y659174D03*
X1393664Y662384D03*
Y665284D03*
X1390417Y677480D03*
X1389067Y674980D03*
X1387817Y677480D03*
X1390417Y680080D03*
X1387817D03*
X1390417Y682680D03*
X1387817D03*
X1388757Y693397D03*
Y690897D03*
X1393343Y716971D03*
X1390807Y717053D03*
X1390817Y714471D03*
X1393317D03*
X1393343Y719471D03*
X1390807Y719553D03*
X1393367Y727023D03*
Y729523D03*
X1393343Y724471D03*
Y721971D03*
X1390807Y722053D03*
Y724553D03*
X1390853Y727053D03*
X1390376Y1268643D03*
X1392876D03*
Y1283661D03*
Y1281161D03*
X1390376D03*
Y1283661D03*
Y1273643D03*
Y1271143D03*
Y1276143D03*
Y1278643D03*
X1392876Y1273643D03*
Y1271143D03*
Y1276143D03*
Y1278643D03*
Y1288661D03*
Y1286161D03*
X1390376Y1288661D03*
Y1286161D03*
Y1291243D03*
X1392876D03*
X1393306Y1340515D03*
Y1343415D03*
X1383541Y1358568D03*
X1384216Y1355411D03*
X1380728Y1353811D03*
X1383466Y1352843D03*
X1383284Y1415973D03*
X1387308Y1413643D03*
X1392021Y1410360D03*
X1389786Y1485895D03*
X1391696Y1483295D03*
Y1488495D03*
X1384996Y1492995D03*
X1389776D03*
X1392386Y1485895D03*
X1384986Y1505295D03*
X1391686Y1495595D03*
X1383086D03*
X1384996Y1498195D03*
X1389776D03*
X1383076Y1502695D03*
Y1507895D03*
X1382386Y1505295D03*
X1389086Y1495595D03*
X1385686D03*
X1392068Y1667907D03*
X1381918D03*
X1385068Y1664907D03*
X1390738Y1664938D03*
X1383800Y1685398D03*
X1392068Y1676875D03*
X1381918D03*
X1388918Y1687878D03*
X1391750Y1697747D03*
X1382045Y1712038D03*
Y1708038D03*
Y1704038D03*
X1390045Y1712038D03*
X1384604Y1728318D03*
X1387620Y1721418D03*
X1385061D03*
X1390179Y1733118D03*
X1389351Y1737117D03*
X1393179Y1733118D03*
X1404917Y109037D03*
X1403207Y118938D03*
X1404917Y116911D03*
X1395302Y251136D03*
Y256136D03*
X1403500Y458377D03*
X1411000Y460362D03*
X1406500Y458362D03*
X1400500Y458377D03*
X1402452Y642825D03*
X1402678Y647064D03*
X1409445Y652266D03*
X1402003Y650221D03*
X1405491Y651821D03*
X1402753Y652789D03*
X1409445Y649758D03*
X1409143Y716971D03*
X1395843D03*
X1406643D03*
X1409127Y714471D03*
X1395817D03*
X1406627D03*
X1409143Y719471D03*
X1395843D03*
X1406643D03*
X1395867Y732023D03*
Y727023D03*
Y729523D03*
X1406667Y727023D03*
X1409167Y732023D03*
Y729523D03*
X1406667Y732023D03*
Y729523D03*
X1409167Y727023D03*
X1409143Y724471D03*
Y721971D03*
X1395843Y724471D03*
Y721971D03*
X1406643Y724471D03*
Y721971D03*
X1409167Y739523D03*
Y734523D03*
Y737023D03*
X1406667Y734523D03*
Y737023D03*
Y739523D03*
X1395376Y1268643D03*
X1406608Y1282606D03*
X1395376Y1273643D03*
Y1271143D03*
Y1281243D03*
Y1283743D03*
Y1276143D03*
Y1278643D03*
Y1288743D03*
Y1286243D03*
Y1291243D03*
X1405716Y1310618D03*
X1401740Y1311980D03*
X1399240D03*
X1408690Y1324803D03*
X1396302Y1328152D03*
Y1325552D03*
X1398902Y1328152D03*
Y1325552D03*
X1396302Y1322952D03*
X1398902D03*
X1401406Y1334918D03*
X1397652Y1330652D03*
X1399122Y1352258D03*
X1394856Y1352488D03*
X1399122Y1346458D03*
Y1349358D03*
X1396922Y1347858D03*
X1394856Y1349588D03*
X1397022Y1350858D03*
X1398375Y1403688D03*
X1401764Y1399928D03*
X1405207Y1395480D03*
X1408543Y1391826D03*
X1395463Y1406918D03*
X1405811Y1430021D03*
X1398386Y1485895D03*
X1403186D03*
X1405096Y1483295D03*
X1396476D03*
X1405096Y1488495D03*
X1396476D03*
X1395786Y1485895D03*
X1409186D03*
X1405786D03*
X1409456Y1537872D03*
X1409532Y1552845D03*
X1409409Y1549120D03*
Y1545220D03*
X1403257Y1552250D03*
X1405079Y1549953D03*
Y1544953D03*
Y1547453D03*
X1406655Y1564073D03*
X1409155D03*
X1405764Y1554436D03*
X1406074Y1581563D03*
X1397955Y1582178D03*
X1403232Y1579519D03*
X1397030Y1594060D03*
X1409286Y1605796D03*
X1406666Y1616332D03*
X1398058Y1619683D03*
X1409660Y1619853D03*
X1400029Y1615796D03*
X1406447Y1619572D03*
X1396783Y1617170D03*
X1399940Y1637127D03*
X1405058Y1639607D03*
X1397367Y1639951D03*
X1408023Y1638705D03*
X1398058Y1628651D03*
X1408208D03*
X1402425Y1649532D03*
X1406814Y1652439D03*
X1399599Y1657583D03*
X1398883Y1680341D03*
X1414199Y49379D03*
X1414619Y244450D03*
X1410750Y244583D03*
X1414000Y460362D03*
X1417000D03*
X1419335Y533958D03*
X1414823Y647030D03*
X1414714Y653008D03*
X1412434Y655943D03*
X1414157Y670665D03*
X1416207Y663333D03*
Y660792D03*
X1421797Y687354D03*
X1423963Y685724D03*
X1419697Y685954D03*
X1416241Y700281D03*
X1416291Y697631D03*
X1421897Y690354D03*
X1423963Y688624D03*
X1419697Y688854D03*
Y691754D03*
X1420417Y712660D03*
Y715260D03*
Y710060D03*
X1423017Y712660D03*
Y715260D03*
Y710060D03*
X1421667Y707560D03*
X1422757Y726097D03*
Y723597D03*
X1423417Y747051D03*
X1423407Y757133D03*
Y749633D03*
Y752133D03*
Y754633D03*
X1418982Y1175144D03*
X1414165Y1289564D03*
X1414172Y1286188D03*
X1424561Y1305566D03*
X1420690Y1324803D03*
X1417690D03*
X1414690D03*
X1411690D03*
X1424163Y1373240D03*
X1411508Y1388384D03*
X1414950Y1384942D03*
X1417491Y1381183D03*
X1420774Y1377106D03*
X1411786Y1485895D03*
X1409876Y1483295D03*
Y1488495D03*
X1416556Y1511082D03*
Y1519682D03*
X1419156Y1512992D03*
Y1517772D03*
X1413956Y1512992D03*
Y1517772D03*
X1416556Y1513682D03*
Y1517082D03*
Y1533082D03*
Y1524482D03*
X1419156Y1531172D03*
Y1526392D03*
X1413956Y1531172D03*
Y1526392D03*
X1423735Y1536715D03*
X1416556Y1530482D03*
Y1527082D03*
X1412020Y1542654D03*
X1415434Y1552845D03*
X1415709Y1545220D03*
Y1549120D03*
X1418523Y1542469D03*
X1419959Y1545076D03*
Y1547576D03*
X1416023Y1542469D03*
X1412559Y1549120D03*
Y1545220D03*
X1420735Y1559750D03*
X1412572Y1556953D03*
X1411655Y1564073D03*
X1412572Y1554436D03*
X1417981Y1568680D03*
X1423531Y1574795D03*
Y1582295D03*
Y1579795D03*
Y1577295D03*
X1424621Y1571911D03*
Y1569411D03*
X1416862Y1582871D03*
X1419811Y1599084D03*
X1416709Y1592819D03*
X1413836Y1586944D03*
X1421232Y1606126D03*
X1422914Y1601663D03*
X1412467Y1602234D03*
X1419914Y1602777D03*
X1418000Y1607500D03*
X1418740Y1622902D03*
X1421392Y1621706D03*
X1422154Y1626270D03*
X1423722Y1616780D03*
X1419622Y1616000D03*
X1422266Y1628947D03*
X1411113Y1637767D03*
X1421890Y1635500D03*
X1418755Y1654999D03*
X1413199Y1643920D03*
X1416357Y1644027D03*
X1420042Y1649716D03*
X1410315Y1646967D03*
X1424315D03*
X1411351Y1737117D03*
X1433817Y-34648D03*
X1438983Y-35569D03*
X1436263Y-18311D03*
Y-21711D03*
X1433817Y-25374D03*
Y-15374D03*
X1438883Y-15050D03*
Y-25050D03*
X1436263Y1689D03*
Y-1711D03*
X1433817Y-4648D03*
X1438883Y-5050D03*
X1433817Y5352D03*
Y14626D03*
X1438883Y14950D03*
Y4950D03*
X1438959Y25382D03*
X1436199Y49379D03*
X1427973Y60409D03*
X1434262Y52892D03*
X1438262D03*
X1431262Y61392D03*
X1434513Y106950D03*
X1439049Y107443D03*
X1429169Y107313D03*
X1438312Y152166D03*
X1431300Y538800D03*
X1435400Y536200D03*
X1431400Y533400D03*
X1435400Y530800D03*
X1439232Y596291D03*
X1435278Y679644D03*
X1436257Y676265D03*
X1434603Y682801D03*
X1438091Y684401D03*
X1435353Y685369D03*
X1426264Y694954D03*
Y697854D03*
X1439227Y747051D03*
X1425917D03*
X1428417D03*
X1428407Y762133D03*
Y759633D03*
X1425907D03*
X1439257Y762133D03*
Y759633D03*
X1425943Y757051D03*
X1428443D03*
X1425943Y749551D03*
Y752051D03*
Y754551D03*
X1428443D03*
Y752051D03*
Y749551D03*
X1439243Y757051D03*
Y749551D03*
Y752051D03*
Y754551D03*
X1439257Y764633D03*
Y769633D03*
Y767133D03*
X1425437Y1308184D03*
X1426202Y1310752D03*
X1427314Y1313482D03*
X1428458Y1316481D03*
X1429517Y1319447D03*
X1430312Y1322412D03*
X1431106Y1325219D03*
X1426441Y1369427D03*
X1428559Y1365296D03*
X1430465Y1361060D03*
X1438798Y1495595D03*
X1435160Y1519190D03*
Y1510590D03*
X1432560Y1517280D03*
Y1512500D03*
X1437760Y1517280D03*
Y1512500D03*
X1435160Y1516590D03*
Y1513190D03*
Y1532490D03*
X1432560Y1534300D03*
X1437760D03*
X1435160Y1534990D03*
X1432560Y1539080D03*
X1437760D03*
X1435160Y1540990D03*
Y1538390D03*
X1434235Y1550240D03*
X1433235Y1543800D03*
X1430735D03*
X1431735Y1550240D03*
X1435578Y1564902D03*
Y1562402D03*
X1430431Y1563595D03*
X1427931D03*
X1424971Y1566764D03*
Y1564264D03*
X1436940Y1554277D03*
X1434578Y1556331D03*
Y1559731D03*
X1430213Y1553652D03*
X1427713D03*
X1435604Y1572106D03*
Y1569606D03*
X1426031Y1582295D03*
X1431031Y1574795D03*
Y1577295D03*
X1426031Y1579795D03*
Y1577295D03*
Y1574795D03*
X1428531D03*
Y1577295D03*
Y1579795D03*
Y1582295D03*
X1430431Y1570595D03*
X1427931D03*
X1437901Y1579795D03*
Y1577295D03*
Y1574795D03*
Y1582295D03*
X1435401D03*
Y1579795D03*
Y1577295D03*
Y1574795D03*
X1431989Y1581199D03*
X1435584Y1596545D03*
X1434494Y1584844D03*
X1431989Y1584099D03*
X1429571Y1584844D03*
X1430244Y1609966D03*
X1438565Y1612583D03*
X1430075Y1613904D03*
X1430319Y1623504D03*
X1434316Y1616909D03*
X1430238Y1617137D03*
X1437594Y1616845D03*
X1426899Y1616990D03*
X1425390Y1635496D03*
X1429072Y1643655D03*
X1433327Y1643287D03*
X1433979Y1655655D03*
X1433911Y1649037D03*
X1433618Y1659331D03*
X1433157Y1651977D03*
X1436311Y1665948D03*
X1438078Y1669992D03*
X1439316Y1675080D03*
X1435904Y1694335D03*
X1433351Y1737117D03*
X1445292Y-28927D03*
X1445307Y-31442D03*
X1442023Y-36764D03*
X1442008Y-34249D03*
X1445276Y-36778D03*
X1445261Y-34263D03*
X1441908Y-26370D03*
X1445161Y-26356D03*
X1441909Y-19948D03*
X1445171D03*
X1441908Y-16370D03*
X1441923Y-13855D03*
X1445161Y-16356D03*
X1445176Y-13841D03*
X1441923Y-23855D03*
X1445176Y-23841D03*
X1441909Y-9948D03*
X1445171D03*
X1441909Y52D03*
X1445171D03*
X1441908Y-6370D03*
X1441923Y-3855D03*
X1445161Y-6356D03*
X1445176Y-3841D03*
X1441908Y3630D03*
X1445161Y3644D03*
X1441909Y10052D03*
X1445171D03*
X1441908Y13630D03*
X1441923Y16145D03*
X1445161Y13644D03*
X1445176Y16159D03*
X1441923Y6145D03*
X1445176Y6159D03*
X1445237Y26688D03*
X1445252Y24173D03*
X1441984Y26702D03*
X1441999Y24187D03*
X1445267Y21658D03*
X1445282Y19143D03*
X1441141Y53699D03*
X1446869Y105129D03*
X1445985Y116953D03*
X1451353Y116158D03*
X1443049Y107443D03*
X1448549Y114643D03*
X1446040Y120218D03*
X1452040Y113018D03*
X1440871Y130118D03*
X1453667Y152166D03*
X1441390Y163944D03*
X1440871Y152166D03*
X1454769Y163842D03*
X1444769D03*
X1442993Y176204D03*
X1444769Y174217D03*
X1453974Y174414D03*
X1449769Y174217D03*
X1439769D03*
Y182217D03*
X1449769D03*
X1456500Y457000D03*
X1443551Y539318D03*
Y535318D03*
X1441053Y560535D03*
X1452708Y610954D03*
Y607954D03*
X1449708Y610954D03*
X1446708D03*
Y607954D03*
X1449708D03*
X1440708Y610954D03*
X1443708D03*
X1440708Y607954D03*
X1443708D03*
X1452708Y613954D03*
X1446708Y616954D03*
Y619954D03*
X1440708D03*
Y616954D03*
X1443708D03*
Y619954D03*
X1449708Y613954D03*
X1446708D03*
X1440708D03*
X1443708D03*
X1446708Y622954D03*
X1440708D03*
X1443708D03*
X1452938Y617364D03*
X1450438D03*
X1452898Y621844D03*
X1450398D03*
X1448996Y645270D03*
Y647770D03*
X1451496Y645270D03*
X1453996D03*
Y647770D03*
X1451496D03*
X1449046Y650370D03*
X1454046D03*
X1451546D03*
X1446426D03*
X1443926D03*
X1443876Y645270D03*
Y647770D03*
X1446376Y645270D03*
Y647770D03*
X1447423Y679610D03*
X1447314Y684998D03*
X1442091Y684846D03*
X1442045Y682338D03*
X1446757Y703265D03*
X1448807Y695913D03*
Y693372D03*
X1445034Y688523D03*
X1452615Y705531D03*
X1453335Y729637D03*
Y732237D03*
Y734837D03*
X1453757Y743597D03*
Y746097D03*
X1441727Y747051D03*
X1444257Y757133D03*
Y759633D03*
Y762133D03*
X1441757Y759633D03*
Y762133D03*
X1441743Y757051D03*
Y754551D03*
Y752051D03*
Y749551D03*
X1444257Y772133D03*
Y764633D03*
Y769633D03*
Y767133D03*
X1441757Y772133D03*
Y764633D03*
Y769633D03*
Y767133D03*
X1454098Y1485895D03*
X1445498D03*
X1447408Y1483295D03*
X1452188D03*
X1447408Y1488495D03*
X1452188D03*
X1445488Y1492995D03*
X1440708D03*
X1451498Y1485895D03*
X1448098D03*
X1447398Y1495595D03*
X1445488Y1498195D03*
X1440708D03*
X1444798Y1495595D03*
X1441398D03*
X1444200Y1533240D03*
X1445535Y1551040D03*
Y1547420D03*
Y1543800D03*
X1439850Y1541470D03*
X1446027Y1561731D03*
X1448505Y1579725D03*
X1440401Y1574795D03*
Y1582295D03*
Y1579795D03*
Y1577295D03*
X1442901Y1582295D03*
Y1579795D03*
Y1577295D03*
Y1574795D03*
X1447026Y1577299D03*
X1455461Y1585567D03*
X1448061Y1593055D03*
X1451000Y1601000D03*
X1446000Y1600500D03*
X1450500Y1614500D03*
Y1624000D03*
X1445500Y1614500D03*
X1441000D03*
X1440027Y1667945D03*
X1455579Y1665701D03*
X1442579Y1673303D03*
X1447579D03*
X1452579D03*
X1453950Y1681450D03*
X1453553Y1686892D03*
X1445079Y1686678D03*
X1449070Y1686722D03*
X1448000Y1676000D03*
X1458199Y49379D03*
X1462405Y61563D03*
X1464830Y59054D03*
X1466681Y78590D03*
X1454549Y107443D03*
X1461242Y128242D03*
X1463017Y136368D03*
X1455667Y125733D03*
X1463017Y139518D03*
X1459177Y163796D03*
X1456226Y152166D03*
X1462682Y450372D03*
X1456982Y437362D03*
X1459682Y450372D03*
X1466609Y458608D03*
X1468395Y487582D03*
X1465395D03*
X1465832Y535330D03*
Y530656D03*
X1464257Y552977D03*
X1463647Y544977D03*
X1456282Y568977D03*
X1464257Y564977D03*
Y560977D03*
Y557498D03*
X1462497Y555021D03*
X1464257Y568977D03*
X1456282Y572977D03*
Y576977D03*
Y580977D03*
X1464257Y572977D03*
Y580977D03*
Y576977D03*
X1467708Y610954D03*
Y607954D03*
X1464708Y610954D03*
Y607954D03*
X1458708Y610954D03*
X1455708D03*
X1461708D03*
Y607954D03*
X1455708D03*
X1458708D03*
X1467708Y616954D03*
Y619954D03*
Y613954D03*
X1461708Y616954D03*
Y619954D03*
X1464708Y616954D03*
Y619954D03*
Y613954D03*
X1458708D03*
X1455708D03*
X1461708D03*
X1467708Y622954D03*
X1461708D03*
X1464708D03*
X1455438Y617364D03*
X1457938D03*
X1455398Y621844D03*
X1457898D03*
X1456496Y645270D03*
X1459396D03*
X1456496Y647770D03*
X1459396D03*
X1456546Y650370D03*
X1459446D03*
X1468257Y696265D03*
X1468196Y699221D03*
X1467521Y702378D03*
X1454715Y700931D03*
X1468271Y704946D03*
X1456881Y708201D03*
Y705301D03*
X1454715Y706931D03*
Y703931D03*
X1454815Y709931D03*
X1458777Y714194D03*
Y717094D03*
X1455935Y729637D03*
Y732237D03*
X1454585Y727137D03*
X1455935Y734837D03*
X1456335Y771710D03*
Y766628D03*
X1458861Y776628D03*
X1461361D03*
X1458861Y769128D03*
Y771628D03*
Y774128D03*
X1461361D03*
Y771628D03*
Y769128D03*
X1461335Y766628D03*
X1458835D03*
X1456335Y776710D03*
Y774210D03*
Y769210D03*
X1461371Y791696D03*
Y789196D03*
X1458871Y779196D03*
X1461371D03*
X1458871Y784196D03*
Y781696D03*
Y786696D03*
X1461371Y784196D03*
Y786696D03*
Y781696D03*
X1456371Y779210D03*
Y781710D03*
Y784210D03*
X1467508Y1492995D03*
X1467498Y1505295D03*
X1458898D03*
X1465598Y1495595D03*
X1467508Y1498195D03*
X1460808Y1502695D03*
X1465588D03*
X1460808Y1507895D03*
X1465588D03*
X1464898Y1505295D03*
X1461498D03*
X1468198Y1495595D03*
X1455579Y1636114D03*
X1466500Y1666000D03*
X1469034Y1667794D03*
X1468102Y1670817D03*
X1458795Y1687083D03*
X1456852Y1673320D03*
X1466599Y1679401D03*
X1466260Y1675155D03*
X1460457Y1685160D03*
X1457940Y1675710D03*
X1463038Y1687060D03*
X1466111Y1685098D03*
X1480199Y49379D03*
X1472129Y56083D03*
X1483820Y122713D03*
Y132405D03*
X1471395Y487582D03*
X1473947Y492169D03*
X1475257Y530656D03*
X1482257Y552977D03*
X1473408Y547948D03*
X1478257Y543977D03*
X1481257Y544977D03*
X1482044Y542517D03*
X1472257Y551241D03*
X1482257Y560477D03*
Y567977D03*
X1472757Y561264D03*
X1473362Y558380D03*
X1472257Y564977D03*
X1481898Y585476D03*
X1478258Y588108D03*
Y584142D03*
X1481934Y699670D03*
X1480300Y697750D03*
X1474963Y701915D03*
X1480232Y704575D03*
X1475009Y704488D03*
X1481725Y715490D03*
X1471009Y703978D03*
X1481725Y712949D03*
X1477952Y708100D03*
X1479757Y722865D03*
X1481665Y745809D03*
X1477171Y774196D03*
Y771696D03*
Y769196D03*
Y776696D03*
X1474661Y776628D03*
Y774128D03*
Y771628D03*
Y769128D03*
X1472161Y776628D03*
Y769128D03*
Y771628D03*
Y774128D03*
X1472145Y766628D03*
X1474645D03*
X1477145D03*
X1477171Y791696D03*
X1474671D03*
X1472171D03*
X1477171Y786696D03*
X1474671D03*
X1477171Y781696D03*
X1474671D03*
X1472171Y789196D03*
Y779196D03*
Y784196D03*
Y786696D03*
Y781696D03*
X1477171Y789196D03*
X1474671D03*
X1477171Y779196D03*
X1474671D03*
X1477171Y784196D03*
X1474671D03*
X1477177Y803488D03*
X1481177D03*
X1469950Y813232D03*
X1473728Y813552D03*
X1478177Y817013D03*
X1480677Y813488D03*
X1484177Y812988D03*
X1474177Y816872D03*
X1472288Y1492995D03*
X1474208Y1483295D03*
X1478988D03*
X1472298Y1485895D03*
X1480898D03*
X1474208Y1488495D03*
X1478988D03*
X1478298Y1485895D03*
X1474898D03*
X1474198Y1495595D03*
X1472288Y1498195D03*
X1471598Y1495595D03*
X1471616Y1670098D03*
X1479375Y1685984D03*
X1482798Y1685982D03*
X1469588Y1673342D03*
X1486000Y1686000D03*
X1470500Y1685500D03*
X1494891Y121171D03*
X1488647Y134562D03*
X1495539Y131237D03*
X1492237Y123842D03*
X1497386Y464980D03*
X1495682Y473302D03*
X1484395Y487582D03*
X1492514Y539657D03*
X1489757Y552977D03*
X1497257D03*
X1484416Y541658D03*
X1488510Y542816D03*
X1490602Y544755D03*
X1497310Y543960D03*
X1494967Y541898D03*
X1497257Y560477D03*
X1489757Y567977D03*
X1497257D03*
X1487660Y585748D03*
X1491677Y583588D03*
X1490677Y580688D03*
X1498543Y587841D03*
X1494371Y594462D03*
X1495236Y612838D03*
X1495486Y599938D03*
X1497986Y602438D03*
Y599938D03*
X1495236Y605338D03*
X1495486Y602438D03*
X1495236Y607838D03*
Y610338D03*
X1492636Y605258D03*
Y607758D03*
Y610258D03*
Y612758D03*
X1497986Y612838D03*
Y605338D03*
Y607838D03*
Y610338D03*
X1495486Y615988D03*
Y618488D03*
X1497986Y615988D03*
Y618488D03*
X1492886Y618408D03*
Y615908D03*
X1489963Y705301D03*
X1487797Y706931D03*
X1487897Y709931D03*
X1489963Y708201D03*
X1485697Y708431D03*
Y705531D03*
Y711331D03*
X1492264Y714544D03*
Y717444D03*
X1486417Y729637D03*
Y732237D03*
X1489017Y729687D03*
Y732237D03*
X1487667Y727137D03*
X1486417Y734837D03*
X1489017D03*
X1484265Y745809D03*
X1491943Y776628D03*
X1494443D03*
X1491943Y769128D03*
Y771628D03*
Y774128D03*
X1494443D03*
Y771628D03*
Y769128D03*
X1494417Y766628D03*
X1491917D03*
X1489417Y776710D03*
Y774210D03*
Y769210D03*
Y771710D03*
Y766628D03*
X1494487Y779210D03*
Y784210D03*
Y786710D03*
Y781710D03*
X1491987Y779210D03*
Y784210D03*
Y786710D03*
Y781710D03*
X1489487Y779210D03*
Y784210D03*
Y786710D03*
Y781710D03*
X1489177Y803488D03*
X1500500Y809063D03*
X1496532Y803513D03*
X1485177Y803488D03*
X1498177Y817013D03*
X1489177Y812988D03*
X1487923Y816770D03*
X1492673Y828513D03*
X1490973Y825557D03*
X1498177Y829359D03*
X1495670Y826073D03*
X1486761Y826279D03*
X1494386Y1178743D03*
X1493260Y1167390D03*
X1496960D03*
X1499098Y1485895D03*
X1494308Y1492995D03*
X1499088D03*
X1492398Y1495595D03*
X1494298Y1505295D03*
X1485698D03*
X1494308Y1498195D03*
X1499088D03*
X1492388Y1502695D03*
X1487608D03*
X1492388Y1507895D03*
X1487608D03*
X1491698Y1505295D03*
X1488298D03*
X1498398Y1495595D03*
X1494998D03*
X1488875Y1677385D03*
X1502199Y49379D03*
X1514576Y219730D03*
X1513348Y253954D03*
X1503785Y464815D03*
X1505974Y470636D03*
X1511917Y483878D03*
X1499752Y488424D03*
X1500757Y537438D03*
X1504757Y537378D03*
X1508757Y537456D03*
X1512757Y537477D03*
X1507644Y554372D03*
X1507468Y564357D03*
X1506337Y561677D03*
X1508281Y559390D03*
X1509757Y575477D03*
X1501821Y577664D03*
X1502986Y602438D03*
Y599938D03*
X1500486Y602438D03*
Y599938D03*
X1502486Y605338D03*
Y607838D03*
Y610338D03*
Y612838D03*
X1500486Y615988D03*
Y618488D03*
X1502986Y615988D03*
Y618488D03*
X1501278Y699221D03*
X1513382Y697750D03*
X1500603Y702378D03*
X1508045Y701915D03*
X1513314Y704575D03*
X1508045Y704423D03*
X1504091Y703978D03*
X1501353Y704946D03*
X1511034Y708100D03*
X1512757Y722897D03*
X1505905Y746119D03*
X1508505D03*
X1510287Y771710D03*
Y769210D03*
Y774210D03*
Y776710D03*
X1507743Y776628D03*
Y774128D03*
Y771628D03*
Y769128D03*
X1505243Y776628D03*
Y769128D03*
Y771628D03*
Y774128D03*
X1505227Y766628D03*
X1507727D03*
X1510227D03*
X1507787Y786710D03*
Y781710D03*
X1505287Y779210D03*
Y784210D03*
Y786710D03*
Y781710D03*
X1510287Y779210D03*
Y784210D03*
Y786710D03*
Y781710D03*
X1507787Y779210D03*
Y784210D03*
X1499243Y803513D03*
X1508177Y803488D03*
X1501500Y799948D03*
X1501730Y811872D03*
X1510261Y814611D03*
X1500422Y814180D03*
X1512523Y809679D03*
X1502177Y817013D03*
X1512539Y812920D03*
X1505016Y817107D03*
X1501338Y825147D03*
X1501636Y828796D03*
X1499469Y860322D03*
Y863322D03*
X1513470Y1178265D03*
X1504470D03*
X1504362Y1167390D03*
X1508063D03*
X1507698Y1485895D03*
X1505788Y1483295D03*
X1501008D03*
X1505788Y1488495D03*
X1501008D03*
X1505098Y1485895D03*
X1501698D03*
X1500998Y1495595D03*
X1512498Y1505295D03*
X1499351Y1737117D03*
X1524124Y47570D03*
X1515854Y119810D03*
X1522917Y119912D03*
X1529384Y201245D03*
X1517708Y216505D03*
X1527392Y238017D03*
X1516452Y249724D03*
X1514900Y251839D03*
X1519120Y479215D03*
X1515936Y484412D03*
X1516757Y537477D03*
X1519930Y543470D03*
X1516257Y547977D03*
X1516336Y551977D03*
X1516357Y555318D03*
X1516257Y559977D03*
X1519317Y561977D03*
X1527853Y560264D03*
X1524777Y605488D03*
Y607988D03*
X1527277Y605488D03*
Y607988D03*
X1524777Y610588D03*
X1527277D03*
X1524777Y613088D03*
X1527277D03*
X1524777Y615618D03*
X1527277D03*
X1524777Y618118D03*
X1527277D03*
X1515016Y699670D03*
X1514807Y715490D03*
Y712949D03*
X1522763Y708201D03*
Y705301D03*
X1518497Y705531D03*
X1520597Y706931D03*
X1518497Y708431D03*
X1520697Y709931D03*
X1518497Y711331D03*
X1525064Y714544D03*
Y717444D03*
X1521817Y729637D03*
Y732237D03*
X1519217Y729637D03*
Y732237D03*
X1520467Y727137D03*
X1521817Y734837D03*
X1519217D03*
X1515895Y746119D03*
X1518495D03*
X1522217Y771710D03*
X1527217Y766628D03*
X1522217Y769210D03*
X1524717Y766628D03*
X1522217D03*
Y774210D03*
Y776710D03*
X1524743Y776628D03*
X1527243D03*
X1524743Y769128D03*
Y771628D03*
Y774128D03*
X1527243D03*
Y771628D03*
Y769128D03*
X1527217Y779210D03*
Y784210D03*
Y786710D03*
Y781710D03*
X1524717Y779210D03*
X1522217D03*
X1524717Y784210D03*
Y786710D03*
X1522217Y784210D03*
Y786710D03*
X1524717Y781710D03*
X1522217D03*
X1515192Y814294D03*
X1517431Y811466D03*
X1521003Y1169488D03*
X1521217Y1190088D03*
X1524425Y1185241D03*
X1525898Y1485895D03*
X1527808Y1483295D03*
Y1488495D03*
X1521108Y1492995D03*
X1525888D03*
X1528498Y1485895D03*
X1521098Y1505295D03*
X1525898D03*
X1527798Y1495595D03*
X1519198D03*
X1521108Y1498195D03*
X1525888D03*
X1519188Y1502695D03*
X1527808D03*
X1514408D03*
X1519188Y1507895D03*
X1514408D03*
X1518498Y1505295D03*
X1525198Y1495595D03*
X1515098Y1505295D03*
X1521798Y1495595D03*
X1521351Y1737117D03*
X1530063Y-40911D03*
X1530064Y-27930D03*
X1530049Y-30445D03*
X1530033Y-35881D03*
X1530018Y-33366D03*
X1530048Y-38396D03*
X1533316Y-40925D03*
X1533317Y-27916D03*
X1536342Y-29236D03*
X1533302Y-30431D03*
X1541580Y-38849D03*
Y-28849D03*
X1536341Y-39605D03*
X1533301Y-38410D03*
X1539134Y-22512D03*
Y-25912D03*
X1530048Y-20028D03*
X1530063Y-17513D03*
X1530018Y-25058D03*
X1530033Y-22543D03*
X1533301Y-20014D03*
X1533316Y-17499D03*
X1536341Y-18819D03*
X1541580Y-19575D03*
X1528993Y4115D03*
Y26115D03*
X1538342Y28406D03*
X1540342Y48720D03*
X1543862Y75343D03*
X1539756Y71839D03*
X1534776D03*
X1539756Y66847D03*
X1534776D03*
X1532866Y69340D03*
X1541666D03*
X1535566D03*
X1538966D03*
X1537450Y226293D03*
X1533160Y231250D03*
X1536542Y300819D03*
X1536538Y296819D03*
X1536422Y292816D03*
X1536542Y304819D03*
Y308819D03*
X1534584Y467067D03*
X1539693Y535212D03*
X1542902Y543641D03*
X1539693Y543613D03*
X1532824Y555981D03*
X1532853Y560264D03*
X1539693Y558943D03*
X1532730Y562949D03*
X1534565Y564945D03*
X1534078Y699221D03*
X1533403Y702378D03*
X1540845Y701915D03*
Y704423D03*
X1536891Y703978D03*
X1534153Y704946D03*
X1543834Y708100D03*
X1543563Y757803D03*
X1543585Y762919D03*
X1543574Y760361D03*
X1538027Y766628D03*
X1540527D03*
X1540543Y776628D03*
Y774128D03*
Y771628D03*
Y769128D03*
X1538043Y776628D03*
Y769128D03*
Y771628D03*
Y774128D03*
X1538027Y784710D03*
Y779210D03*
X1540527D03*
X1538027Y781710D03*
X1540527D03*
X1539972Y807319D03*
X1529306Y1177468D03*
X1540801Y1178265D03*
X1537301D03*
X1539301Y1175765D03*
X1534317Y1216828D03*
X1532896Y1234836D03*
X1531227Y1227648D03*
X1540227D03*
X1542747Y1253602D03*
X1538587Y1245065D03*
X1540850Y1240863D03*
X1543772Y1241016D03*
X1543519Y1248205D03*
X1536916Y1240844D03*
X1534498Y1485895D03*
X1539298D03*
X1541208Y1483295D03*
X1532588D03*
X1541208Y1488495D03*
X1532588D03*
X1531898Y1485895D03*
X1541898D03*
X1543582Y1524562D03*
X1541191Y1544953D03*
Y1547453D03*
Y1549953D03*
X1539369Y1552250D03*
X1542767Y1564073D03*
X1541876Y1554436D03*
X1542186Y1581563D03*
X1534067Y1582178D03*
X1539344Y1579519D03*
X1543351Y1737117D03*
X1550965Y3001D03*
X1555568Y17045D03*
Y22037D03*
X1553601Y19541D03*
X1554510Y28406D03*
X1555452Y25977D03*
X1547424Y28406D03*
X1553452Y23981D03*
X1548496D03*
X1546496Y25977D03*
X1552674Y26477D03*
X1556379Y19541D03*
X1549274Y26477D03*
X1554520Y37106D03*
X1547434D03*
X1554510Y40020D03*
X1547424D03*
X1554520Y48720D03*
X1547434D03*
X1552662Y75343D03*
X1556776Y71839D03*
X1550756Y72850D03*
X1545776D03*
X1554866Y69340D03*
X1556776Y66847D03*
X1557566Y69340D03*
X1546562Y75343D03*
X1549962D03*
X1550756Y77842D03*
X1545776D03*
X1554360Y207251D03*
X1552981Y220826D03*
X1555481Y218326D03*
X1556960Y287478D03*
X1551900Y287288D03*
X1553913Y298119D03*
X1544489Y288816D03*
X1546789Y287116D03*
X1548772Y291916D03*
X1558480Y302678D03*
X1553154Y479063D03*
X1558198Y486791D03*
X1551779Y530698D03*
X1546149Y541169D03*
X1545960Y565162D03*
X1545987Y562012D03*
X1551887Y606938D03*
X1553657Y678965D03*
X1553827Y687991D03*
X1556027Y680391D03*
X1555893Y686261D03*
Y683361D03*
X1553657Y681965D03*
X1553727Y684991D03*
X1546257Y701097D03*
X1558194Y695501D03*
Y692501D03*
X1552347Y712897D03*
X1554947D03*
X1552347Y710297D03*
Y707697D03*
X1554947Y710297D03*
Y707697D03*
X1553597Y705197D03*
X1546114Y704575D03*
X1547607Y715490D03*
Y712949D03*
X1551250Y723840D03*
X1553750D03*
X1556555Y740617D03*
X1556544Y738059D03*
X1554055Y740617D03*
X1554044Y738059D03*
X1546965Y746119D03*
X1546954Y743561D03*
X1556708Y747282D03*
X1556688Y744688D03*
X1548119Y751952D03*
X1545619D03*
X1548119Y754832D03*
X1545619D03*
X1546063Y757803D03*
X1546085Y762919D03*
X1546074Y760361D03*
X1556708Y749782D03*
Y754782D03*
Y752282D03*
Y757282D03*
Y762282D03*
Y759782D03*
Y764782D03*
Y769782D03*
Y767282D03*
X1556121Y798542D03*
X1551124Y801289D03*
X1551961Y807269D03*
X1556361D03*
X1547561D03*
X1549877Y1217288D03*
Y1221288D03*
X1551113Y1238088D03*
X1548360Y1234750D03*
X1550517Y1232905D03*
X1555570Y1235968D03*
X1555367Y1248078D03*
X1555303Y1242557D03*
X1545627Y1254068D03*
X1545480Y1245090D03*
X1544911Y1260654D03*
X1543980Y1258312D03*
X1547062Y1258468D03*
X1553811Y1264488D03*
X1554692Y1269688D03*
X1557559Y1269095D03*
X1557510Y1280291D03*
X1554377Y1278763D03*
X1560454Y1279004D03*
X1553226Y1288814D03*
X1553548Y1284991D03*
X1556515Y1292232D03*
X1555222Y1302757D03*
X1547195Y1478165D03*
X1547216Y1480812D03*
X1547898Y1485895D03*
X1545988Y1483295D03*
Y1488495D03*
X1545298Y1485895D03*
X1552668Y1511082D03*
Y1519682D03*
X1555268Y1512992D03*
Y1517772D03*
X1550068Y1512992D03*
Y1517772D03*
X1545473Y1522117D03*
X1547548Y1520070D03*
X1552668Y1513682D03*
Y1517082D03*
Y1533082D03*
Y1524482D03*
X1555268Y1531172D03*
Y1526392D03*
X1550068Y1531172D03*
Y1526392D03*
X1552668Y1530482D03*
Y1527082D03*
X1548132Y1542654D03*
X1551821Y1549120D03*
Y1545220D03*
X1551546Y1552845D03*
X1556071Y1547576D03*
X1554635Y1542469D03*
X1552135D03*
X1556071Y1545076D03*
X1545644Y1552845D03*
X1545521Y1549120D03*
Y1545220D03*
X1548671Y1549120D03*
Y1545220D03*
X1548684Y1556953D03*
X1555993Y1563595D03*
X1558493D03*
X1556847Y1559750D03*
X1545267Y1564073D03*
X1547767D03*
X1548684Y1554436D03*
X1552118Y1569763D03*
X1549618D03*
X1554093Y1582295D03*
Y1574795D03*
Y1579795D03*
Y1577295D03*
X1551593Y1582295D03*
Y1579795D03*
X1556593Y1582295D03*
Y1579795D03*
Y1574795D03*
Y1577295D03*
X1549093Y1579795D03*
Y1582295D03*
X1546593D03*
Y1579795D03*
X1558560Y1571682D03*
X1556060D03*
X1557633Y1584844D03*
X1572965Y3001D03*
X1569742Y17045D03*
X1560548D03*
X1567774Y19541D03*
X1569742Y22037D03*
X1560548D03*
X1561597Y28406D03*
X1562669Y23981D03*
X1568683Y28406D03*
X1567625Y23981D03*
X1560669Y25977D03*
X1569625D03*
X1562557Y19541D03*
X1566847Y26477D03*
X1559779Y19541D03*
X1570552D03*
X1563447Y26477D03*
X1561607Y37106D03*
X1568693D03*
X1568683Y40020D03*
X1561597D03*
X1568693Y48720D03*
X1561607D03*
X1572756Y72847D03*
X1561756Y71839D03*
X1565866Y75340D03*
X1567776Y72847D03*
X1561756Y66847D03*
X1563666Y69340D03*
X1568566Y75340D03*
X1571966D03*
X1560966Y69340D03*
X1572756Y77839D03*
X1567776D03*
X1572502Y254250D03*
X1572549Y257491D03*
X1564517Y299432D03*
X1569592Y294816D03*
X1572283Y301816D03*
X1566442Y294816D03*
X1564506Y310334D03*
Y313734D03*
X1571516Y319099D03*
X1568070Y497847D03*
X1573070D03*
X1570570D03*
X1570068Y534095D03*
X1573326Y543351D03*
X1573487Y546996D03*
X1572436Y578933D03*
X1568446Y582733D03*
X1572436Y582433D03*
X1564946Y582733D03*
X1561246Y580393D03*
X1572436Y574022D03*
X1568936Y585933D03*
Y589433D03*
X1565436Y585933D03*
Y589433D03*
X1562016Y584283D03*
Y587783D03*
X1572436Y589433D03*
Y585933D03*
X1566010Y673210D03*
X1567208Y677281D03*
X1562730Y675180D03*
X1566533Y680438D03*
X1570021Y682038D03*
X1567283Y683006D03*
X1572514Y747188D03*
X1561714D03*
X1559214D03*
X1561688Y744688D03*
X1559188D03*
X1572498D03*
X1572588Y757282D03*
Y759782D03*
X1561708Y757282D03*
X1559208D03*
X1561708Y759782D03*
X1559208D03*
X1561708Y762282D03*
X1559208D03*
X1572514Y752188D03*
Y749688D03*
Y754688D03*
X1561714Y749688D03*
Y752188D03*
X1559214D03*
Y749688D03*
X1561714Y754688D03*
X1559214D03*
X1561708Y769782D03*
X1559208D03*
X1561708Y767282D03*
X1559208D03*
X1561708Y764782D03*
X1559208D03*
X1562995Y789522D03*
X1569518Y806684D03*
X1570583Y800104D03*
X1572668Y806778D03*
X1564267Y1253158D03*
X1567737Y1271411D03*
X1561927Y1269901D03*
X1568660Y1283460D03*
X1559181Y1287165D03*
X1568100Y1290418D03*
X1567000Y1293446D03*
X1562820Y1309360D03*
X1568456Y1311533D03*
X1572036Y1306083D03*
X1572416Y1303160D03*
X1564268Y1338440D03*
X1562937Y1341609D03*
X1572331Y1348205D03*
X1566901Y1347726D03*
X1564758Y1367834D03*
X1572906Y1366759D03*
X1563967Y1363205D03*
X1573560Y1485895D03*
X1573550Y1492995D03*
X1568770D03*
X1566860Y1495595D03*
X1573550Y1498195D03*
X1568770D03*
X1572860Y1495595D03*
X1569460D03*
X1563222Y1519190D03*
Y1510590D03*
X1560622Y1517280D03*
Y1512500D03*
X1565822Y1517280D03*
Y1512500D03*
X1563222Y1516590D03*
Y1513190D03*
Y1532490D03*
X1560622Y1534300D03*
X1565822D03*
X1572230Y1533000D03*
X1563222Y1534990D03*
X1560622Y1539080D03*
X1565822D03*
X1563222Y1540990D03*
X1573597Y1543800D03*
Y1547420D03*
Y1551040D03*
X1563222Y1538390D03*
X1564581Y1562316D03*
X1562613Y1564816D03*
X1564839Y1554561D03*
X1567089Y1563596D03*
X1562640Y1556331D03*
Y1559731D03*
X1564128Y1572225D03*
X1562621Y1569761D03*
X1559093Y1577295D03*
Y1574795D03*
X1565963D03*
X1568463D03*
X1565963Y1577295D03*
X1568463D03*
Y1579795D03*
X1565963D03*
X1568463Y1582295D03*
X1565963D03*
X1570963Y1574795D03*
Y1582295D03*
Y1579795D03*
Y1577295D03*
X1563463Y1574795D03*
Y1582295D03*
Y1579795D03*
Y1577295D03*
X1560051Y1581199D03*
X1574966Y1577038D03*
X1562556Y1584844D03*
X1560051Y1584099D03*
X1565351Y1737117D03*
X1583915Y17045D03*
X1574722D03*
X1581947Y19541D03*
X1583915Y22037D03*
X1576730Y19541D03*
X1574722Y22037D03*
X1575770Y28406D03*
X1576842Y23981D03*
X1582857Y28406D03*
X1581798Y23981D03*
X1574842Y25977D03*
X1583798D03*
X1588125Y19541D03*
X1581020Y26477D03*
X1573952Y19541D03*
X1584725D03*
X1577620Y26477D03*
X1575780Y37106D03*
X1582867D03*
X1582857Y40020D03*
X1575770D03*
X1582867Y48720D03*
X1575780D03*
X1587866Y75340D03*
X1574666D03*
X1578776Y71839D03*
X1583756D03*
X1576866Y69340D03*
X1578776Y66847D03*
X1583756D03*
X1585666Y69340D03*
X1579566D03*
X1582966D03*
X1574546Y251294D03*
X1586291Y306746D03*
Y303596D03*
X1586621Y484304D03*
X1580519Y497650D03*
X1575570Y497847D03*
X1579748Y536344D03*
X1584397Y655622D03*
X1586497Y651222D03*
X1586597Y654222D03*
X1584397Y652722D03*
Y649822D03*
X1576843Y674425D03*
X1579807Y671268D03*
X1586367Y671428D03*
X1587717Y676528D03*
Y673928D03*
X1585117Y676528D03*
Y673928D03*
Y679128D03*
X1587717D03*
X1573975Y679975D03*
X1579244Y682635D03*
X1573975Y682483D03*
X1576964Y686160D03*
X1586070Y696830D03*
Y694330D03*
X1580737Y693550D03*
Y691009D03*
X1578904Y721340D03*
Y723840D03*
X1577588Y747282D03*
X1575014Y747188D03*
X1577498Y744688D03*
X1574998D03*
X1575088Y757282D03*
X1577588Y749782D03*
Y754782D03*
Y752282D03*
X1575014Y749688D03*
Y752188D03*
Y754688D03*
X1584849Y793506D03*
X1575370Y1252770D03*
X1581327Y1252858D03*
X1586835Y1271918D03*
X1578690Y1283310D03*
X1585290Y1285098D03*
X1574168Y1283300D03*
X1577077Y1270937D03*
X1580577D03*
X1584068Y1271198D03*
X1583007Y1288958D03*
X1580010Y1296100D03*
X1574560Y1296410D03*
X1580520Y1289900D03*
X1586167Y1295478D03*
X1575024Y1306373D03*
X1587028Y1307137D03*
X1586557Y1304509D03*
X1577913Y1341623D03*
X1575504Y1356103D03*
X1578336D03*
Y1359253D03*
X1578411Y1348623D03*
X1578020Y1344773D03*
X1584156Y1381419D03*
X1586000Y1387641D03*
X1590723Y1381589D03*
X1582160Y1485895D03*
X1575470Y1483295D03*
X1580250D03*
X1575470Y1488495D03*
X1580250D03*
X1579560Y1485895D03*
X1576160D03*
X1586960Y1505295D03*
X1575460Y1495595D03*
X1574089Y1561731D03*
X1576653Y1579333D03*
X1583523Y1585567D03*
X1587351Y1737117D03*
X1594965Y3001D03*
X1603072Y17045D03*
X1598092D03*
X1588895D03*
X1603072Y22037D03*
X1598092D03*
X1596121Y19541D03*
X1590903D03*
X1588895Y22037D03*
X1589943Y28406D03*
X1595972Y23981D03*
X1591016D03*
X1597030Y28406D03*
X1589016Y25977D03*
X1597972D03*
X1602299Y19541D03*
X1595194Y26477D03*
X1598899Y19541D03*
X1591794Y26477D03*
X1589953Y37106D03*
X1597040D03*
X1597030Y40020D03*
X1589943D03*
X1597040Y48720D03*
X1589953D03*
X1589776Y72847D03*
X1594756D03*
X1596666Y75340D03*
X1600776Y71842D03*
X1598866Y69343D03*
X1600776Y66850D03*
X1590566Y75340D03*
X1601562Y69343D03*
X1593966Y75340D03*
X1589776Y77839D03*
X1594756D03*
X1603970Y222956D03*
X1593303Y234250D03*
Y239250D03*
X1602270Y229530D03*
X1598303Y234250D03*
X1596462Y229790D03*
X1593658Y252010D03*
X1593303Y244250D03*
X1593349Y248160D03*
X1597481Y271991D03*
X1599837Y295328D03*
X1600918Y521688D03*
X1593214Y531226D03*
X1604890D03*
X1596299Y536344D03*
X1597562Y555463D03*
X1595036D03*
X1591962D03*
X1589436D03*
X1599978Y643512D03*
X1599303Y646669D03*
X1602791Y648269D03*
X1600053Y649237D03*
X1588663Y649592D03*
Y652492D03*
X1590964Y661741D03*
Y658741D03*
X1594844Y713419D03*
Y715919D03*
X1592344D03*
Y713419D03*
X1594818Y710919D03*
X1594844Y718419D03*
X1592344D03*
X1594844Y720919D03*
X1592344D03*
X1594688Y723512D03*
Y726012D03*
Y728512D03*
Y731012D03*
X1592188Y723512D03*
Y726012D03*
Y728512D03*
Y731012D03*
X1594688Y736012D03*
X1592188D03*
X1594688Y733512D03*
X1592188D03*
X1594900Y780112D03*
X1589557Y1252778D03*
X1590097Y1246768D03*
X1598467Y1267539D03*
X1588832Y1269083D03*
X1597177Y1282288D03*
X1594152Y1282578D03*
X1598883Y1270766D03*
X1590827Y1271378D03*
X1593397Y1271458D03*
X1596273Y1271472D03*
X1594539Y1295288D03*
X1591005Y1288892D03*
X1596363Y1286296D03*
X1590921Y1309276D03*
X1603507Y1306262D03*
X1599241Y1306622D03*
X1589845Y1305289D03*
X1599007Y1309762D03*
X1601772Y1337293D03*
X1601959Y1351773D03*
X1597621Y1365384D03*
X1595438Y1370603D03*
X1592788Y1388318D03*
X1597234Y1382689D03*
X1599139Y1400464D03*
X1600531Y1404710D03*
X1597992Y1433183D03*
X1595716Y1431861D03*
X1602782Y1435920D03*
X1600442Y1434535D03*
X1595570Y1492995D03*
X1600350D03*
X1602270Y1483295D03*
X1600360Y1485895D03*
X1602270Y1488495D03*
X1602960Y1485895D03*
X1595560Y1505295D03*
X1602260Y1495595D03*
X1593660D03*
X1595570Y1498195D03*
X1600350D03*
X1588870Y1502695D03*
X1593650D03*
X1588870Y1507895D03*
X1593650D03*
X1592960Y1505295D03*
X1599660Y1495595D03*
X1589560Y1505295D03*
X1596260Y1495595D03*
X1616965Y3001D03*
X1605077Y19541D03*
X1604117Y28406D03*
X1604127Y37106D03*
X1604117Y40020D03*
X1604127Y48720D03*
X1609866Y75340D03*
X1611776Y72847D03*
X1616756D03*
X1607666Y69343D03*
X1605756Y71842D03*
Y66850D03*
X1612566Y75340D03*
X1615966D03*
X1604962Y69343D03*
X1611776Y77839D03*
X1616756D03*
X1615020Y183050D03*
X1619909Y298742D03*
Y293742D03*
X1612144Y418552D03*
X1614701Y422587D03*
X1616464Y457509D03*
X1616250Y465042D03*
X1609166Y527300D03*
X1611775D03*
X1609166Y524700D03*
X1611775D03*
X1613169Y531819D03*
X1604991Y536344D03*
X1606535Y553297D03*
X1616084Y549105D03*
X1616198Y556364D03*
X1618859Y542820D03*
X1607369Y561330D03*
X1609355Y592794D03*
X1618356Y612137D03*
Y609137D03*
X1618434Y605753D03*
X1609044Y600986D03*
X1608640Y640660D03*
X1617397Y630822D03*
Y636622D03*
Y633722D03*
X1615677Y648488D03*
X1618117Y657528D03*
Y654928D03*
X1606745Y646206D03*
X1612014Y648866D03*
X1606745Y648714D03*
X1613507Y657240D03*
X1609734Y652391D03*
X1618117Y660128D03*
X1613507Y659781D03*
X1613154Y688238D03*
Y690738D03*
X1605644Y715919D03*
Y713419D03*
X1608144D03*
Y715919D03*
X1605628Y710919D03*
X1608128D03*
X1610628D03*
X1610718Y713513D03*
Y716013D03*
X1605644Y718419D03*
Y720919D03*
X1608144Y718419D03*
Y720919D03*
X1610718Y721013D03*
Y718513D03*
X1608118Y723512D03*
X1605618D03*
X1608118Y726012D03*
X1605618D03*
X1610618Y723512D03*
X1605618Y728512D03*
X1617200Y766870D03*
X1607267Y1271978D03*
X1604137Y1271358D03*
X1605801Y1286168D03*
X1605447Y1288748D03*
X1608901Y1285887D03*
X1605360Y1294595D03*
X1608652Y1303338D03*
X1608341Y1313269D03*
X1608418Y1333589D03*
Y1331089D03*
X1614767Y1443512D03*
X1605648Y1437305D03*
X1607050Y1483295D03*
X1608960Y1485895D03*
X1607050Y1488495D03*
X1606360Y1485895D03*
X1613760Y1505295D03*
X1615670Y1502695D03*
Y1507895D03*
X1616360Y1505295D03*
X1609351Y1737117D03*
X1631987Y19541D03*
X1632896Y28406D03*
X1625809D03*
X1626882Y23981D03*
X1631838D03*
X1624882Y25977D03*
X1622329Y28261D03*
X1631060Y26477D03*
X1627660D03*
X1632906Y37106D03*
X1625819D03*
X1632896Y40020D03*
X1625809D03*
X1632906Y48720D03*
X1625819D03*
X1623189D03*
X1629662Y69343D03*
X1633070Y75340D03*
X1618666D03*
X1627756Y71842D03*
X1622776D03*
X1627756Y66850D03*
X1622776D03*
X1620862Y69343D03*
X1623562D03*
X1626962D03*
X1631200Y164110D03*
X1627410Y172008D03*
X1631455Y167875D03*
X1627152Y168920D03*
X1629597Y221842D03*
Y227157D03*
X1627156Y238303D03*
X1627986Y282728D03*
X1627909Y286742D03*
Y298742D03*
Y294742D03*
Y290742D03*
X1619909Y306746D03*
Y303596D03*
X1627909Y302742D03*
X1621680Y366920D03*
X1632500Y381500D03*
X1625000Y383399D03*
X1630927Y398002D03*
X1631657Y392925D03*
X1631889Y521480D03*
X1618884Y533388D03*
X1632798Y544564D03*
X1622391Y564169D03*
X1631558Y588513D03*
X1628756Y588591D03*
X1624067Y588474D03*
X1621187Y588591D03*
X1632012Y603015D03*
X1621512D03*
X1625012D03*
X1628512D03*
X1632978Y624512D03*
X1632303Y627669D03*
X1633053Y630237D03*
X1621663Y630592D03*
X1619597Y635222D03*
X1621663Y633492D03*
X1619497Y632222D03*
X1623964Y642741D03*
Y639741D03*
X1620717Y657528D03*
X1619367Y652428D03*
X1620717Y654928D03*
X1621050Y671768D03*
X1623550D03*
X1620717Y660128D03*
X1627643Y694419D03*
Y696919D03*
Y699419D03*
X1625143D03*
Y696919D03*
Y694419D03*
X1627643Y701919D03*
X1625143D03*
X1627617Y691919D03*
X1625117D03*
Y709512D03*
Y704512D03*
Y707012D03*
Y712012D03*
X1627617Y709512D03*
Y704512D03*
Y707012D03*
Y712012D03*
X1628046Y763765D03*
X1626928Y1260917D03*
X1629428D03*
X1631928D03*
X1626333Y1311091D03*
Y1308091D03*
X1627052Y1424716D03*
X1627174Y1420450D03*
X1625285Y1433384D03*
X1635281Y1422450D03*
X1627217Y1428366D03*
X1627242Y1436148D03*
X1627181Y1448016D03*
X1622697Y1440797D03*
X1625170Y1444016D03*
X1635227Y1436528D03*
X1627160Y1485895D03*
X1629070Y1483295D03*
Y1488495D03*
X1622370Y1492995D03*
X1627150D03*
X1633160Y1485895D03*
X1629760D03*
X1629060Y1495595D03*
X1620460D03*
X1622360Y1505295D03*
X1622370Y1498195D03*
X1627150D03*
X1620450Y1502695D03*
Y1507895D03*
X1619760Y1505295D03*
X1626460Y1495595D03*
X1623060D03*
X1631351Y1737117D03*
X1638965Y3001D03*
X1648128Y17045D03*
X1633954D03*
X1638934D03*
X1648128Y22037D03*
X1647069Y28406D03*
X1648011Y25977D03*
X1633954Y22037D03*
X1638934D03*
X1646160Y19541D03*
X1640943D03*
X1639983Y28406D03*
X1641055Y23981D03*
X1646011D03*
X1639055Y25977D03*
X1633838D03*
X1645233Y26477D03*
X1638165Y19541D03*
X1641833Y26477D03*
X1634765Y19541D03*
X1647079Y37106D03*
X1639993D03*
X1647069Y40020D03*
X1639983D03*
X1647079Y48720D03*
X1639993D03*
X1634980Y72847D03*
X1639960D03*
X1641870Y75340D03*
X1645980Y71839D03*
X1644070Y69340D03*
X1645980Y66847D03*
X1646770Y69340D03*
X1635770Y75340D03*
X1639170D03*
X1634980Y77839D03*
X1639960D03*
X1636047Y224597D03*
Y229912D03*
X1642240Y399603D03*
X1642135Y414202D03*
X1647310Y408922D03*
Y411422D03*
X1639800Y426982D03*
X1636800D03*
X1639800Y429982D03*
X1636800D03*
X1639800Y432982D03*
X1636800D03*
X1647110Y434177D03*
X1639800Y435982D03*
X1636800D03*
X1639800Y438982D03*
X1636800D03*
X1636929Y524690D03*
Y528190D03*
Y531690D03*
Y535190D03*
Y538690D03*
X1639868Y542444D03*
X1636783Y542604D03*
X1635798Y545564D03*
X1638798D03*
Y548964D03*
Y552164D03*
X1635798D03*
Y548964D03*
Y555364D03*
X1638798D03*
X1635798Y558364D03*
X1635697Y561253D03*
X1635944Y609510D03*
Y612510D03*
X1636022Y606126D03*
X1645123Y624478D03*
X1647158Y618971D03*
X1639745Y627206D03*
X1646507Y640781D03*
X1645014Y629866D03*
X1639745Y629714D03*
X1635791Y629269D03*
X1646507Y638240D03*
X1642734Y633391D03*
X1638443Y699419D03*
Y696919D03*
Y694419D03*
Y701919D03*
X1640943Y694419D03*
Y696919D03*
Y699419D03*
Y701919D03*
X1643517Y702013D03*
Y699513D03*
Y694513D03*
Y697013D03*
X1643427Y691919D03*
X1640927D03*
X1638427D03*
X1640877Y706972D03*
Y709472D03*
X1638377D03*
Y704472D03*
Y706972D03*
X1640877Y704472D03*
X1643377Y709510D03*
Y704510D03*
Y707010D03*
X1640877Y711972D03*
X1638377D03*
X1643377Y712010D03*
X1635088Y767205D03*
Y771005D03*
X1644188Y766870D03*
X1634428Y1260917D03*
X1645163Y1276184D03*
X1641677Y1341488D03*
X1641904Y1351467D03*
Y1348567D03*
X1641677Y1344488D03*
X1641087Y1396118D03*
X1641065Y1403393D03*
X1644001Y1408069D03*
X1646483Y1412741D03*
X1641065Y1406393D03*
X1643283Y1425541D03*
X1643183Y1419441D03*
X1643283Y1431541D03*
X1635619Y1430536D03*
X1639834Y1434478D03*
X1636167Y1446746D03*
X1642400Y1439674D03*
X1645979Y1437950D03*
X1650400Y1437820D03*
X1641167Y1446746D03*
X1648337Y1451313D03*
X1635760Y1485895D03*
X1633850Y1483295D03*
Y1488495D03*
X1647260Y1495595D03*
X1640560Y1505295D03*
X1647250Y1502695D03*
X1642470D03*
X1647250Y1507895D03*
X1642470D03*
X1646560Y1505295D03*
X1643160D03*
X1647700Y1674228D03*
X1646879Y1681738D03*
X1648013Y1713684D03*
X1645029Y1715609D03*
Y1710609D03*
X1648029Y1708609D03*
X1648013Y1728834D03*
X1648029Y1718759D03*
Y1723759D03*
X1645029Y1725759D03*
Y1730759D03*
X1648029Y1733909D03*
X1660965Y3001D03*
X1653108Y17045D03*
X1655116Y19541D03*
X1653108Y22037D03*
X1654156Y28406D03*
X1652338Y19541D03*
X1648938D03*
X1654166Y37106D03*
X1654156Y40020D03*
X1654166Y48720D03*
X1650960Y66847D03*
X1652870Y69340D03*
X1655066Y75343D03*
X1662065Y72850D03*
X1656980D03*
X1650960Y71839D03*
X1657766Y75343D03*
X1661166D03*
X1650170Y69340D03*
X1662065Y77842D03*
X1656980D03*
X1652525Y141762D03*
Y146762D03*
Y151762D03*
Y161762D03*
X1650023Y221842D03*
X1654419Y224597D03*
X1659419D03*
X1654419Y233062D03*
X1650023Y227157D03*
X1654419Y229912D03*
X1661928Y230172D03*
X1652610Y394727D03*
X1659610D03*
X1652810Y407402D03*
X1650020Y408952D03*
Y411452D03*
X1661110Y434177D03*
X1654110D03*
X1657545Y434506D03*
X1650035Y434750D03*
X1657194Y599956D03*
X1651194D03*
X1660194Y609450D03*
X1654194D03*
X1660194Y599956D03*
X1657194Y609450D03*
X1654194Y599956D03*
X1651194Y609450D03*
X1654147Y616523D03*
X1650917Y657528D03*
Y654928D03*
X1653517Y657528D03*
X1652167Y652428D03*
X1653517Y654928D03*
X1648604Y671768D03*
X1650917Y660128D03*
X1651104Y671768D03*
X1653517Y660128D03*
X1651959Y689800D03*
X1662377Y696300D03*
Y693300D03*
X1660594Y1298735D03*
X1651187D03*
X1660594Y1303935D03*
Y1306535D03*
Y1301335D03*
X1651187Y1303935D03*
Y1306535D03*
Y1301335D03*
X1651072Y1314137D03*
X1660572Y1313837D03*
X1660635Y1329166D03*
X1651072Y1323137D03*
Y1320137D03*
Y1317137D03*
X1660572Y1322837D03*
Y1319837D03*
X1660635Y1326466D03*
X1660572Y1316837D03*
X1658015Y1328966D03*
X1658115Y1326466D03*
X1660635Y1331666D03*
Y1334166D03*
Y1339166D03*
Y1336666D03*
X1650177Y1341488D03*
X1658277Y1341888D03*
X1658015Y1336466D03*
Y1338966D03*
Y1331466D03*
Y1333966D03*
X1650177Y1351467D03*
Y1348567D03*
X1658904Y1351467D03*
Y1348567D03*
X1650177Y1344488D03*
X1658677D03*
X1653390Y1386316D03*
Y1388857D03*
X1654774Y1402619D03*
X1648857Y1403424D03*
X1649197Y1396743D03*
X1654883Y1397231D03*
X1660152Y1397383D03*
X1664106Y1397828D03*
X1660152Y1399891D03*
X1657163Y1393706D03*
X1661807Y1416948D03*
X1655383Y1425541D03*
X1649283Y1419441D03*
Y1431541D03*
X1655383D03*
Y1419441D03*
X1663777Y1421568D03*
X1662487Y1424178D03*
X1662465Y1444358D03*
X1655957Y1445116D03*
X1658089Y1437444D03*
X1649380Y1446713D03*
X1662560Y1485895D03*
X1653960D03*
X1655870Y1483295D03*
X1660650D03*
X1655870Y1488495D03*
X1660650D03*
X1649170Y1492995D03*
X1653950D03*
X1659960Y1485895D03*
X1656560D03*
X1649160Y1505295D03*
X1655860Y1495595D03*
X1649170Y1498195D03*
X1653950D03*
X1653260Y1495595D03*
X1649860D03*
X1662129Y1582178D03*
X1659975Y1592929D03*
X1653464Y1668416D03*
X1661101Y1671631D03*
X1656101Y1671720D03*
X1651101Y1671833D03*
X1653930Y1660640D03*
X1656180Y1659220D03*
X1656849Y1664949D03*
X1651698Y1665045D03*
X1651101Y1700478D03*
X1661125Y1690751D03*
X1656101Y1701094D03*
X1656997Y1708609D03*
X1660541Y1704237D03*
X1656997Y1723759D03*
Y1718759D03*
X1653351Y1737117D03*
X1656997Y1733909D03*
X1677030Y28406D03*
X1677972Y25977D03*
X1676121Y19541D03*
X1669943Y28406D03*
X1675972Y23981D03*
X1671016D03*
X1669016Y25977D03*
X1675194Y26477D03*
X1671794D03*
X1677040Y37106D03*
X1669953D03*
X1677030Y40020D03*
X1669943D03*
X1677040Y48720D03*
X1669953D03*
X1677204Y75340D03*
X1663866Y75343D03*
X1672960Y71839D03*
X1667980Y66847D03*
X1672960D03*
X1674870Y69340D03*
X1667980Y71839D03*
X1666070Y69340D03*
X1668770D03*
X1672170D03*
X1673100Y121762D03*
Y126762D03*
Y136762D03*
Y131762D03*
X1665100Y156762D03*
Y166762D03*
X1673403Y199997D03*
X1664335Y210191D03*
X1673223Y220857D03*
X1663310Y215488D03*
X1663610Y394727D03*
X1668516Y599956D03*
X1674516D03*
X1668516Y609450D03*
X1671516Y599956D03*
X1674516Y609450D03*
X1677516Y599956D03*
X1671516Y609450D03*
X1677516D03*
X1664789Y767265D03*
Y771065D03*
X1673889Y766870D03*
X1675187Y1298735D03*
Y1303935D03*
Y1306535D03*
Y1301335D03*
X1674972Y1313837D03*
X1675134Y1329219D03*
X1675234Y1326519D03*
X1674972Y1316837D03*
X1672623Y1326476D03*
X1663437Y1326526D03*
X1674972Y1319837D03*
Y1322837D03*
X1677754Y1326519D03*
Y1329019D03*
X1663437Y1334726D03*
X1672623Y1334676D03*
X1663437Y1329726D03*
X1672623Y1332176D03*
X1663437Y1332226D03*
X1672623Y1329676D03*
X1675134Y1331719D03*
Y1334219D03*
Y1336719D03*
Y1339219D03*
X1677754Y1339019D03*
Y1336519D03*
Y1331519D03*
Y1334019D03*
X1674831Y1351266D03*
Y1348366D03*
X1675931Y1384335D03*
Y1387235D03*
X1666919Y1402585D03*
X1667594Y1399428D03*
X1666844Y1396860D03*
X1671067Y1405418D03*
X1672277Y1407694D03*
X1674777D03*
X1672501Y1416678D03*
X1672907Y1429928D03*
X1672273Y1420567D03*
X1675641Y1432891D03*
X1672401Y1423365D03*
X1664237Y1426278D03*
X1671079Y1435069D03*
X1663239Y1428592D03*
X1666290Y1444391D03*
X1670147Y1444311D03*
X1675960Y1485895D03*
X1667360D03*
X1669270Y1483295D03*
X1674050D03*
X1669270Y1488495D03*
X1674050D03*
X1673360Y1485895D03*
X1669960D03*
X1673630Y1533092D03*
Y1537872D03*
X1676685Y1537893D03*
X1671034Y1549734D03*
Y1552234D03*
X1668703Y1550898D03*
X1671034Y1546934D03*
X1673674Y1563575D03*
X1668827Y1553551D03*
X1671034Y1557234D03*
Y1554734D03*
X1673706Y1560425D03*
X1670248Y1581563D03*
X1671006Y1576744D03*
Y1574244D03*
Y1571744D03*
X1668826Y1575498D03*
Y1572998D03*
X1676176Y1580650D03*
X1674923Y1582973D03*
X1677556Y1656405D03*
X1674356D03*
X1671156D03*
X1676971Y1668582D03*
X1670534Y1670149D03*
X1666168Y1667688D03*
X1670202Y1663150D03*
X1675290Y1663157D03*
X1673245Y1673475D03*
X1674338Y1677832D03*
X1671902Y1676267D03*
X1669377Y1675241D03*
X1664256Y1690794D03*
X1673132Y1690741D03*
X1670773Y1688827D03*
X1680029Y1710609D03*
Y1715609D03*
X1668000Y1711759D03*
X1665520Y1716877D03*
X1672500Y1708927D03*
X1668000Y1726909D03*
X1675360Y1721252D03*
X1675351Y1737117D03*
X1665520Y1732027D03*
X1682965Y3001D03*
X1692262Y17045D03*
X1678088D03*
X1683068D03*
X1692262Y22037D03*
X1692145Y25977D03*
X1678088Y22037D03*
X1683068D03*
X1690294Y19541D03*
X1685077D03*
X1684117Y28406D03*
X1691203D03*
X1690145Y23981D03*
X1685189D03*
X1683189Y25977D03*
X1689367Y26477D03*
X1682299Y19541D03*
X1685967Y26477D03*
X1678899Y19541D03*
X1684127Y37106D03*
X1691213D03*
X1691203Y40020D03*
X1684117D03*
X1691213Y48720D03*
X1684127D03*
X1679114Y72847D03*
X1688200Y69343D03*
X1690114Y66850D03*
Y71842D03*
X1686004Y75340D03*
X1684094Y72847D03*
X1690900Y69343D03*
X1679904Y75340D03*
X1683304D03*
X1679114Y77839D03*
X1684094D03*
X1684925Y118762D03*
X1695100Y121762D03*
X1683275Y120762D03*
X1695100Y136762D03*
Y131762D03*
X1684925D03*
Y136762D03*
Y123762D03*
Y126762D03*
Y149762D03*
Y145762D03*
X1695100Y146762D03*
X1684925Y141762D03*
X1695100Y156762D03*
Y161762D03*
Y166762D03*
X1684925Y161762D03*
Y153762D03*
Y157762D03*
Y166762D03*
X1678809Y206451D03*
X1682433Y220857D03*
X1682408Y228337D03*
X1684942Y234000D03*
X1689000D03*
X1692429Y403985D03*
X1694050Y416643D03*
X1690208Y421855D03*
X1686154Y434160D03*
X1690140D03*
X1692450Y436772D03*
X1692974Y553115D03*
X1685890Y708610D03*
X1684708Y1298435D03*
Y1303635D03*
Y1306235D03*
Y1301035D03*
X1684672Y1313837D03*
X1690697Y1329066D03*
Y1326566D03*
X1684672Y1322837D03*
Y1319837D03*
Y1316837D03*
X1690697Y1336566D03*
Y1334066D03*
Y1331566D03*
X1679028Y1341733D03*
X1687234Y1341533D03*
Y1344033D03*
X1679028Y1344233D03*
X1690697Y1339066D03*
X1687233Y1351320D03*
X1679133Y1351420D03*
X1687233Y1348420D03*
X1679133Y1348520D03*
X1679180Y1372169D03*
X1681780D03*
X1679180Y1366969D03*
X1681780D03*
Y1369569D03*
X1679180D03*
X1680530Y1374669D03*
X1686172Y1386416D03*
Y1388957D03*
X1685963Y1402187D03*
X1687665Y1397331D03*
X1692934Y1397483D03*
Y1399991D03*
X1689945Y1393806D03*
X1682500Y1390475D03*
X1680300Y1391875D03*
X1682500Y1396275D03*
X1680400Y1394875D03*
X1678234Y1393605D03*
Y1396505D03*
X1682500Y1393375D03*
X1687621Y1404138D03*
X1683587Y1433425D03*
X1684677Y1440258D03*
X1687357Y1440268D03*
X1683741Y1443075D03*
X1685298Y1451231D03*
X1681538Y1451522D03*
X1689062Y1451496D03*
X1687783Y1472068D03*
X1680430Y1511198D03*
X1680730Y1519682D03*
X1682760Y1512169D03*
X1683330Y1517772D03*
X1678130Y1512992D03*
Y1517772D03*
X1680730Y1517082D03*
Y1513682D03*
Y1533082D03*
Y1524482D03*
X1683330Y1531172D03*
Y1526392D03*
X1678130Y1531172D03*
Y1526392D03*
X1684172Y1538135D03*
X1680730Y1530482D03*
Y1527082D03*
X1682561Y1552726D03*
X1685745Y1552579D03*
X1686219Y1549994D03*
X1691226Y1563526D03*
X1680558Y1555690D03*
X1688584Y1553284D03*
X1691548Y1555287D03*
X1691226Y1559526D03*
X1685745Y1555079D03*
Y1557579D03*
X1685995Y1561516D03*
X1680589Y1559626D03*
Y1563526D03*
X1682494Y1568271D03*
Y1575125D03*
X1680491Y1578089D03*
Y1571235D03*
X1689880Y1572067D03*
X1690353Y1591494D03*
X1680695Y1656307D03*
X1686675Y1659287D03*
X1688243Y1663802D03*
X1692415Y1663740D03*
X1685500Y1663599D03*
X1680367Y1663367D03*
X1686857Y1683918D03*
X1679420Y1683597D03*
X1684733Y1698952D03*
X1695102Y1698947D03*
X1691357Y1688418D03*
X1691952Y1698947D03*
X1689184Y1702095D03*
X1683013Y1713684D03*
X1691997Y1708609D03*
X1683029D03*
X1682724Y1717701D03*
X1680519Y1726825D03*
X1689383Y1729187D03*
X1680877Y1723593D03*
X1692218Y1717539D03*
X1685383Y1729559D03*
X1704965Y3001D03*
X1697242Y17045D03*
X1707186Y15708D03*
X1699250Y19541D03*
X1697242Y22037D03*
X1698290Y28406D03*
X1705376D03*
X1696472Y19541D03*
X1693072D03*
X1703583Y26505D03*
X1700183D03*
X1698300Y37106D03*
X1705381Y37108D03*
X1698290Y40020D03*
X1698300Y48720D03*
X1705386D03*
X1703536Y50649D03*
X1700136D03*
X1701114Y72847D03*
X1706094D03*
X1697000Y69343D03*
X1699204Y75340D03*
X1695094Y66850D03*
Y71842D03*
X1701904Y75340D03*
X1705304D03*
X1694300Y69343D03*
X1706094Y77839D03*
X1701114D03*
X1695100Y126762D03*
Y141762D03*
Y151762D03*
X1705120Y143610D03*
X1693000Y234000D03*
X1698220Y369652D03*
X1699809Y403985D03*
X1695579D03*
X1702959Y404243D03*
X1697161Y406602D03*
X1704444Y407045D03*
X1707444D03*
X1706500Y415862D03*
Y413362D03*
X1707780Y410738D03*
X1695455Y422287D03*
X1707568Y420370D03*
X1697914Y427155D03*
X1698014Y424055D03*
X1701124Y433650D03*
X1697214Y433655D03*
X1704624Y433650D03*
X1701124Y423802D03*
X1707544Y431745D03*
X1704974Y553115D03*
X1700974D03*
X1696974D03*
X1693490Y620672D03*
X1701121Y641658D03*
X1706101D03*
X1697530Y636369D03*
X1701661Y644554D03*
X1705561D03*
X1699500Y654738D03*
Y673738D03*
X1694490Y767265D03*
Y771065D03*
X1708049Y766870D03*
X1699087Y1298435D03*
Y1303635D03*
Y1306235D03*
Y1301035D03*
X1699072Y1313737D03*
X1696047Y1326576D03*
X1705383D03*
X1693417Y1329266D03*
X1693217Y1326566D03*
X1699072Y1322737D03*
Y1319737D03*
Y1316737D03*
X1693417Y1334266D03*
Y1331766D03*
X1705383Y1334676D03*
X1696047D03*
X1705383Y1329676D03*
X1696047Y1332176D03*
Y1329676D03*
X1705383Y1332176D03*
X1693417Y1336766D03*
Y1339266D03*
X1695533Y1351320D03*
Y1348420D03*
X1699701Y1402685D03*
X1700376Y1399528D03*
X1696888Y1397928D03*
X1699626Y1396960D03*
X1700272Y1460547D03*
X1702281Y1449801D03*
X1705108Y1451774D03*
X1695020Y1465621D03*
X1698440Y1466590D03*
X1705246Y1465325D03*
X1701348Y1466557D03*
X1695529Y1545193D03*
X1709964Y1597490D03*
X1709833Y1612940D03*
Y1606340D03*
X1701984Y1671618D03*
X1695987D03*
X1704822Y1694243D03*
X1702985Y1700328D03*
X1700156Y1698830D03*
X1702750Y1696185D03*
X1706086Y1691568D03*
X1700520Y1716877D03*
X1703000Y1711759D03*
X1702777Y1723593D03*
X1695166Y1717606D03*
X1697351Y1737117D03*
X1720148Y22910D03*
X1717148Y19910D03*
X1712977Y19986D03*
X1722148Y19910D03*
X1722085Y25908D03*
X1717055D03*
X1710106Y39768D03*
X1723241Y48822D03*
X1710106Y48978D03*
X1708004Y75340D03*
X1721646Y68115D03*
X1716558Y67866D03*
X1715861Y72593D03*
X1710886Y82208D03*
X1715550Y102923D03*
X1712486Y117908D03*
X1712686Y111908D03*
X1719909Y112713D03*
Y116713D03*
X1713399Y132858D03*
X1717384Y135373D03*
X1716609Y141297D03*
X1721628Y147312D03*
X1714293Y156278D03*
X1711293D03*
X1716893D03*
X1719493D03*
X1722093D03*
X1711293Y158878D03*
X1714293D03*
X1711293Y161478D03*
X1714293D03*
X1711293Y163978D03*
X1714293D03*
X1711293Y166478D03*
X1714293D03*
X1722093Y158878D03*
X1719493D03*
X1716893D03*
X1722093Y161478D03*
Y163978D03*
Y166478D03*
X1719493Y161478D03*
X1716893D03*
X1719493Y163978D03*
X1716893D03*
Y166478D03*
X1719493D03*
X1721400Y374462D03*
X1719200Y371162D03*
X1717220Y381152D03*
X1713720D03*
X1717220Y384652D03*
Y388152D03*
X1713720D03*
Y384652D03*
X1717220Y391652D03*
X1713720D03*
X1709000Y415862D03*
Y413362D03*
X1711144Y425945D03*
X1709339Y637251D03*
X1718465Y657982D03*
X1718241Y652105D03*
X1720050Y649142D03*
X1716030Y668182D03*
X1709759Y670221D03*
X1708305Y679720D03*
X1718686Y676154D03*
X1721754Y1299488D03*
X1708754Y1298388D03*
X1721847Y1307298D03*
X1721754Y1304688D03*
X1708754Y1300988D03*
X1721754Y1302088D03*
X1708754Y1303588D03*
Y1306188D03*
X1722672Y1313237D03*
X1708672Y1313737D03*
X1707916Y1329319D03*
X1722672Y1316237D03*
X1708672Y1322737D03*
Y1319737D03*
X1710536Y1329119D03*
X1708016Y1326619D03*
X1710536D03*
X1722672Y1319237D03*
Y1322237D03*
X1719916Y1326559D03*
X1717396D03*
X1719916Y1329059D03*
X1717396D03*
X1708672Y1316737D03*
X1707916Y1334319D03*
Y1331819D03*
Y1339319D03*
Y1336819D03*
X1710536Y1336619D03*
Y1339119D03*
X1719916Y1339059D03*
X1717396D03*
X1719916Y1336559D03*
X1717396D03*
X1710536Y1334119D03*
Y1331619D03*
X1719916Y1331559D03*
Y1334059D03*
X1717396D03*
Y1331559D03*
X1710176Y1342089D03*
X1718706Y1341629D03*
Y1344129D03*
X1718813Y1348450D03*
Y1351350D03*
X1709533Y1351520D03*
Y1348620D03*
X1710176Y1344589D03*
X1711962Y1367069D03*
X1714562D03*
X1711962Y1369669D03*
X1714562D03*
X1719902Y1368509D03*
Y1365909D03*
Y1363409D03*
X1716267Y1375178D03*
X1713312Y1374769D03*
X1708713Y1384435D03*
Y1387335D03*
X1715282Y1396375D03*
X1713082Y1391975D03*
X1715282Y1390575D03*
X1711016Y1393705D03*
Y1396605D03*
X1713182Y1394975D03*
X1715282Y1393475D03*
X1717447Y1417213D03*
X1714447D03*
X1717447Y1423213D03*
Y1420213D03*
X1714447D03*
Y1423213D03*
X1720210Y1435330D03*
X1722334Y1468146D03*
X1718425Y1468245D03*
X1722347Y1471246D03*
X1716070Y1472037D03*
X1719893Y1594940D03*
X1712870Y1586615D03*
X1715693Y1597190D03*
X1719893Y1612940D03*
Y1599740D03*
Y1603040D03*
Y1606340D03*
Y1609640D03*
X1713593D03*
Y1603040D03*
X1720845Y1668498D03*
X1722149Y1715265D03*
X1719149Y1703190D03*
X1719181Y1706712D03*
X1721172Y1712115D03*
X1710360Y1706502D03*
X1721912Y1705115D03*
X1722133Y1725340D03*
X1722149Y1730415D03*
X1719218Y1727265D03*
X1719148Y1721530D03*
X1722149Y1720265D03*
X1710230Y1729654D03*
X1719351Y1737117D03*
X1735375Y-40925D03*
X1727111Y-38849D03*
Y-28849D03*
X1732350Y-39605D03*
X1735390Y-38410D03*
X1735374Y-27916D03*
X1732349Y-29236D03*
X1735389Y-30431D03*
X1729557Y-22512D03*
Y-25912D03*
X1727111Y-19575D03*
X1735390Y-20014D03*
X1735375Y-17499D03*
X1732350Y-18819D03*
X1726965Y3001D03*
X1732286Y28208D03*
X1728786D03*
X1725286D03*
X1736006Y41838D03*
Y44338D03*
X1727336Y57024D03*
X1726596Y61784D03*
X1729836Y57024D03*
Y54524D03*
X1727336D03*
X1724685Y51454D03*
X1727225Y51424D03*
X1729895Y51354D03*
X1726741Y48822D03*
X1730241D03*
X1726596Y64284D03*
X1737617Y75640D03*
Y73140D03*
Y79140D03*
Y81640D03*
X1726814Y102968D03*
X1722984Y101713D03*
X1723184Y93313D03*
X1736731Y102293D03*
X1728965Y112941D03*
X1729046Y118178D03*
X1739686Y120938D03*
X1733344Y134953D03*
X1736474D03*
X1725093Y156278D03*
Y158878D03*
Y161478D03*
Y163978D03*
Y166478D03*
X1730364Y177588D03*
X1735471Y293682D03*
Y290682D03*
Y296682D03*
Y299682D03*
X1730331Y293722D03*
Y296722D03*
X1732831D03*
X1730331Y299722D03*
X1732831D03*
Y293722D03*
X1723492Y293068D03*
X1732751Y305732D03*
X1730251D03*
X1732751Y302732D03*
X1730251D03*
X1735391Y305692D03*
Y302692D03*
X1725344Y359334D03*
X1725400Y372062D03*
X1737260Y368132D03*
X1732660Y372692D03*
X1725500Y383662D03*
X1728300Y377787D03*
X1723259Y653641D03*
X1733083Y654034D03*
X1733043Y657091D03*
X1736848Y650974D03*
X1726409Y653641D03*
X1726334Y670345D03*
X1737002Y671494D03*
X1724191Y767299D03*
Y771099D03*
X1737850Y766794D03*
X1732624Y1299718D03*
X1732717Y1307528D03*
X1732624Y1302318D03*
Y1304918D03*
X1732702Y1313007D03*
Y1316007D03*
Y1322007D03*
Y1319007D03*
X1735202Y1368279D03*
Y1365679D03*
Y1363179D03*
X1723917Y1380518D03*
Y1377178D03*
X1737126Y1403838D03*
Y1401238D03*
X1732766Y1410562D03*
Y1413062D03*
X1735266Y1410562D03*
Y1413062D03*
X1732766Y1426362D03*
Y1428862D03*
X1735266Y1426362D03*
Y1428862D03*
X1722810Y1435330D03*
X1737606Y1539807D03*
X1737541Y1543707D03*
X1730004Y1540968D03*
X1726604Y1540970D03*
X1734575Y1562068D03*
X1735379Y1566282D03*
X1735354Y1580480D03*
X1735351Y1569832D03*
X1736479Y1584330D03*
X1736579Y1587480D03*
X1730202Y1602093D03*
X1723929Y1654456D03*
X1735463Y1651965D03*
X1730381Y1647386D03*
X1726381D03*
X1734500Y1656965D03*
X1723963Y1658965D03*
Y1663465D03*
Y1667965D03*
X1734962Y1662965D03*
X1734963Y1673465D03*
X1724263Y1681465D03*
X1724323Y1676965D03*
X1724263Y1672465D03*
X1734763Y1680465D03*
X1735463Y1694465D03*
X1725423Y1692656D03*
X1731936Y1690165D03*
X1731117Y1705115D03*
Y1715265D03*
X1732251Y1708265D03*
X1731117Y1720265D03*
Y1730415D03*
X1738628Y-40911D03*
X1738658Y-35881D03*
X1738673Y-33366D03*
X1738643Y-38396D03*
X1738627Y-27930D03*
X1738642Y-30445D03*
X1738643Y-20028D03*
X1738628Y-17513D03*
X1738673Y-25058D03*
X1738658Y-22543D03*
X1748965Y3001D03*
X1748708Y26641D03*
X1752008Y25146D03*
X1748116Y37058D03*
X1751031Y39063D03*
X1738093Y53103D03*
Y55603D03*
X1741621Y76613D03*
Y74113D03*
Y82613D03*
Y80113D03*
X1743491Y92827D03*
X1738435Y100244D03*
X1741935D03*
X1745435D03*
X1740231Y102293D03*
X1743731D03*
X1748686Y97408D03*
X1740091Y92827D03*
X1745451Y119585D03*
X1747448Y121413D03*
X1750786Y120018D03*
X1744976Y122998D03*
X1754339Y128242D03*
X1750325Y179827D03*
X1750851Y216427D03*
X1748325D03*
X1752461Y255337D03*
X1749571Y255317D03*
X1752461Y252337D03*
X1749571Y252317D03*
X1752022Y269794D03*
Y266794D03*
X1742971Y293682D03*
Y290682D03*
X1737971D03*
X1740471Y293682D03*
Y290682D03*
Y299682D03*
X1737971D03*
X1740471Y296682D03*
X1737971D03*
Y293682D03*
X1751352Y293386D03*
X1745671Y290682D03*
Y293682D03*
X1752250Y303850D03*
X1737891Y302692D03*
X1740391D03*
X1737891Y305692D03*
X1740391D03*
X1744510Y377452D03*
X1744380Y382892D03*
X1742398Y484304D03*
X1742652Y671494D03*
X1745502Y660088D03*
X1742306Y661032D03*
X1745484Y668216D03*
X1751490Y713890D03*
X1748990D03*
X1746490D03*
X1743990D03*
X1751490Y706390D03*
X1748990D03*
X1746490D03*
X1743990D03*
X1751490Y708890D03*
X1748990D03*
X1746490D03*
X1743990D03*
X1751490Y711390D03*
X1748990D03*
X1746490D03*
X1743990D03*
X1742766Y1418462D03*
Y1415962D03*
X1737766Y1410562D03*
Y1413062D03*
X1740266Y1410562D03*
Y1413062D03*
X1742766D03*
Y1410562D03*
X1740266Y1415962D03*
Y1418462D03*
X1743072Y1432211D03*
X1737766Y1426362D03*
Y1428862D03*
X1742766Y1423462D03*
X1740266Y1426362D03*
Y1423462D03*
Y1420962D03*
X1742766D03*
X1741329Y1482405D03*
Y1485405D03*
Y1491405D03*
Y1488405D03*
Y1506405D03*
Y1503405D03*
Y1509405D03*
Y1512405D03*
X1745543Y1518678D03*
X1742758Y1521239D03*
X1745746D03*
X1751120Y1521223D03*
X1751087Y1518704D03*
X1748346Y1521223D03*
X1748313Y1518704D03*
X1740058Y1537419D03*
X1739565Y1528105D03*
X1751132Y1526748D03*
Y1524248D03*
Y1529248D03*
X1742810Y1524534D03*
X1745410D03*
X1748358Y1526748D03*
Y1524248D03*
Y1529248D03*
X1744866Y1539589D03*
X1742165Y1539620D03*
X1743188Y1543871D03*
Y1547871D03*
X1740587Y1547946D03*
X1737738Y1548021D03*
X1740400Y1543682D03*
X1740079Y1559505D03*
X1740188Y1556371D03*
X1740979Y1577905D03*
X1746779Y1583378D03*
X1751558Y1579332D03*
X1746079Y1587705D03*
X1743681Y1626750D03*
X1750681D03*
X1747181D03*
X1743481Y1616550D03*
X1750481D03*
X1746981D03*
X1747963Y1641965D03*
X1750463Y1654465D03*
X1744963Y1656465D03*
X1744463Y1651229D03*
X1749329Y1662956D03*
X1743329Y1668956D03*
X1743153Y1662956D03*
X1749329Y1674956D03*
X1743329D03*
X1747986Y1686215D03*
X1751340Y1686140D03*
X1739640Y1713383D03*
X1742120Y1708265D03*
X1744620Y1716018D03*
X1750380Y1707468D03*
X1747120Y1710824D03*
X1739640Y1728533D03*
X1742120Y1723415D03*
X1749480Y1718158D03*
X1741351Y1737117D03*
X1762420Y17031D03*
X1765920D03*
X1753388Y28406D03*
X1760475D03*
X1765980Y27031D03*
X1765920Y22031D03*
X1758638Y26477D03*
X1755238D03*
X1763840Y37790D03*
X1767266Y48748D03*
X1753398Y48720D03*
X1760485D03*
X1759666Y57708D03*
X1764366Y57508D03*
X1763010Y51223D03*
X1765527Y53692D03*
X1758635Y50649D03*
X1755235D03*
X1758047Y68637D03*
X1757923Y72637D03*
X1767956Y76843D03*
X1758539Y87153D03*
Y83653D03*
X1758534Y79743D03*
X1765034Y80443D03*
X1767136Y83653D03*
X1761417Y90017D03*
X1754364Y100353D03*
X1766244Y93673D03*
X1760444Y106173D03*
X1763644D03*
X1764644Y122973D03*
X1755944Y111073D03*
Y108473D03*
X1760944Y116773D03*
X1757944D03*
X1760124Y128246D03*
X1766911Y179890D03*
X1752851Y179827D03*
X1757385Y179890D03*
X1764385D03*
X1759911D03*
X1755504Y202263D03*
X1758030D03*
X1762564Y202326D03*
X1765090D03*
X1757951Y216427D03*
X1755425D03*
X1762485Y216490D03*
X1765011D03*
X1758859Y251544D03*
X1755969Y251524D03*
X1758859Y248544D03*
X1755969Y248524D03*
X1766399Y251361D03*
X1763509Y251341D03*
X1766399Y248361D03*
X1763509Y248341D03*
X1761573Y266657D03*
X1764573D03*
X1761573Y269657D03*
X1764573D03*
X1758022Y269794D03*
Y266794D03*
X1755022Y269794D03*
Y266794D03*
X1755772Y278859D03*
X1758772D03*
X1761772D03*
X1755772Y281859D03*
X1758772D03*
X1761772D03*
X1752772Y278859D03*
Y281859D03*
X1754850Y303930D03*
X1756800Y364048D03*
Y368048D03*
X1756933Y372452D03*
X1759379Y507927D03*
X1753566Y512968D03*
X1768041Y556537D03*
X1753990Y711390D03*
Y708890D03*
Y706390D03*
Y713890D03*
X1753891Y767305D03*
Y771105D03*
X1767450Y766870D03*
X1759949Y1297324D03*
X1764267Y1460080D03*
X1764029Y1485405D03*
Y1482405D03*
Y1491405D03*
Y1488405D03*
X1756329Y1485405D03*
Y1482405D03*
Y1491405D03*
Y1488405D03*
Y1506405D03*
Y1503405D03*
X1764029Y1506405D03*
Y1503405D03*
X1756329Y1509405D03*
Y1512405D03*
X1764029Y1509405D03*
Y1512405D03*
X1765286Y1518471D03*
X1765176Y1515902D03*
X1765286Y1521095D03*
X1765246Y1524001D03*
Y1526601D03*
X1765334Y1529342D03*
X1765709Y1556050D03*
X1764679Y1572105D03*
X1765679Y1575405D03*
X1762679D03*
X1766079Y1578705D03*
X1763079D03*
X1769054Y1585705D03*
X1754479Y1585905D03*
X1753079Y1596650D03*
X1753512Y1583478D03*
X1753079Y1606550D03*
Y1603050D03*
Y1600150D03*
X1763706Y1616451D03*
X1760206D03*
X1767206D03*
X1761839Y1634223D03*
X1754763Y1641665D03*
X1757763Y1643365D03*
X1765854Y1646456D03*
X1755463Y1654465D03*
X1755329Y1668956D03*
Y1662956D03*
X1761494Y1661947D03*
X1767888Y1664465D03*
X1762263Y1671765D03*
X1765163Y1670543D03*
X1755329Y1674956D03*
X1765463Y1677465D03*
X1761463Y1683465D03*
X1763463Y1691465D03*
X1758963Y1691565D03*
X1752864Y1716383D03*
X1763351Y1737117D03*
X1770965Y3001D03*
X1775920Y17031D03*
X1770920D03*
X1769420Y19506D03*
X1777420D03*
Y24506D03*
X1775920Y27068D03*
X1770920Y22031D03*
X1775920D03*
X1772886Y37430D03*
X1768956Y37558D03*
X1777720Y37792D03*
X1773830Y49000D03*
X1779377Y50738D03*
X1774294Y60133D03*
X1774291Y57191D03*
X1769240Y50788D03*
X1769200Y54300D03*
X1780300Y54400D03*
X1775546Y73376D03*
X1774294Y63033D03*
X1779744Y72973D03*
Y70073D03*
X1770334Y72737D03*
X1768134Y80543D03*
X1778205Y90982D03*
X1781451Y88238D03*
X1773577Y88339D03*
X1778544Y97973D03*
X1769244Y113773D03*
Y110973D03*
Y108073D03*
X1771881Y128439D03*
Y125939D03*
Y123439D03*
X1781966Y128501D03*
Y126001D03*
Y123501D03*
X1781368Y162824D03*
X1771385Y179890D03*
X1773911D03*
X1780929Y179408D03*
X1776930Y179051D03*
X1778500Y183790D03*
X1773581Y194120D03*
X1771055D03*
X1771931Y200920D03*
X1769405D03*
X1777170Y201002D03*
X1774644D03*
X1769585Y215090D03*
X1772111D03*
X1776585D03*
X1779111D03*
X1778874Y253799D03*
X1775984Y253779D03*
X1778874Y256799D03*
X1775984Y256779D03*
X1778796Y261633D03*
X1767573Y266657D03*
X1775633Y261666D03*
X1767573Y269657D03*
X1778796Y266633D03*
Y269133D03*
Y264133D03*
X1775633Y269166D03*
Y266666D03*
Y264166D03*
X1778796Y271633D03*
X1775633Y271666D03*
X1770520Y364148D03*
Y368148D03*
X1770280Y372452D03*
X1770220Y382952D03*
Y377452D03*
X1782324Y403932D03*
Y410432D03*
Y418932D03*
Y425432D03*
X1771236Y557224D03*
X1779376Y558324D03*
X1782376D03*
X1773963Y557537D03*
X1776986Y749023D03*
X1776550Y763765D03*
X1769650Y1280200D03*
X1771000Y1278060D03*
X1782369Y1447581D03*
X1782385Y1450095D03*
X1782337Y1453191D03*
X1775682Y1466568D03*
X1779029Y1482405D03*
Y1485405D03*
Y1491405D03*
Y1488405D03*
Y1506405D03*
Y1503405D03*
Y1509405D03*
Y1512405D03*
X1780012Y1518631D03*
Y1516031D03*
Y1521231D03*
X1777152Y1518631D03*
Y1516031D03*
Y1521231D03*
X1774552D03*
Y1516031D03*
Y1518631D03*
X1768176Y1515902D03*
X1768286Y1518471D03*
Y1521095D03*
X1770886D03*
Y1518471D03*
X1770776Y1515902D03*
X1780039Y1523860D03*
Y1526360D03*
X1779997Y1528888D03*
X1777179Y1526360D03*
Y1523860D03*
X1774579D03*
Y1526360D03*
X1768246Y1526601D03*
Y1524001D03*
X1768334Y1529342D03*
X1770846Y1524001D03*
Y1526601D03*
X1776188Y1543871D03*
Y1546871D03*
X1769188D03*
Y1543871D03*
X1768688Y1552871D03*
Y1549871D03*
X1772688Y1543871D03*
Y1546871D03*
X1776113Y1541172D03*
X1769113D03*
X1772613D03*
X1775979Y1556805D03*
Y1559805D03*
X1768209Y1556000D03*
X1769826Y1562559D03*
X1771079Y1566782D03*
X1770404Y1575330D03*
X1780579Y1582178D03*
X1771094Y1570332D03*
X1772904Y1585005D03*
X1778794Y1585332D03*
X1768105Y1595925D03*
X1775794Y1585332D03*
X1768030Y1599249D03*
X1768180Y1606549D03*
X1768030Y1603149D03*
X1780154Y1615026D03*
X1777454D03*
X1780154Y1617726D03*
X1777454D03*
X1773349Y1631938D03*
Y1634438D03*
Y1636938D03*
X1770649Y1631938D03*
Y1634438D03*
X1781423Y1634394D03*
Y1636894D03*
X1778723Y1634294D03*
X1776023D03*
Y1636894D03*
X1778723D03*
X1773929Y1657465D03*
Y1654956D03*
X1768929Y1651956D03*
X1773863Y1661465D03*
X1774940Y1669037D03*
X1773738Y1672965D03*
X1773963Y1680965D03*
X1774338Y1676865D03*
X1771038Y1692956D03*
X1792965Y3001D03*
X1793070Y25001D03*
X1796781Y46686D03*
X1787826Y37548D03*
X1783700Y50011D03*
X1785072Y53161D03*
X1794099Y50461D03*
X1788204Y74958D03*
X1785108Y76078D03*
X1785144Y86973D03*
Y89973D03*
X1787756Y85178D03*
X1788204Y82338D03*
Y78108D03*
X1784144Y113973D03*
Y111173D03*
Y108273D03*
X1784006Y137395D03*
X1788950Y142750D03*
X1787390Y161834D03*
Y165834D03*
Y156834D03*
Y151834D03*
X1789811Y178083D03*
X1793444D03*
X1794629Y193323D03*
X1791645Y193397D03*
X1795219Y185910D03*
X1785320Y193072D03*
X1784915Y186053D03*
X1795949Y205580D03*
X1795909Y209128D03*
X1795365Y197567D03*
X1796019Y202030D03*
X1791445Y197497D03*
X1783448Y212957D03*
X1795794Y253719D03*
X1787534Y253769D03*
X1795794Y256719D03*
X1787534Y256769D03*
X1783896Y266633D03*
Y269133D03*
X1794174Y274499D03*
X1790674D03*
X1783896Y271633D03*
X1789771Y367866D03*
X1797929Y385293D03*
X1786260Y379059D03*
X1792507Y403932D03*
X1795479Y408056D03*
X1792335Y418775D03*
X1792450Y410615D03*
X1795468Y421334D03*
X1792220Y425432D03*
X1785376Y558324D03*
X1788376D03*
X1792895Y683536D03*
X1783592Y767565D03*
Y771365D03*
X1792692Y766870D03*
X1794362Y1275546D03*
X1785336Y1447565D03*
Y1450065D03*
X1785634Y1456326D03*
X1782530Y1456229D03*
X1785408Y1453385D03*
X1788029Y1485405D03*
Y1482405D03*
Y1491405D03*
Y1488405D03*
Y1506405D03*
Y1503405D03*
Y1509405D03*
Y1512405D03*
X1794265Y1518262D03*
Y1520862D03*
Y1523462D03*
Y1526062D03*
X1794268Y1528720D03*
X1784601Y1578967D03*
X1787239Y1579406D03*
X1788679Y1585805D03*
X1789379Y1588478D03*
X1789294Y1583278D03*
X1797118Y1596588D03*
X1797143Y1607014D03*
X1797076Y1603662D03*
X1797043Y1599811D03*
X1791979Y1616550D03*
X1795479D03*
X1782654Y1615026D03*
Y1617726D03*
X1784048Y1636875D03*
Y1634375D03*
X1786615Y1631800D03*
X1786588Y1634472D03*
X1786624Y1637021D03*
X1807515Y56461D03*
X1807546Y59443D03*
X1805525Y146716D03*
X1800040Y164393D03*
X1802565Y156557D03*
X1804111Y178083D03*
X1807711D03*
Y175083D03*
X1800554Y177229D03*
X1808622Y170869D03*
X1803165Y196127D03*
X1797621Y193373D03*
X1800389Y193424D03*
X1803045Y193397D03*
X1797719Y186610D03*
X1806470Y186866D03*
X1802570Y186913D03*
X1811274Y198098D03*
X1798943Y204744D03*
Y209044D03*
X1802276Y209013D03*
X1805235Y208950D03*
X1802276Y204713D03*
X1800125Y201857D03*
X1805235Y204650D03*
X1799629Y198870D03*
X1803145Y198697D03*
X1811668Y218900D03*
X1811606Y222513D03*
X1808429Y218837D03*
X1811606Y226438D03*
X1808367Y222450D03*
X1810479Y211850D03*
X1810509Y214660D03*
X1808260Y213232D03*
X1808367Y226375D03*
X1807296Y255033D03*
X1804174Y253739D03*
Y256739D03*
X1807596Y264133D03*
Y266633D03*
Y269133D03*
X1797674Y274499D03*
X1801174D03*
X1807596Y271633D03*
X1803129Y362293D03*
X1800160Y362542D03*
X1802929Y385293D03*
X1808962Y698055D03*
Y700555D03*
Y703055D03*
X1798462Y698055D03*
X1801962D03*
X1805462D03*
Y700555D03*
X1801962D03*
X1798462D03*
X1805462Y703055D03*
X1801962D03*
X1798462D03*
X1808962Y705555D03*
Y708055D03*
X1798462Y705555D03*
X1801962D03*
X1805462D03*
X1798462Y708055D03*
X1801962D03*
X1805462D03*
X1809002Y710945D03*
Y713445D03*
Y715945D03*
X1805502Y710945D03*
Y713445D03*
Y715945D03*
X1802050Y710940D03*
X1811526Y1281671D03*
X1812029Y1485405D03*
Y1482405D03*
X1803029D03*
Y1485405D03*
X1812029Y1491405D03*
Y1488405D03*
X1803029Y1491405D03*
Y1488405D03*
Y1506405D03*
Y1503405D03*
X1812029Y1506405D03*
Y1503405D03*
X1803029Y1509405D03*
Y1512405D03*
X1812029Y1509405D03*
Y1512405D03*
X1797362Y1518304D03*
X1799882Y1520912D03*
Y1518312D03*
X1797362Y1520904D03*
X1801789Y1536742D03*
X1804049Y1528031D03*
X1799882Y1523512D03*
X1797362Y1523504D03*
X1799882Y1526112D03*
X1797362Y1526104D03*
X1799994Y1528674D03*
X1797450Y1528768D03*
X1809890Y1524532D03*
X1807290D03*
X1804688Y1545871D03*
Y1542371D03*
Y1552871D03*
Y1549371D03*
X1801688Y1545871D03*
Y1552871D03*
Y1549371D03*
X1807408Y1539223D03*
X1810408D03*
X1804688Y1555871D03*
X1801688D03*
X1804688Y1559371D03*
X1798479Y1575605D03*
X1798879Y1578905D03*
X1801479Y1575605D03*
X1800479Y1572305D03*
X1801879Y1578905D03*
X1812078Y1596725D03*
X1812003Y1607375D03*
Y1603875D03*
X1812078Y1600225D03*
X1809179Y1616550D03*
X1809254Y1613775D03*
X1798979Y1616550D03*
X1818615Y49379D03*
X1818155Y149325D03*
X1815005D03*
X1812570Y159275D03*
X1825111Y164393D03*
X1817196Y163797D03*
Y159947D03*
X1818828Y175241D03*
X1817275Y180619D03*
X1817674Y188699D03*
X1813224Y194699D03*
X1816190Y208879D03*
X1813079Y211850D03*
X1813109Y214660D03*
X1819529Y320321D03*
X1820307Y373829D03*
X1817157D03*
X1828669Y379552D03*
X1820656Y388051D03*
X1820144Y398052D03*
X1816994D03*
X1819374Y410432D03*
X1816224D03*
X1818874Y423932D03*
X1822724Y424948D03*
X1815724Y423932D03*
X1825874Y424948D03*
X1822394Y436225D03*
X1827073Y565157D03*
X1824073D03*
X1821073D03*
X1812462Y698055D03*
Y700555D03*
Y703055D03*
Y705555D03*
Y708055D03*
X1812502Y710945D03*
Y713445D03*
Y715945D03*
X1827029Y1488405D03*
Y1491405D03*
Y1485405D03*
Y1482405D03*
Y1506405D03*
Y1503405D03*
Y1509405D03*
Y1512405D03*
X1818475Y1524682D03*
X1815875D03*
X1823649Y1525144D03*
X1815344Y1539373D03*
X1818344D03*
X1823112Y1538659D03*
X1812679Y1616550D03*
X1816179D03*
X1812754Y1613775D03*
X1816254D03*
X1840615Y49379D03*
X1831166Y149986D03*
X1837641Y159275D03*
X1827580Y151834D03*
X1840700Y326201D03*
Y348201D03*
Y370201D03*
X1829732Y367359D03*
Y371329D03*
X1840700Y392201D03*
Y414201D03*
X1828483Y431678D03*
X1840700Y436201D03*
Y458201D03*
Y480201D03*
Y502201D03*
Y524201D03*
Y546201D03*
Y568201D03*
Y590201D03*
Y656201D03*
Y678201D03*
Y700201D03*
Y722201D03*
Y744201D03*
Y766201D03*
Y788201D03*
Y810201D03*
Y832201D03*
Y854201D03*
Y876201D03*
Y898201D03*
Y920201D03*
Y942201D03*
Y964201D03*
Y986201D03*
Y1008201D03*
Y1030201D03*
Y1052201D03*
Y1074201D03*
Y1096201D03*
Y1118201D03*
Y1140201D03*
Y1162201D03*
Y1184201D03*
Y1206201D03*
Y1228201D03*
Y1250201D03*
Y1272201D03*
Y1294201D03*
Y1316201D03*
Y1338201D03*
Y1404201D03*
Y1448201D03*
Y1470201D03*
X1833288Y1469639D03*
X1840700Y1492201D03*
Y1514201D03*
Y1536201D03*
Y1558201D03*
Y1580201D03*
X1835198Y1601502D03*
X1828889Y1622578D03*
Y1644578D03*
Y1666578D03*
Y1688578D03*
X1854479Y66461D03*
Y110461D03*
Y132461D03*
Y154461D03*
X1847866Y159124D03*
X1854479Y176461D03*
X1850791Y170287D03*
X1854479Y198461D03*
Y220461D03*
Y242461D03*
Y264461D03*
Y286461D03*
X1853692Y308447D03*
G54D311*
X1653051Y414202D03*
G54D140*
X274913Y1019214D03*
X320189Y838505D03*
Y1199923D03*
X561133Y838505D03*
Y1199923D03*
X606409Y1019214D03*
X841240Y1420331D03*
X1016240D03*
X1251055Y1019213D03*
X1296331Y838504D03*
Y1199922D03*
X1537275Y838504D03*
Y1199922D03*
X1582551Y1019213D03*
G54D212*
X584276Y486000D03*
X593724D03*
X798724Y366000D03*
X789276D03*
X811224Y399500D03*
X801776D03*
X810224Y409500D03*
X800776D03*
G54D302*
X1319667Y83687D03*
Y101327D03*
X1323604Y74869D03*
X1327541Y83687D03*
X1323604Y92509D03*
X1327541Y101327D03*
X1373745Y74869D03*
X1369808Y83687D03*
X1377682D03*
G54D113*
X178582Y1572490D03*
X184382D03*
X172782D03*
X178582D03*
X251487Y92733D03*
X257287D03*
Y97633D03*
X251487D03*
X329886Y598794D03*
X324086D03*
X424100Y1644500D03*
X436100Y1627500D03*
X429900Y1644500D03*
X441900Y1627500D03*
X684643Y96858D03*
X690443D03*
Y101758D03*
X684643D03*
X797536Y1364193D03*
X803336D03*
X1120110Y1580298D03*
X1125910D03*
X1180655Y1605490D03*
X1190107Y182851D03*
X1195907D03*
X1186455Y1605490D03*
D03*
X1192255D03*
X1295078Y157495D03*
X1300878D03*
X1307700Y518723D03*
X1313500D03*
X1614959Y525962D03*
X1620759D03*
X1726608Y94527D03*
X1732408D03*
Y99727D03*
X1726608D03*
G54D20*
X14092Y290137D03*
Y298207D03*
X28068Y290137D03*
Y298207D03*
X44692Y290137D03*
Y298207D03*
X58668Y290137D03*
Y298207D03*
X1632822Y221842D03*
Y229912D03*
X1646798Y221842D03*
Y229912D03*
G54D104*
X155260Y1715941D03*
Y1718500D03*
Y1721059D03*
X162740Y1715941D03*
Y1718500D03*
Y1721059D03*
X181760Y1715441D03*
Y1718000D03*
Y1720559D03*
X189240Y1715441D03*
X198760Y1715000D03*
Y1712441D03*
X189240Y1718000D03*
Y1720559D03*
X198760Y1717559D03*
X206240Y1715000D03*
Y1712441D03*
Y1717559D03*
G54D221*
X663382Y516260D03*
Y523740D03*
X673618Y520000D03*
G54D320*
X1787993Y194161D03*
Y196130D03*
Y198098D03*
X1806497Y194161D03*
Y200067D03*
Y198098D03*
Y196130D03*
Y202035D03*
G54D230*
X721113Y651187D03*
Y646147D03*
X719145Y651187D03*
Y646147D03*
X1146221Y1558549D03*
Y1553509D03*
X1144253Y1558549D03*
Y1553509D03*
X1471975Y1676881D03*
Y1681921D03*
X1473943Y1676881D03*
Y1681921D03*
G54D131*
X274301Y115216D03*
X707457Y119341D03*
X1749422Y116340D03*
G54D122*
X230905Y1734212D03*
X297835D03*
X495078D03*
X562008D03*
X1238778D03*
X1305708D03*
X1502952D03*
X1569882D03*
G54D11*
X8879Y180928D03*
X8013Y219222D03*
X6109Y1673058D03*
X18691Y180321D03*
X14517Y223688D03*
X34180Y293407D03*
X38944Y303000D03*
X39600Y378562D03*
X38800Y406562D03*
X39163Y519914D03*
X40373Y762118D03*
Y768332D03*
X55301Y53544D03*
X44700Y375262D03*
X50200D03*
X53500Y371362D03*
X40800Y400962D03*
X43814Y408139D03*
X47902Y512585D03*
X53658Y512639D03*
X41010Y534105D03*
X49039Y542027D03*
X54399D03*
X42150Y1546791D03*
X45120Y1603396D03*
X45833Y1626496D03*
X50927Y1663587D03*
Y1668587D03*
X49069Y1678149D03*
X59406Y57055D03*
X64000Y306000D03*
X65710Y376042D03*
X63350Y371362D03*
X57342Y375262D03*
X58254Y514975D03*
X59849Y541987D03*
X66250Y1412899D03*
X68392Y1432013D03*
X59039Y1549644D03*
X66854Y1597165D03*
X61133Y1631796D03*
X56133Y1631696D03*
X62152Y1653448D03*
X68399Y1653382D03*
X56821Y1653527D03*
X64462Y1678404D03*
X56694Y1677916D03*
X70237Y1678363D03*
X80991Y151189D03*
X84009Y146557D03*
X80979Y156192D03*
X80965Y161194D03*
X84377Y166361D03*
X71136Y390398D03*
X76600Y386364D03*
X70500Y381562D03*
X71480Y399442D03*
X76200Y395865D03*
X78760Y1312186D03*
Y1307106D03*
X70460Y1600665D03*
X74233Y1614396D03*
Y1607847D03*
X73399Y1653408D03*
X79117Y1666864D03*
X82630Y1678315D03*
X76468Y1678409D03*
X89539Y-76554D03*
X89009Y146231D03*
X94010Y146250D03*
X98892Y147345D03*
X94291Y167275D03*
X89290Y167307D03*
X93193Y1377757D03*
X92988Y1560481D03*
X100939Y-76554D03*
X112339D03*
X100818Y165506D03*
X113500Y1398600D03*
X102376Y1409377D03*
X102548Y1415954D03*
X107202Y1558112D03*
X123739Y-76554D03*
X120016Y289822D03*
X115016D03*
X120016Y310256D03*
X115016D03*
X124700Y1401000D03*
X120700Y1408100D03*
X118658Y1455464D03*
X121500Y1467400D03*
X120353Y1655843D03*
X119927Y1669843D03*
Y1674843D03*
X123353Y1686843D03*
X135139Y-76554D03*
X136617Y521997D03*
Y526997D03*
X143649Y672383D03*
X143949Y677610D03*
X141514Y1436500D03*
X132353Y1655769D03*
X144253Y1655843D03*
X132427Y1686343D03*
X137427D03*
X157939Y-76554D03*
X146539D03*
X157923Y1520968D03*
X152339Y1655756D03*
X144985Y1671863D03*
X151353Y1686843D03*
X169339Y-76554D03*
X162112Y1450019D03*
X166180Y1514420D03*
X161162Y1514314D03*
X167900Y1540000D03*
Y1535000D03*
Y1530000D03*
X180739Y-76554D03*
X186421Y671555D03*
X184700Y677660D03*
X185124Y1701851D03*
X185084Y1691988D03*
X192139Y-76554D03*
X203539D03*
X195979Y106017D03*
X192845Y136262D03*
X195979Y125562D03*
X204088Y138912D03*
X197375Y152500D03*
X197575Y160432D03*
X198698Y1662215D03*
X214939Y-76554D03*
X208179Y106017D03*
X214900Y120502D03*
X218402Y148760D03*
X211862Y1701100D03*
X233335Y57341D03*
X233785Y208935D03*
X227157Y715915D03*
X245330Y56939D03*
X239734Y57435D03*
X237929Y107838D03*
X242196Y119305D03*
X243813Y132383D03*
X236916Y146832D03*
X237396Y163965D03*
X248625Y762182D03*
X243625D03*
X249909Y58971D03*
X253086Y87365D03*
X254936Y146882D03*
X254821Y151940D03*
X259496Y162665D03*
X256090Y206540D03*
X263271Y771988D03*
X259490Y1565110D03*
X258560Y1558660D03*
X274996Y153865D03*
X275049Y148706D03*
X276996Y143965D03*
X274996Y159206D03*
X278697Y165096D03*
X265075Y213077D03*
X264818Y227950D03*
X276704Y1526953D03*
X264617Y1561520D03*
X287196Y143965D03*
X292496Y144016D03*
X281996Y143965D03*
X284990Y168020D03*
X290840Y170080D03*
X283811Y215870D03*
X286546Y222118D03*
X287000Y243069D03*
X292740Y242691D03*
X286872Y1508981D03*
X289460Y1520200D03*
X289224Y1514314D03*
X281704Y1526953D03*
X297696Y144165D03*
X294224Y1514314D03*
X308222Y1561079D03*
X319641Y274000D03*
X314271Y593038D03*
X314771Y1555834D03*
X312715Y1575985D03*
X329221Y164920D03*
X333031Y255324D03*
X337750Y584750D03*
X339811Y131052D03*
X341895Y233980D03*
X342192Y270260D03*
X351157Y550415D03*
Y590415D03*
X365400Y146910D03*
X365836Y163265D03*
X365162Y243366D03*
X357391Y286874D03*
X357341Y281424D03*
X366000Y307500D03*
X365071Y551038D03*
X362200Y566750D03*
X364047Y556773D03*
X360261Y561044D03*
X379090Y157936D03*
X376091Y287874D03*
Y280274D03*
Y295474D03*
X382184Y476726D03*
Y496726D03*
X371962Y524954D03*
X380771Y542138D03*
X379689Y586040D03*
X368798Y587938D03*
X376197Y1576200D03*
X375513Y1587172D03*
X387894Y135157D03*
X397090Y151741D03*
X389000Y303760D03*
X394184Y476726D03*
X397184Y496726D03*
X392184D03*
X388985Y554870D03*
X395171Y559463D03*
X397101Y566188D03*
X395157Y573815D03*
X393604Y579473D03*
X387103Y584506D03*
X391175Y1565695D03*
X393261Y1560775D03*
X386822Y1556550D03*
X389128Y1576969D03*
X391604Y1587172D03*
X387324Y1670120D03*
X392324D03*
X397324D03*
X403881Y133980D03*
X406000Y139483D03*
X398599Y209695D03*
X407299Y201500D03*
X402184Y476844D03*
Y496726D03*
X406512Y534213D03*
X399657Y546915D03*
X409766Y1526953D03*
X404766D03*
X404775Y1535976D03*
Y1540976D03*
X407611Y1599022D03*
X401547Y1603022D03*
X407676Y1626475D03*
X412342Y1628467D03*
X406441Y1657000D03*
X427549Y60016D03*
X414400Y110770D03*
X413416Y153150D03*
X420527Y144234D03*
X427299Y199500D03*
X419299Y201000D03*
X422302Y214926D03*
X420000Y219940D03*
X423583Y245868D03*
X424220Y253768D03*
Y263768D03*
Y258768D03*
X415984Y476767D03*
Y496649D03*
X414934Y1508981D03*
X419934D03*
X425571Y1520200D03*
X424775Y1513907D03*
X422437Y1526983D03*
X425000Y1626900D03*
X413299Y1633417D03*
X417000Y1661000D03*
X440186Y93386D03*
X432200Y101800D03*
X428085Y98885D03*
X442221Y100933D03*
X436482Y98172D03*
X435383Y149854D03*
X441240Y149323D03*
X429200Y155890D03*
X435299Y201745D03*
X429784Y476690D03*
Y496572D03*
X435580Y1279986D03*
X430335Y1514314D03*
X431682Y1601671D03*
X433795Y1606554D03*
X436500Y1618700D03*
X428500Y1630500D03*
X434280Y1644807D03*
X446797Y148500D03*
X454997Y155750D03*
X443299Y201745D03*
X451224Y201820D03*
X447691Y489766D03*
X453470Y1555409D03*
X446959Y1576531D03*
X446807Y1585178D03*
X443594Y1640854D03*
X464249Y60016D03*
X466449Y55016D03*
X465849Y65016D03*
X465687Y105944D03*
X469874Y100869D03*
X466396Y95901D03*
X466600Y118000D03*
X468348Y112011D03*
X466600Y133000D03*
Y138000D03*
X466680Y124253D03*
X462637Y146170D03*
X468997Y155750D03*
X461997D03*
X459174Y209620D03*
Y204620D03*
X468540Y293270D03*
X461535Y293862D03*
X459673Y1572604D03*
X463581Y1584220D03*
X465000Y1644000D03*
X464500Y1679774D03*
X465000Y1705500D03*
X464500Y1711500D03*
X485260Y168390D03*
X478997Y155750D03*
X473997D03*
X485997D03*
X475578Y214985D03*
X477856Y1682741D03*
X479000Y1706500D03*
X502204Y179084D03*
X488800Y307380D03*
X515539Y77767D03*
X510477D03*
X507204Y179084D03*
X512204D03*
X510786Y194424D03*
X506462Y190316D03*
X510692Y248651D03*
X513193Y436878D03*
X511601Y445740D03*
X523150Y77767D03*
X528212D03*
X523504Y214072D03*
X528450Y1564400D03*
X523250Y1564540D03*
X522933Y1556550D03*
X544600Y131060D03*
X546461Y156667D03*
X533850Y169018D03*
X545396Y184681D03*
X536821Y190256D03*
Y195256D03*
X537402Y430775D03*
X540751Y603398D03*
X545877Y1526953D03*
X540877D03*
X554196Y179881D03*
X555755Y302485D03*
X548945Y302782D03*
X556248Y389786D03*
Y394786D03*
X561048Y412774D03*
X553715Y408628D03*
X556981Y451000D03*
X553058Y472332D03*
X555897Y657605D03*
Y662605D03*
X555091Y1265586D03*
X547645Y1509085D03*
X553633Y1520200D03*
X558397Y1514314D03*
X553397D03*
X572232Y77862D03*
X562784Y78299D03*
X572221Y83562D03*
X567521Y87362D03*
X567508Y81049D03*
X562821Y84262D03*
X575800Y316330D03*
X571925Y458443D03*
X570216Y759762D03*
X575216D03*
X570216Y772262D03*
X575216D03*
X572395Y1561079D03*
X572243Y1569327D03*
X586394Y78494D03*
X579060Y77970D03*
X579885Y371627D03*
X585585Y382427D03*
Y395177D03*
X578248Y415846D03*
X590998Y411846D03*
X578248Y423949D03*
X578267Y431976D03*
X584165Y479658D03*
X578944Y1555834D03*
X602287Y85071D03*
X595394Y144640D03*
X599030Y225861D03*
Y219777D03*
X605650Y214136D03*
X599974Y214461D03*
X594105Y234277D03*
X604974Y235511D03*
X600494Y232821D03*
X592248Y389786D03*
X598185Y404287D03*
X594251Y425240D03*
X600000Y446000D03*
X599623Y458376D03*
X599452Y470130D03*
X595253Y1266668D03*
X618039Y84584D03*
X616274Y187961D03*
X621274D03*
X616274Y197961D03*
X621274D03*
X616274Y192961D03*
X621274D03*
Y207961D03*
X616274Y202961D03*
X621274D03*
X616274Y212961D03*
X611074Y214061D03*
X620735Y215169D03*
X610304Y235381D03*
X615885Y371627D03*
X621585Y382427D03*
Y395177D03*
X617000Y435632D03*
X615425Y422465D03*
X634914Y121280D03*
X626705Y285305D03*
X631505Y299730D03*
Y294730D03*
X624609Y468828D03*
X622434Y1362366D03*
X628194Y1395604D03*
X634516Y1686547D03*
X633333Y1692156D03*
X642541Y78436D03*
X646388Y89882D03*
X651391Y138972D03*
Y133972D03*
X642394Y144262D03*
X651391Y143972D03*
Y148972D03*
X648585Y302289D03*
X649888Y395717D03*
X651132Y436517D03*
X650875Y449862D03*
X650800Y456240D03*
X651016Y469863D03*
X637522Y501978D03*
X643313Y518746D03*
X638967Y671774D03*
X638847Y1389887D03*
X650995Y1556550D03*
X657166Y79131D03*
X654391Y152972D03*
X654471Y163972D03*
X654371Y158572D03*
X654157Y169197D03*
X654326Y174437D03*
X654311Y186192D03*
X656318Y254591D03*
X656128Y263486D03*
X659326Y363566D03*
X659575Y478662D03*
X651908Y507929D03*
Y514092D03*
X666100Y1308048D03*
Y1312502D03*
X663224Y1387870D03*
X663431Y1645780D03*
X659837Y1698400D03*
X660654Y1704783D03*
X675242Y111960D03*
X673861Y121202D03*
X678072Y128093D03*
X680200Y417110D03*
Y425280D03*
X680266Y434313D03*
X680250Y452074D03*
Y459812D03*
Y467712D03*
X668660Y486095D03*
X681227Y488419D03*
X668946Y1508979D03*
X679792Y1536622D03*
X667971Y1685417D03*
X669513Y1732836D03*
X669555Y1723539D03*
X686211Y91492D03*
X695040Y401079D03*
X694600Y406060D03*
X683500Y421080D03*
X683400Y430360D03*
Y445830D03*
X683300Y438320D03*
X683450Y455932D03*
Y463812D03*
X694549Y499912D03*
X688500Y535514D03*
X691682Y586081D03*
X686211Y1534158D03*
X696554Y125044D03*
X710451Y152512D03*
X710799Y163012D03*
X700000Y386790D03*
X704000Y406000D03*
X699945Y402495D03*
X708218Y401233D03*
X709570Y504315D03*
X697359Y504128D03*
X700278Y499958D03*
X706041Y500099D03*
X700461Y517157D03*
X704710Y668000D03*
X698391Y1385228D03*
X708994Y1568507D03*
X710420Y1585173D03*
X710550Y1576523D03*
X709836Y1594721D03*
X709382Y1601210D03*
X697950Y1634097D03*
X707997Y1630768D03*
X702160Y1647367D03*
X709523Y1674429D03*
X704019Y1671507D03*
X704659Y1678474D03*
X719640Y386862D03*
X711500Y405673D03*
X723500Y401062D03*
X715500Y401378D03*
X719500Y406062D03*
X724500Y503014D03*
X712500Y500014D03*
X720500D03*
X716500Y503014D03*
X720400Y517440D03*
X718129Y656130D03*
X723166Y656225D03*
X715803Y670949D03*
X715152Y1634265D03*
X721898Y1636624D03*
X725371Y1673230D03*
X718891Y1672937D03*
X721408Y1677865D03*
X739500Y383500D03*
X733900Y405940D03*
X737425Y402000D03*
X736500Y500014D03*
X732500Y503014D03*
X728500Y500014D03*
X728938Y517520D03*
X741000Y518862D03*
X736339Y514603D03*
X731694Y662061D03*
X730782Y1555496D03*
X727755Y1636539D03*
X732260Y1633591D03*
X736485Y1636763D03*
X740723Y1633619D03*
X738526Y1674392D03*
X730592Y1672921D03*
X734017Y1676824D03*
X741850Y87100D03*
X753601Y143438D03*
X753501Y151312D03*
X755901Y170562D03*
X753500Y208000D03*
X746500Y207500D03*
X751000Y225000D03*
X754800Y379919D03*
X743500Y386962D03*
X745000Y400000D03*
X744000Y405970D03*
X750800Y405992D03*
X753700Y401179D03*
X752500Y500014D03*
X742144Y504935D03*
X744500Y500014D03*
X748500Y503014D03*
X747110Y1579863D03*
X747160Y1587773D03*
X744315Y1673134D03*
X745382Y1683663D03*
X764343Y162084D03*
X761000Y199000D03*
X763958Y272775D03*
X764767Y267322D03*
X763500Y386862D03*
X756300Y405840D03*
X762500Y401100D03*
X761600Y406060D03*
X766300Y404280D03*
X757500Y499980D03*
X765690D03*
X761500Y503014D03*
X764600Y517022D03*
X766566Y532172D03*
X770800Y535640D03*
X766889Y1486756D03*
Y1530256D03*
X757770Y1636083D03*
X761510Y1656483D03*
X773901Y170064D03*
X783267Y267722D03*
Y282922D03*
Y275322D03*
X772513Y374490D03*
X783736Y441100D03*
X783241Y461515D03*
X777385Y466879D03*
X783796Y456205D03*
X783895Y470961D03*
X783759Y479344D03*
X777465Y483344D03*
X776400Y533300D03*
X778850Y1556133D03*
X771592Y1572717D03*
X771650Y1591733D03*
X793879Y194881D03*
X789942Y204724D03*
X793879Y214567D03*
X794058Y301569D03*
X793221Y296062D03*
X793897Y309026D03*
X786624Y465585D03*
X800185Y453381D03*
X799150Y1575233D03*
X799775Y1591498D03*
Y1598719D03*
X799888Y1603833D03*
X814115Y120773D03*
X810811Y135132D03*
X810641Y128262D03*
X810481Y141762D03*
X805690Y188976D03*
Y220472D03*
X803302Y265848D03*
X810139Y274098D03*
X805491Y373158D03*
X802175Y418362D03*
X813114Y443344D03*
X801552Y463318D03*
X811189Y524000D03*
X809216Y551473D03*
X814954Y565087D03*
X813400Y1575483D03*
X813571Y1597534D03*
X822531Y125698D03*
X828615D03*
X817501Y194881D03*
X821438Y204724D03*
X817501Y214567D03*
X816232Y341584D03*
X818157Y381020D03*
X816747Y412367D03*
X816236Y439279D03*
X816109Y449802D03*
X816000Y463578D03*
X816170Y458524D03*
X816109Y471344D03*
X820500Y515323D03*
X817441Y533000D03*
X820850Y1556133D03*
X831540Y70643D03*
X834115Y135698D03*
X833615Y129198D03*
X839461Y146042D03*
X833321Y145912D03*
X831296Y171632D03*
X845221Y192862D03*
X839221D03*
X834921Y220303D03*
X838681Y224752D03*
X843511Y228962D03*
X839081Y233252D03*
X836181Y275686D03*
X843417Y384888D03*
X838500Y471000D03*
X835236Y483635D03*
X841854Y504972D03*
X836893Y537215D03*
X834750Y561347D03*
X841150Y1575233D03*
X841775Y1591574D03*
X841851Y1598753D03*
X841924Y1603879D03*
X852258Y54892D03*
X856630Y70793D03*
X846191Y145262D03*
X849321Y196532D03*
X853341Y199932D03*
X855401Y204772D03*
X859075Y387739D03*
X852000Y408000D03*
X848500Y461500D03*
X852240Y482500D03*
X849351Y499070D03*
X855400Y1575483D03*
X856015Y1596916D03*
X855745Y1615986D03*
X866452Y168862D03*
Y173862D03*
X869901Y209562D03*
X868520Y263654D03*
X871190Y391760D03*
X865366Y393710D03*
X864386Y417186D03*
X862987Y507305D03*
X868496Y776516D03*
X862850Y1556133D03*
X870453Y1616463D03*
X883150Y1575233D03*
X883869Y1591629D03*
X883831Y1598716D03*
X883905Y1603864D03*
X882535Y1616701D03*
X900456Y155618D03*
X895456D03*
X893701Y201799D03*
X899501Y201899D03*
X904850Y1556133D03*
X897381Y1574788D03*
X898065Y1596318D03*
X910258Y600751D03*
X910377Y606694D03*
X925068Y272340D03*
X925650Y1576233D03*
Y1586733D03*
X925726Y1592261D03*
X945263Y269781D03*
X938956Y585132D03*
X940856Y614150D03*
X939681Y628662D03*
X944265Y1285729D03*
X937755Y1594881D03*
X963500Y1275000D03*
X977071Y215709D03*
X981897Y198629D03*
X992830Y260781D03*
Y271443D03*
X992508Y295634D03*
X988646Y371434D03*
X986696Y428366D03*
X988242Y1273193D03*
X1008707Y230423D03*
X997461Y230019D03*
X1008108Y420886D03*
X999304Y1282574D03*
Y1289215D03*
X1014435Y160518D03*
X1021440Y226423D03*
X1010028Y263340D03*
Y274002D03*
X1010550Y298312D03*
X1010157Y288489D03*
X1019264Y493655D03*
X1022764Y489655D03*
X1019410Y485582D03*
X1018872Y549855D03*
X1029269Y378764D03*
X1033069Y382764D03*
X1029269Y386244D03*
X1033449Y424500D03*
X1039015Y444404D03*
X1034246Y553980D03*
X1038333Y551098D03*
X1038054Y544261D03*
X1045848Y194881D03*
X1041911Y204724D03*
X1045848Y214567D03*
X1050639Y1311149D03*
Y1307149D03*
X1057659Y188976D03*
Y220472D03*
X1058223Y464938D03*
X1060316Y460251D03*
X1058205Y471500D03*
X1062258Y467919D03*
X1060719Y516059D03*
X1066019Y1378597D03*
X1069470Y194881D03*
X1073407Y204724D03*
X1069470Y214567D03*
X1075600Y1533700D03*
X1088558Y377306D03*
X1088588Y382506D03*
X1090035Y388477D03*
X1088221Y394170D03*
X1107043Y447355D03*
X1109043Y452855D03*
X1107005Y481355D03*
X1107043Y468039D03*
X1111043Y471855D03*
X1107005Y475355D03*
X1111005Y478355D03*
X1107043Y489391D03*
X1111043Y485771D03*
X1103110Y1533520D03*
X1113167Y1554508D03*
X1105500Y1643500D03*
X1107766Y1635951D03*
X1111167Y1643333D03*
X1110936Y1654416D03*
X1109519Y1660925D03*
X1103489Y1711244D03*
X1128100Y376862D03*
X1127408Y386271D03*
X1126387Y615658D03*
X1123816Y1456373D03*
X1119131Y1534854D03*
X1117665Y1539877D03*
X1125156Y1573436D03*
X1120656D03*
X1115005Y1573346D03*
X1120152Y1597498D03*
X1125756D03*
X1115005Y1587936D03*
X1116481Y1661631D03*
X1120303Y1670114D03*
X1115450Y1685011D03*
X1119361Y1724109D03*
X1141901Y56691D03*
X1138710Y370496D03*
X1131400Y391562D03*
X1141267Y500296D03*
X1143095Y1459523D03*
X1137604Y1561627D03*
X1141916Y1573597D03*
X1132168Y1630557D03*
X1138456Y1632280D03*
X1142350Y1659564D03*
X1135398Y1663760D03*
X1148043Y456855D03*
X1152043Y453121D03*
X1148043Y462921D03*
X1152543Y459855D03*
Y465480D03*
X1148043Y468039D03*
X1152839Y482374D03*
X1151036Y501627D03*
X1155109Y1456295D03*
X1152549Y1562311D03*
X1148089Y1573555D03*
X1163431Y82818D03*
X1166691Y1555367D03*
X1169035Y1547314D03*
X1187374Y59122D03*
X1187214Y52572D03*
X1186734Y65122D03*
X1180777Y90385D03*
X1180280Y100793D03*
X1177336Y577407D03*
X1178536Y584307D03*
X1174053Y1547420D03*
X1175773Y1568000D03*
Y1563000D03*
Y1573000D03*
X1181660Y1690829D03*
X1195488Y83175D03*
X1197381Y133866D03*
X1196227Y432202D03*
Y448202D03*
Y440202D03*
X1195645Y601873D03*
Y605973D03*
X1196988Y1673050D03*
X1189407Y1707143D03*
X1189454Y1723702D03*
X1213107Y161551D03*
X1210607Y157051D03*
Y166051D03*
X1210707Y171051D03*
X1212888Y176470D03*
X1209059Y181187D03*
X1212182Y185187D03*
X1214094Y282948D03*
Y287948D03*
X1209937Y465376D03*
Y460376D03*
Y470376D03*
X1203272Y1399140D03*
X1204492Y1442500D03*
X1204664Y1447500D03*
X1213072Y1673059D03*
X1230693Y150239D03*
X1230094Y287948D03*
Y282948D03*
X1222094D03*
Y292066D03*
Y305216D03*
X1226094Y314216D03*
X1232154Y436875D03*
Y431875D03*
Y441875D03*
X1224200Y1393500D03*
X1221837Y1438800D03*
X1246715Y463158D03*
X1245187Y458182D03*
Y453182D03*
X1239800Y1389500D03*
X1233700Y1395600D03*
X1241613Y1414500D03*
X1239965Y1427544D03*
X1252693Y133549D03*
X1249693Y129239D03*
Y145053D03*
X1253107Y167276D03*
X1249107Y163551D03*
X1253107Y180551D03*
X1249107Y177051D03*
Y170551D03*
X1253107Y174051D03*
X1249107Y184051D03*
X1262094Y282948D03*
X1254094D03*
X1262094Y287948D03*
X1258500Y392500D03*
X1259075Y769000D03*
X1275964Y95379D03*
X1267611Y150030D03*
X1270094Y282948D03*
Y292066D03*
X1274000Y385000D03*
X1277457Y396165D03*
X1269258Y399125D03*
X1272457Y394559D03*
X1269229Y407865D03*
X1277738Y417241D03*
X1272825Y416295D03*
X1277677Y770388D03*
X1264895Y769106D03*
X1267530Y1598620D03*
X1272490Y1594520D03*
X1265783Y1590340D03*
X1283465Y86960D03*
X1284593Y122259D03*
X1287693Y128239D03*
X1290193Y132739D03*
X1287693Y137239D03*
Y146239D03*
X1290193Y141739D03*
X1280901Y168401D03*
X1281128Y161816D03*
X1280791Y173783D03*
X1281570Y184513D03*
X1278094Y282948D03*
X1286094D03*
Y292066D03*
X1282458Y396184D03*
X1287340Y397279D03*
X1280886Y421145D03*
X1281677Y756588D03*
X1290677Y771388D03*
X1289577Y1559953D03*
X1284577D03*
X1296200Y56536D03*
X1301705Y72342D03*
X1294094Y287948D03*
Y282948D03*
X1302094D03*
Y292066D03*
X1296677Y770888D03*
X1297333Y1553200D03*
X1302097Y1547314D03*
X1294745Y1541981D03*
X1297097Y1547314D03*
X1308110Y56536D03*
X1320020Y56604D03*
X1313615Y72342D03*
X1310094Y287948D03*
Y282948D03*
X1318094D03*
X1316095Y1594079D03*
X1315943Y1600322D03*
X1331930Y56570D03*
X1329435Y70452D03*
X1333399Y87709D03*
X1334094Y287948D03*
X1326094Y282948D03*
X1334094D03*
X1326094Y292066D03*
X1337257Y678765D03*
X1322644Y1588834D03*
X1343840Y56536D03*
X1337435Y70452D03*
X1343877D03*
X1341399Y87709D03*
X1348199D03*
X1350094Y287948D03*
X1342094Y282948D03*
X1350094D03*
X1342094Y292066D03*
X1355750Y56536D03*
X1353309Y87675D03*
X1360109D03*
X1356199Y100425D03*
X1366094Y287948D03*
X1358094Y282948D03*
X1366094D03*
X1358094Y292066D03*
X1367950Y56536D03*
X1378945Y68142D03*
X1372655Y236594D03*
Y241594D03*
Y246594D03*
Y251594D03*
X1379261Y1716438D03*
X1394695Y1589550D03*
X1383800Y1695238D03*
X1392420Y1708038D03*
X1410961Y1280751D03*
X1399009Y1598883D03*
X1401552Y1594362D03*
X1398018Y1605304D03*
X1410622Y1617000D03*
X1399940Y1646967D03*
X1424271Y112849D03*
X1422807Y1541981D03*
X1417639Y1559953D03*
X1412639D03*
X1412648Y1568976D03*
Y1573976D03*
X1416000Y1617000D03*
X1418740Y1638167D03*
X1439951Y62174D03*
X1431816Y104219D03*
X1438549Y124818D03*
X1433549D03*
X1435645Y166180D03*
X1427119Y244450D03*
X1440119D03*
X1438209Y1547314D03*
X1433209D03*
X1427807Y1541981D03*
X1429800Y1557762D03*
X1433184Y1628126D03*
X1439500Y1633500D03*
X1450723Y103655D03*
X1443549Y124818D03*
X1450915Y125038D03*
X1449769Y163842D03*
X1441898Y576755D03*
X1449956Y1267923D03*
X1455314Y1267286D03*
X1452207Y1594079D03*
X1454274Y1600121D03*
X1451500Y1633500D03*
X1445500D03*
X1445079Y1677089D03*
X1451000Y1677000D03*
X1445754Y1689990D03*
X1460820Y52933D03*
X1458756Y1588834D03*
X1463231Y1676766D03*
X1472647Y539478D03*
X1473444Y555208D03*
X1478147Y547728D03*
X1484347Y580388D03*
X1481612Y1675112D03*
X1474146Y1687854D03*
X1492789Y576602D03*
X1509479Y130822D03*
X1502085Y545432D03*
X1507109Y550059D03*
X1502757Y570977D03*
X1505477Y1265844D03*
X1513046Y1286424D03*
X1530884Y62569D03*
X1526894Y209250D03*
Y221250D03*
Y214250D03*
Y249250D03*
Y244250D03*
X1519457Y556338D03*
X1522875Y1268496D03*
X1529045Y1280128D03*
X1521346Y1281136D03*
X1518081Y1296288D03*
X1530807Y1589550D03*
X1533815Y57185D03*
X1545747Y301400D03*
X1545556Y292816D03*
X1545187Y306854D03*
X1542842Y1265928D03*
X1532335Y1265721D03*
X1537295Y1274681D03*
X1531750Y1598190D03*
X1536664Y1594520D03*
X1553772Y289856D03*
X1558773Y289875D03*
X1559054Y310900D03*
X1553653Y310980D03*
X1548197Y311209D03*
X1558924Y1541975D03*
X1553751Y1559953D03*
X1548751D03*
X1563655Y290970D03*
X1561507Y1553200D03*
X1566271Y1547314D03*
X1561271D03*
X1582928Y214250D03*
Y234250D03*
Y239250D03*
Y229250D03*
Y244250D03*
X1577934Y531226D03*
X1586818Y1588834D03*
X1580269Y1594079D03*
X1580117Y1600322D03*
X1605241Y541123D03*
X1617534Y289742D03*
X1627800Y519254D03*
X1629833Y1312091D03*
X1634065Y1415729D03*
X1646010Y423702D03*
X1647377Y1385408D03*
X1646533Y1445767D03*
X1662900Y141762D03*
Y151762D03*
Y146762D03*
Y161762D03*
X1654610Y405002D03*
X1661610Y405202D03*
X1653610Y423702D03*
X1661210D03*
X1650757Y626918D03*
X1658869Y1589550D03*
X1680020Y420132D03*
X1674640Y1445639D03*
X1676819Y1541979D03*
X1665726Y1594362D03*
X1679816Y1674318D03*
X1676397Y1684818D03*
X1677930Y1679305D03*
X1676397Y1689818D03*
Y1699818D03*
Y1694818D03*
X1675360Y1716877D03*
Y1732027D03*
X1687537Y1567788D03*
X1694075Y1567158D03*
X1686064Y1573892D03*
X1684816Y1674318D03*
X1689816D03*
X1706066Y57098D03*
X1700617Y1682744D03*
Y1687744D03*
Y1692744D03*
X1722566Y57098D03*
X1717566D03*
X1712566D03*
X1717808Y108959D03*
X1716876Y120278D03*
X1721384Y135373D03*
X1717100Y377962D03*
X1718465Y660982D03*
X1718576Y666238D03*
X1718819Y1400561D03*
X1710360Y1716877D03*
X1729609Y90014D03*
X1731470Y358022D03*
X1738480Y358082D03*
X1735870Y387082D03*
X1728860Y387032D03*
X1730202Y1579277D03*
X1734589Y1666203D03*
X1735463Y1684165D03*
X1734863Y1676514D03*
X1741852Y123774D03*
X1745490Y357002D03*
X1746120Y368132D03*
X1745910Y363112D03*
Y373522D03*
X1742770Y387112D03*
X1747963Y1652565D03*
X1752963Y1652665D03*
X1740463Y1684165D03*
X1745463D03*
X1749480Y1728533D03*
X1756598Y677503D03*
X1762812D03*
X1763263Y1657865D03*
X1763163Y1679965D03*
X1775558Y1604620D03*
X1797692Y146285D03*
X1797765Y151834D03*
Y156834D03*
Y161834D03*
X1785051Y177578D03*
X1795346Y372732D03*
X1793479Y1598723D03*
X1785221Y1605473D03*
X1800212Y390411D03*
X1810924Y427432D03*
X1800979Y1583378D03*
X1815315Y145716D03*
X1814905Y156797D03*
Y166947D03*
X1818274Y366053D03*
Y385293D03*
X1839916Y161834D03*
G54D203*
X506670Y132573D03*
Y157769D03*
X538166Y132573D03*
Y157769D03*
G54D330*
G01X34671Y1502214D02*
X39496D01*
G01X31521D02*
X30019Y1500712D01*
X28123D01*
X27205Y1501630D01*
G01X31521Y1497914D02*
X30223Y1499212D01*
X28187D01*
X27205Y1498230D01*
G01X38496Y1496714D02*
X35871D01*
X34671Y1497914D01*
G01X43020Y382942D02*
X44473Y384395D01*
X45876D01*
G01X41933Y395652D02*
X43347Y394238D01*
X45876D01*
G01X48412Y520331D02*
Y518235D01*
X47812Y517635D01*
G01X48172Y538879D02*
X48412Y538639D01*
Y535095D01*
G01X45951Y528697D02*
X43437D01*
X42810Y528070D01*
G01X48383Y1532395D02*
X42150Y1538628D01*
Y1546791D01*
G01Y1550505D02*
X46150D01*
G01X42150Y1546791D02*
Y1550505D01*
G01X51996Y1551367D02*
X51923Y1551294D01*
X49196D01*
G01X57370Y1542339D02*
Y1543054D01*
X53842Y1546582D01*
Y1549521D01*
X51996Y1551367D01*
G01Y1554517D02*
Y1556097D01*
X50642Y1557451D01*
G01X41208Y1598896D02*
Y1594396D01*
G01Y1603396D02*
Y1598896D01*
G01X45120Y1603396D02*
X41208D01*
G01X51133Y1633321D02*
Y1631796D01*
G01X46133Y1633321D02*
Y1632260D01*
X47297Y1631096D01*
G01X53406Y399799D02*
Y402862D01*
G01X68020Y395222D02*
X67035Y396207D01*
X64872D01*
G01Y394238D02*
X67036D01*
X68020Y395222D01*
G01X56286Y520331D02*
Y518199D01*
X55682Y517595D01*
G01X54317Y526729D02*
X53333Y527713D01*
G01X56286Y535095D02*
Y537701D01*
X56192Y537795D01*
G01X60715Y528697D02*
X63165D01*
X63633Y528229D01*
G01X64771Y1552869D02*
X67196D01*
G01X61133Y1636421D02*
Y1631796D01*
G01X56133Y1636421D02*
Y1631696D01*
G01X67058Y1630396D02*
Y1635048D01*
X69003Y1636993D01*
X75764D01*
G01X64462Y1658400D02*
Y1655624D01*
G01X339278Y1192112D02*
X338827Y1192563D01*
Y1214334D01*
X327237Y1225924D01*
X287604D01*
X246690Y1266838D01*
X213909D01*
X210689Y1270058D01*
X98095D01*
X72333Y1295820D01*
Y1306745D01*
X74395Y1308807D01*
X77059D01*
X78760Y1307106D01*
G01X336778Y1192112D02*
X337327Y1192661D01*
Y1213712D01*
X326615Y1224424D01*
X286982D01*
X246068Y1265338D01*
X213287D01*
X210067Y1268558D01*
X97473D01*
X70833Y1295198D01*
Y1307367D01*
X73773Y1310307D01*
X76881D01*
X78760Y1312186D01*
G01Y1307106D02*
X80463Y1308809D01*
X81783D01*
X82953Y1307639D01*
Y1307607D01*
G01X78760Y1312186D02*
X80637Y1310309D01*
X81725D01*
X83023Y1311607D01*
G01X70592Y1634905D02*
X70208Y1634521D01*
Y1630396D01*
G01X79164Y1636992D02*
X77077Y1634905D01*
X73742D01*
G01X96966Y159744D02*
Y163610D01*
X98862Y165506D01*
X100818D01*
G01Y168906D02*
X99974D01*
X94407Y163339D01*
Y162303D01*
G01X94158Y1311176D02*
X93715Y1311619D01*
X90150D01*
G01D02*
Y1314560D01*
G01X82953Y1307607D02*
X84155Y1308809D01*
X85670D01*
X86980Y1307499D01*
G01X83023Y1311607D02*
X84298Y1310332D01*
X85713D01*
X87000Y1311619D01*
G01X98428Y1544165D02*
X97018Y1545575D01*
Y1546331D01*
G01X83121Y1544869D02*
Y1542294D01*
G01X101679Y158191D02*
X99273D01*
X98857Y157775D01*
X96966D01*
G01X101995Y1382593D02*
X104863D01*
G01X107000Y1407425D02*
X110000D01*
G01X107000Y1410575D02*
Y1414425D01*
X106925Y1414500D01*
G01D02*
Y1416925D01*
X110000Y1420000D01*
G01X110075Y1414500D02*
Y1417075D01*
X111500Y1418500D01*
G01X110075Y1414500D02*
Y1410500D01*
G01X104511Y1550071D02*
X108511D01*
G01X134595Y1382593D02*
X137463D01*
G01X140925Y1417500D02*
Y1415575D01*
X142000Y1414500D01*
G01X136500Y1425000D02*
X137500Y1424000D01*
Y1420925D01*
X140925Y1417500D01*
G01X144925Y1429500D02*
X141500D01*
G01X144075Y1417500D02*
Y1418924D01*
X143499Y1419500D01*
X141500D01*
X139500Y1421500D01*
Y1425000D01*
X138000Y1426500D01*
G01X141028Y1449037D02*
Y1447528D01*
X139500Y1446000D01*
G01D02*
X136100Y1442600D01*
G01X143500Y1445575D02*
X143066Y1445573D01*
X138013Y1440487D01*
G01D02*
X137026Y1439500D01*
G01X135948Y1437425D02*
X139575D01*
X140500Y1436500D01*
X141514D01*
G01D02*
X143925D01*
X144925Y1437500D01*
G01X141028Y1449037D02*
X145028D01*
G01X142465Y1662493D02*
Y1663063D01*
X141191Y1664337D01*
G01X143778Y1682587D02*
X141078Y1679887D01*
G01X148000Y1414425D02*
X145000D01*
G01X148000Y1417575D02*
X144150D01*
X144075Y1417500D01*
G01X151000Y1445575D02*
X147000D01*
G01D02*
X143500D01*
G01X145028Y1449037D02*
X149028D01*
G01X167295Y1382593D02*
X170163D01*
G01X171433Y1521331D02*
Y1518085D01*
X171388Y1518040D01*
G01X164650Y1531600D02*
Y1529350D01*
G01Y1542500D02*
Y1540250D01*
G01Y1538000D02*
Y1540250D01*
G01X183142Y1509459D02*
Y1507707D01*
X182947Y1507512D01*
G01X183548Y1522169D02*
Y1524532D01*
G01X185688Y1519195D02*
X185076Y1519807D01*
X183548D01*
G01D02*
Y1522169D01*
G01Y1519807D02*
Y1517445D01*
G01D02*
Y1515225D01*
X184530Y1514243D01*
G01X184323Y1511505D02*
X184530Y1511712D01*
Y1514243D01*
G01D02*
X186860D01*
G01X171388Y1510800D02*
X173488D01*
G01X171388Y1514420D02*
X173488D01*
G01X171388Y1518040D02*
X173488D01*
G01X186530Y1521453D02*
X183548Y1522169D01*
G01X183142Y1509459D02*
Y1510324D01*
X184323Y1511505D01*
G01X181961D02*
X179598D01*
G01X180780Y1507509D02*
Y1509459D01*
G01X179598Y1511505D02*
X178580Y1510487D01*
Y1507509D01*
G01X181503Y1528075D02*
X180288Y1528995D01*
X179457Y1529256D01*
G01X184530Y1527880D02*
X183548Y1526898D01*
Y1524532D01*
G01X179457D02*
X181503Y1523351D01*
G01D02*
X182684Y1524532D01*
X183548D01*
G01Y1536343D02*
Y1537656D01*
X184323Y1538431D01*
G01X183548Y1536343D02*
Y1533980D01*
G01X171433Y1528731D02*
X173980D01*
G01X179457Y1529256D02*
X177579Y1528725D01*
G01X179457Y1524532D02*
X177579Y1523810D01*
G01X186579Y1536063D02*
Y1536343D01*
X183548D01*
G01X184530Y1527880D02*
X187081Y1528853D01*
G01X183548Y1533980D02*
Y1531618D01*
G01X181503Y1528075D02*
X182290Y1528862D01*
X183548D01*
G01Y1531618D02*
Y1528862D01*
G01D02*
X184530Y1527880D01*
G01X184323Y1538431D02*
X183142Y1540477D01*
G01X183051Y1542425D02*
Y1540568D01*
X183142Y1540477D01*
G01X181961Y1538431D02*
X180780Y1540477D01*
G01X183051Y1544625D02*
X182427D01*
X180780Y1542978D01*
Y1540477D01*
G01X178980Y1540317D02*
Y1539755D01*
X179598Y1539137D01*
Y1538431D01*
G01X200195Y1382593D02*
X203063D01*
G01X187866Y1509459D02*
Y1507683D01*
X188254Y1507295D01*
G01X197315Y1509459D02*
Y1507683D01*
X197703Y1507295D01*
G01X192591Y1509459D02*
Y1507683D01*
X192979Y1507295D01*
G01X201033Y1514243D02*
X198703D01*
G01X203428D02*
X201033D01*
G01X198703D02*
X196309D01*
G01D02*
X193979D01*
G01X186860D02*
X189254D01*
G01D02*
X189047Y1511505D01*
G01X189254Y1514243D02*
X191584D01*
G01X193979D02*
X193772Y1511505D01*
G01X193979Y1514243D02*
X191584D01*
G01X198496Y1511505D02*
X198703Y1514243D01*
G01X189254Y1522200D02*
X186530Y1521453D01*
G01X193979Y1522200D02*
X191254Y1521453D01*
G01X198703Y1522200D02*
X195979Y1521453D01*
G01X203428Y1522200D02*
X200703Y1521453D01*
G01X191254D02*
X189254Y1522200D01*
G01X195979Y1521453D02*
X193979Y1522200D01*
G01X200703Y1521453D02*
X198703Y1522200D01*
G01X187866Y1509459D02*
Y1510324D01*
X189047Y1511505D01*
G01X192591Y1509459D02*
Y1510324D01*
X193772Y1511505D01*
G01X197315Y1509459D02*
Y1510324D01*
X198496Y1511505D01*
G01X189254Y1536063D02*
X189047Y1538431D01*
G01X193979Y1536063D02*
X193772Y1538431D01*
G01X198496D02*
X198703Y1536063D01*
G01X189254D02*
X186579D01*
G01X193979D02*
X196029D01*
G01X189254D02*
X191304D01*
G01X203428D02*
X200753D01*
G01X196029D02*
X198703D01*
G01X191304D02*
X193979D01*
G01X200753D02*
X198703D01*
G01X189254Y1528106D02*
X191805Y1528853D01*
G01X193979Y1528106D02*
X196530Y1528853D01*
G01X198703Y1528106D02*
X201254Y1528853D01*
G01X187081D02*
X189254Y1528106D01*
G01X191805Y1528853D02*
X193979Y1528106D01*
G01X196530Y1528853D02*
X198703Y1528106D01*
G01X201254Y1528853D02*
X203428Y1528106D01*
G01X187866Y1540477D02*
X188254Y1540865D01*
Y1542641D01*
G01X189047Y1538431D02*
X187866Y1540477D01*
G01X192591D02*
X192979Y1540865D01*
Y1542641D01*
G01X193772Y1538431D02*
X192591Y1540477D01*
G01X197315D02*
X198496Y1538431D01*
G01X197703Y1542641D02*
Y1540865D01*
X197315Y1540477D01*
G01X210199Y714074D02*
X208949Y715324D01*
Y720364D01*
X211933Y723348D01*
Y739580D01*
X224194Y751841D01*
X240996D01*
X246913Y757758D01*
Y760470D01*
X248625Y762182D01*
G01X206199Y714074D02*
X207449Y715324D01*
Y720986D01*
X210433Y723970D01*
Y740202D01*
X223572Y753341D01*
X240374D01*
X245413Y758380D01*
Y760394D01*
X243625Y762182D01*
G01X211488Y1509459D02*
Y1507683D01*
X211876Y1507295D01*
G01X203428Y1514243D02*
X203221Y1511505D01*
G01X215206Y1514243D02*
X217601D01*
G01X215206D02*
X212876D01*
G01X210482D02*
X212876D01*
G01X205758D02*
X208152D01*
G01X205758D02*
X203428D01*
G01X208152D02*
X207945Y1511505D01*
G01X208152Y1514243D02*
X210482D01*
G01X212669Y1511505D02*
X212876Y1514243D01*
G01X208152Y1522200D02*
X205427Y1521453D01*
G01X212876Y1522200D02*
X210152Y1521453D01*
G01X217601Y1522200D02*
X214876Y1521453D01*
G01X205427D02*
X203428Y1522200D01*
G01X210152Y1521453D02*
X208152Y1522200D01*
G01X214876Y1521453D02*
X212876Y1522200D01*
G01X216213Y1509459D02*
Y1507683D01*
X216601Y1507295D01*
G01X216213Y1509459D02*
Y1510324D01*
X217394Y1511505D01*
G01X211488Y1509459D02*
Y1510324D01*
X212669Y1511505D01*
G01X203428Y1536063D02*
X203221Y1538431D01*
G01X207945D02*
X208152Y1536063D01*
G01X212669Y1538431D02*
X212876Y1536063D01*
G01X203428D02*
X205478D01*
G01X217601D02*
X214926D01*
G01X212876D02*
X210202D01*
G01X205478D02*
X208152D01*
G01X214926D02*
X212876D01*
G01X210202D02*
X208152D01*
G01X203428Y1528106D02*
X205978Y1528853D01*
G01X208152Y1528106D02*
X210703Y1528853D01*
G01X212876Y1528106D02*
X215427Y1528853D01*
G01X205978D02*
X208152Y1528106D01*
G01X210703Y1528853D02*
X212876Y1528106D01*
G01X215427Y1528853D02*
X217601Y1528106D01*
G01X202039Y1540477D02*
X202427Y1540865D01*
Y1542641D01*
G01X203221Y1538431D02*
X202039Y1540477D01*
G01X206764D02*
X207945Y1538431D01*
G01X207152Y1542641D02*
Y1540865D01*
X206764Y1540477D01*
G01X211488D02*
X212669Y1538431D01*
G01X216213Y1540477D02*
X217394Y1538431D01*
G01X216601Y1542641D02*
Y1540865D01*
X216213Y1540477D01*
G01X211876Y1542641D02*
Y1540865D01*
X211488Y1540477D01*
G01X228675Y564034D02*
X229575Y563134D01*
Y561562D01*
X231625Y559512D01*
X265210D01*
G01X224157Y715915D02*
X227157D01*
G01D02*
X228657Y714415D01*
X231260D01*
X232668Y715823D01*
G01X224157Y715915D02*
X223721Y715479D01*
X222306D01*
X221306Y716479D01*
Y722128D01*
X222686Y723508D01*
X228827D01*
X302630Y797311D01*
X465222D01*
X521769Y853858D01*
X522655D01*
X523074Y853439D01*
G01X232711Y711602D02*
X231398Y712915D01*
X224157D01*
G01D02*
X223407Y713665D01*
X221874D01*
X219706Y715833D01*
Y722785D01*
X221929Y725008D01*
X228205D01*
X302008Y798811D01*
X464406D01*
X521002Y855407D01*
X522542D01*
X523074Y855939D01*
G01X220937Y1509459D02*
Y1507683D01*
X221325Y1507295D01*
G01X230386Y1509459D02*
Y1507683D01*
X230774Y1507295D01*
G01X225661Y1509459D02*
Y1507683D01*
X226049Y1507295D01*
G01X217394Y1511505D02*
X217601Y1514243D01*
G01D02*
X219931D01*
G01X229380D02*
X227050D01*
G01X229380D02*
X231774D01*
G01X227050D02*
X224655D01*
G01D02*
X222325D01*
G01D02*
X222118Y1511505D01*
G01X219931Y1514243D02*
X222325D01*
G01X226843Y1511505D02*
X227050Y1514243D01*
G01X222325Y1522200D02*
X219601Y1521453D01*
G01X227050Y1522200D02*
X224325Y1521453D01*
G01X227050Y1522200D02*
X229049Y1521453D01*
G01X219601D02*
X217601Y1522200D01*
G01X224325Y1521453D02*
X222325Y1522200D01*
G01X229049Y1521453D02*
X231774Y1522200D01*
G01X220937Y1509459D02*
Y1510324D01*
X222118Y1511505D01*
G01X230386Y1509459D02*
Y1510324D01*
X231567Y1511505D01*
G01X226843D02*
X225661Y1510323D01*
Y1509459D01*
G01X217394Y1538431D02*
X217601Y1536063D01*
G01X222118Y1538431D02*
X222325Y1536063D01*
G01X226843Y1538431D02*
X227050Y1536063D01*
G01X217601D02*
X219651D01*
G01X222325D02*
X224375D01*
G01X231774D02*
X229100D01*
G01X224375D02*
X227050D01*
G01X229100D02*
X227050D01*
G01X217601Y1528106D02*
X220152Y1528853D01*
G01X222325Y1528106D02*
X224876Y1528853D01*
G01X231774Y1528106D02*
X229600Y1528853D01*
G01X220152D02*
X222325Y1528106D01*
G01X224876Y1528853D02*
X227050Y1528106D01*
G01X229600Y1528853D02*
X227050Y1528106D01*
G01X222325Y1536063D02*
X219651D01*
G01X220937Y1540477D02*
X222118Y1538431D01*
G01X221325Y1542641D02*
Y1540865D01*
X220937Y1540477D01*
G01X225661D02*
X226843Y1538431D01*
G01X226049Y1542641D02*
Y1540865D01*
X225661Y1540477D01*
G01X231567Y1538431D02*
X230386Y1540477D01*
G01X230774Y1542641D02*
Y1540865D01*
X230386Y1540477D01*
G01X242297Y123968D02*
X242298Y123967D01*
Y122532D01*
X242196Y122430D01*
Y119305D01*
G01X246297Y123968D02*
Y120445D01*
X245157Y119305D01*
X242196D01*
G01X238297Y123968D02*
Y121555D01*
G01X235147Y127118D02*
Y124435D01*
G01X246297Y127118D02*
Y129899D01*
X243813Y132383D01*
G01X242297Y127118D02*
Y129693D01*
X241271Y130719D01*
G01X237275Y142062D02*
X239912D01*
X239988Y141986D01*
G01X232817Y564002D02*
X231742Y562927D01*
Y562012D01*
X232242Y561512D01*
X246314D01*
G01X243625Y762182D02*
X245413Y763970D01*
Y766126D01*
X241371Y770168D01*
Y776088D01*
X287849Y822566D01*
X310102D01*
X310831Y821837D01*
X327376D01*
X335016Y829477D01*
X336529Y835540D01*
Y843721D01*
X332895Y849156D01*
X327914Y853241D01*
X318228Y857249D01*
X305991Y869486D01*
Y877458D01*
X306902Y878369D01*
X308295Y879177D01*
X308693Y880671D01*
G01X248625Y762182D02*
X246913Y763894D01*
Y766748D01*
X242871Y770790D01*
Y775466D01*
X288471Y821066D01*
X309479D01*
X310208Y820337D01*
X327998D01*
X336371Y828710D01*
X338029Y835355D01*
Y844177D01*
X334019Y850175D01*
X328693Y854543D01*
X319078Y858522D01*
X307491Y870108D01*
Y876836D01*
X307825Y877169D01*
X309047Y877879D01*
X309048D01*
X310543Y877482D01*
G01X232995Y1382593D02*
X235863D01*
G01X235110Y1509459D02*
Y1507683D01*
X235498Y1507295D01*
G01X244559Y1509459D02*
Y1507683D01*
X244947Y1507295D01*
G01X239835Y1509459D02*
Y1507683D01*
X240223Y1507295D01*
G01X231567Y1511505D02*
X231774Y1514243D01*
G01D02*
X234104D01*
G01X243553D02*
X241223D01*
G01X245947D02*
X243553D01*
G01X241223D02*
X238828D01*
G01D02*
X236498D01*
G01D02*
X236291Y1511505D01*
G01X234104Y1514243D02*
X236498D01*
G01X241016Y1511505D02*
X241223Y1514243D01*
G01X245740Y1511505D02*
X245947Y1514243D01*
G01Y1522200D02*
X243223Y1521453D01*
G01X241223Y1522200D02*
X238498Y1521453D01*
G01X236498Y1522200D02*
X233774Y1521453D01*
G01X243223D02*
X241223Y1522200D01*
G01X238498Y1521453D02*
X236498Y1522200D01*
G01X233774Y1521453D02*
X231774Y1522200D01*
G01X235110Y1509459D02*
Y1510324D01*
X236291Y1511505D01*
G01X244559Y1509459D02*
Y1510324D01*
X245740Y1511505D01*
G01X239835Y1509459D02*
Y1510324D01*
X241016Y1511505D01*
G01X231774Y1536063D02*
X231567Y1538431D01*
G01X236291D02*
X236498Y1536063D01*
G01X241223D02*
X241016Y1538431D01*
G01X245740D02*
X245947Y1536063D01*
G01X231774D02*
X233824D01*
G01X241223D02*
X243273D01*
G01X241223D02*
X238548D01*
G01X233824D02*
X236498D01*
G01X243273D02*
X245947D01*
G01X238548D02*
X236498D01*
G01X241223Y1528106D02*
X243774Y1528853D01*
G01X236498Y1528106D02*
X239049Y1528853D01*
G01X231774Y1528106D02*
X234325Y1528853D01*
G01X245947Y1528106D02*
X248498Y1528853D01*
G01X243774D02*
X245947Y1528106D01*
G01X239049Y1528853D02*
X241223Y1528106D01*
G01X234325Y1528853D02*
X236498Y1528106D01*
G01X247947Y1521453D02*
X245947Y1522200D01*
G01X235110Y1540477D02*
X236291Y1538431D01*
G01X235498Y1542641D02*
Y1540865D01*
X235110Y1540477D01*
G01X239835D02*
X240223Y1540865D01*
Y1542641D01*
G01X241016Y1538431D02*
X239835Y1540477D01*
G01X244559D02*
X245740Y1538431D01*
G01X244947Y1542641D02*
Y1540865D01*
X244559Y1540477D01*
G01X257993Y127456D02*
Y123246D01*
X262486Y118753D01*
Y115319D01*
X262490Y115315D01*
G01X260521D02*
Y117925D01*
X254478Y123968D01*
X254297D01*
G01X250297D02*
X254297D01*
G01X246297D02*
X250297D01*
G01X280001Y570398D02*
X280523Y569876D01*
Y568461D01*
X273574Y561512D01*
X246314D01*
G01X258732Y1509459D02*
X259120Y1509071D01*
Y1507295D01*
G01X249283Y1509459D02*
Y1507683D01*
X249671Y1507295D01*
G01X254008Y1509459D02*
Y1507683D01*
X254396Y1507295D01*
G01X261082Y1524532D02*
X260121Y1523571D01*
Y1522200D01*
G01X255189Y1511505D02*
X255396Y1514243D01*
G01X248277D02*
X250672D01*
G01X255396D02*
X253002D01*
G01X255396D02*
X257726D01*
G01X245947D02*
X248277D01*
G01X250672D02*
X250465Y1511505D01*
G01X250672Y1514243D02*
X253002D01*
G01X259913Y1511505D02*
X258732Y1509459D01*
G01X259913Y1511505D02*
X260242Y1511834D01*
Y1514243D01*
G01D02*
X257726D01*
G01X261082Y1515083D02*
X260242Y1514243D01*
G01X260121Y1522200D02*
X257396Y1521453D01*
G01X255396Y1522200D02*
X252672Y1521453D01*
G01X250672Y1522200D02*
X247947Y1521453D01*
G01X260121Y1522200D02*
X262141Y1521453D01*
G01X257396D02*
X255396Y1522200D01*
G01X252672Y1521453D02*
X250672Y1522200D01*
G01X250465Y1511505D02*
X249283Y1510323D01*
Y1509459D01*
G01X254008D02*
Y1510324D01*
X255189Y1511505D01*
G01Y1538431D02*
X255396Y1536063D01*
G01X259913Y1538431D02*
X260121Y1536063D01*
G01X250465Y1538431D02*
X250672Y1536063D01*
G01X255396D02*
X252722D01*
G01X260121D02*
X257446D01*
G01X250672D02*
X247997D01*
G01X260121D02*
X262777D01*
G01X252722D02*
X250672D01*
G01X257446D02*
X255396D01*
G01X247997D02*
X245947D01*
G01X255396Y1528106D02*
X257947Y1528853D01*
G01X250672Y1528106D02*
X253223Y1528853D01*
G01X257947D02*
X261082Y1526894D01*
G01X253223Y1528853D02*
X255396Y1528106D01*
G01X248498Y1528853D02*
X250672Y1528106D01*
G01X254008Y1540477D02*
X255189Y1538431D01*
G01X254396Y1542641D02*
Y1540865D01*
X254008Y1540477D01*
G01X258732D02*
X259913Y1538431D01*
G01X259120Y1542641D02*
Y1540865D01*
X258732Y1540477D01*
G01X249283D02*
X250465Y1538431D01*
G01X249671Y1542641D02*
Y1540865D01*
X249283Y1540477D01*
G01X275031Y74536D02*
X276312Y75817D01*
Y77530D01*
X275381Y78461D01*
G01D02*
X276188Y79268D01*
Y82074D01*
X275238Y83024D01*
G01X270364Y115315D02*
Y118415D01*
G01X272361Y120243D02*
X272450Y120154D01*
Y115432D01*
X272333Y115315D01*
G01X283716Y570398D02*
X282700Y569382D01*
Y567700D01*
X274512Y559512D01*
X265210D01*
G01X274201Y579479D02*
Y579478D01*
G01X276801Y578503D02*
X275177D01*
X274201Y579479D01*
G01D02*
X273069Y580611D01*
Y581995D01*
G01X269405Y581960D02*
X267419D01*
X266601Y582778D01*
Y586578D01*
G01X269405Y581960D02*
X269440Y581995D01*
X273069D01*
G01X276851Y570398D02*
X274096Y573153D01*
Y574698D01*
G01X267601Y608378D02*
X268312Y607667D01*
Y605247D01*
G01X266193Y647524D02*
X269061D01*
G01X269463Y1336447D02*
X266595D01*
G01X265421Y1507355D02*
Y1509061D01*
X265819Y1509459D01*
G01X263457D02*
X263321Y1509323D01*
Y1507355D01*
G01X263128Y1513902D02*
X262263D01*
X261082Y1515083D01*
G01X263128Y1516264D02*
Y1513902D01*
G01X261082Y1515083D02*
Y1516580D01*
X263128Y1518626D01*
G01X262141Y1521453D02*
X263128Y1518626D01*
G01X263457Y1509459D02*
X264638Y1511505D01*
G01X265173Y1524532D02*
X264535Y1523894D01*
X261720D01*
X261082Y1524532D01*
G01X263128Y1528075D02*
X261947Y1529256D01*
X261082D01*
G01Y1526894D02*
X261947D01*
X263128Y1528075D01*
G01X261082Y1524532D02*
Y1526894D01*
G01X268380Y1551550D02*
Y1550322D01*
X270139Y1548563D01*
G01D02*
X270829Y1549253D01*
Y1551499D01*
X271580Y1552250D01*
G01X264638Y1538431D02*
Y1539296D01*
X263457Y1540477D01*
G01X266538Y1538658D02*
X266311Y1538431D01*
X264638D01*
G01X261530Y1550300D02*
Y1553220D01*
G01X278881Y74536D02*
X277812Y75605D01*
Y77742D01*
X278531Y78461D01*
G01D02*
X277688Y79304D01*
Y82074D01*
X278638Y83024D01*
G01X289206Y160315D02*
Y164404D01*
X297671Y172869D01*
Y222512D01*
X306293Y231134D01*
X310047D01*
X310339Y231426D01*
G01X286876Y585177D02*
X286866Y585167D01*
Y581298D01*
G01D02*
Y577698D01*
G01X283716D02*
Y581298D01*
G01Y577698D02*
Y574022D01*
G01D02*
Y570398D01*
G01X279976Y585178D02*
X279885Y585087D01*
Y576778D01*
X280566Y576097D01*
Y574022D01*
G01D02*
Y570963D01*
X280001Y570398D01*
G01X289421Y575098D02*
Y572953D01*
X286866Y570398D01*
G01X283726Y585179D02*
X283725Y585178D01*
X279976D01*
G01X285650Y1505000D02*
X287495D01*
X288575Y1506080D01*
G01X280450Y1503100D02*
Y1500253D01*
X280621Y1500082D01*
G01X283000Y1523850D02*
X286200D01*
G01D02*
Y1525350D01*
X284800Y1526750D01*
G01X291765Y157756D02*
X292695D01*
X293596Y158657D01*
Y166368D01*
X299356Y172128D01*
Y222041D01*
X306360Y229045D01*
X309570D01*
X310339Y228276D01*
G01X301791Y681765D02*
X298923D01*
G01X302359Y1336419D02*
X299491D01*
G01X299450Y1518040D02*
X301550D01*
G01X299450Y1514420D02*
X301550D01*
G01X299450Y1510800D02*
X301550D01*
G01X299495Y1521331D02*
Y1518085D01*
X299450Y1518040D01*
G01X299495Y1528731D02*
X302042D01*
G01X307519Y1529256D02*
X305641Y1528725D01*
G01X307519Y1524532D02*
X305641Y1523810D01*
G01X296207Y1532851D02*
Y1531761D01*
X295042Y1530596D01*
G01X307199Y1550788D02*
X303999D01*
G01D02*
Y1546940D01*
X304606Y1546333D01*
G01X314264Y227851D02*
Y228076D01*
X313607Y228733D01*
X310796D01*
X310339Y228276D01*
G01X314264Y231851D02*
Y231849D01*
X313455Y231040D01*
X310725D01*
X310339Y231426D01*
G01X315928Y1509459D02*
Y1507683D01*
X316316Y1507295D01*
G01X311204Y1509459D02*
Y1507709D01*
X311009Y1507514D01*
G01X307660Y1511505D02*
X306694Y1510539D01*
Y1507279D01*
G01X312592Y1514243D02*
X314922D01*
G01X311610Y1519807D02*
Y1517445D01*
G01X313750Y1519195D02*
X313138Y1519807D01*
X311610D01*
G01X317316Y1514243D02*
X317109Y1511505D01*
G01X314922Y1514243D02*
X317316D01*
G01X319646D02*
X317316D01*
G01X319646D02*
X322041D01*
G01X311610Y1519807D02*
Y1522169D01*
G01Y1517445D02*
Y1515225D01*
X312592Y1514243D01*
G01X312385Y1511505D02*
X312592Y1511712D01*
Y1514243D01*
G01X311610Y1522169D02*
Y1524532D01*
G01X322041Y1522200D02*
X319316Y1521453D01*
G01X311610Y1522169D02*
X314592Y1521453D01*
G01X319316D02*
X317316Y1522200D01*
G01X314592Y1521453D02*
X317316Y1522200D01*
G01X315928Y1509459D02*
Y1510324D01*
X317109Y1511505D01*
G01X311204Y1509459D02*
Y1510324D01*
X312385Y1511505D01*
G01X310023D02*
X307660D01*
G01X308842Y1509459D02*
Y1508311D01*
X308893Y1508260D01*
Y1507460D01*
G01X311610Y1536343D02*
Y1533980D01*
G01X317316Y1536063D02*
X317109Y1538431D01*
G01X311610Y1536343D02*
Y1537656D01*
X312385Y1538431D01*
G01X311610Y1533980D02*
Y1531618D01*
G01X309565Y1528075D02*
X308350Y1528995D01*
X307519Y1529256D01*
G01X309565Y1523351D02*
X310746Y1524532D01*
X311610D01*
G01X307519D02*
X309565Y1523351D01*
G01X312592Y1527880D02*
X311610Y1526898D01*
Y1524532D01*
G01X312592Y1527880D02*
X311610Y1528862D01*
G01D02*
X310352D01*
X309565Y1528075D01*
G01X311610Y1531618D02*
Y1528862D01*
G01X317316Y1536063D02*
X319366D01*
G01X311610Y1536343D02*
X314641D01*
Y1536063D01*
G01X319366D02*
X322041D01*
G01X314641D02*
X317316D01*
G01X322041Y1528106D02*
X319867Y1528853D01*
G01X312592Y1527880D02*
X315143Y1528853D01*
G01X319867D02*
X317316Y1528106D01*
G01X315143Y1528853D02*
X317316Y1528106D01*
G01X312385Y1538431D02*
X311204Y1540477D01*
G01X315928D02*
X316316Y1540865D01*
Y1542641D01*
G01X317109Y1538431D02*
X315928Y1540477D01*
G01X311113Y1542425D02*
Y1540568D01*
X311204Y1540477D01*
G01X310023Y1538431D02*
X308842Y1540477D01*
G01X307042Y1540317D02*
Y1539755D01*
X307660Y1539137D01*
Y1538431D01*
G01X308842Y1540477D02*
Y1542856D01*
X310611Y1544625D01*
X311113D01*
G01X311476Y1554939D02*
Y1552567D01*
G01X334561Y701915D02*
X331693D01*
G01X335263Y1336362D02*
X332395D01*
G01X325377Y1509459D02*
Y1507683D01*
X325765Y1507295D01*
G01X320653Y1509459D02*
Y1507683D01*
X321041Y1507295D01*
G01X322041Y1514243D02*
X321834Y1511505D01*
G01X324371Y1514243D02*
X322041D01*
G01X326765D02*
X326558Y1511505D01*
G01X324371Y1514243D02*
X326765D01*
G01X329095D02*
X326765D01*
G01X331490D02*
X331283Y1511505D01*
G01X329095Y1514243D02*
X331490D01*
G01X333820D02*
X331490D01*
G01X333820D02*
X336214D01*
G01Y1522200D02*
X333489Y1521453D01*
G01X331490Y1522200D02*
X328765Y1521453D01*
G01X326765Y1522200D02*
X324041Y1521453D01*
G01X333489D02*
X331490Y1522200D01*
G01X328765Y1521453D02*
X326765Y1522200D01*
G01X324041Y1521453D02*
X322041Y1522200D01*
G01X320653Y1509459D02*
Y1510324D01*
X321834Y1511505D01*
G01X325377Y1509459D02*
Y1510324D01*
X326558Y1511505D01*
G01X321834Y1538431D02*
X322041Y1536063D01*
G01X326558Y1538431D02*
X326765Y1536063D01*
G01X331283Y1538431D02*
X331490Y1536063D01*
G01X322041D02*
X324091D01*
G01X326765D02*
X328815D01*
G01X331490D02*
X333540D01*
G01X324091D02*
X326765D01*
G01X328815D02*
X331490D01*
G01X333540D02*
X336214D01*
G01Y1528106D02*
X334040Y1528853D01*
G01X326765Y1528106D02*
X329316Y1528853D01*
G01X326765Y1528106D02*
X324592Y1528853D01*
G01X334040D02*
X331490Y1528106D01*
G01X329316Y1528853D02*
X331490Y1528106D01*
G01X324592Y1528853D02*
X322041Y1528106D01*
G01X321041Y1542641D02*
Y1540865D01*
X320653Y1540477D01*
G01X325765Y1542641D02*
Y1540865D01*
X325377Y1540477D01*
G01X330489Y1542641D02*
Y1540865D01*
X330101Y1540477D01*
G01X320653D02*
X321834Y1538431D01*
G01X325377Y1540477D02*
X326558Y1538431D01*
G01X330101Y1540477D02*
X331283Y1538431D01*
G01X334826Y1540477D02*
X335214Y1540865D01*
Y1542641D01*
G01X336007Y1538431D02*
X334826Y1540477D01*
G01X343141Y225070D02*
Y223624D01*
X344106Y222659D01*
G01X346245Y229180D02*
X348645D01*
G01X348999Y1509459D02*
Y1507683D01*
X349387Y1507295D01*
G01X344275Y1509459D02*
Y1507683D01*
X344663Y1507295D01*
G01X339550Y1509459D02*
Y1507683D01*
X339938Y1507295D01*
G01X336214Y1514243D02*
X336007Y1511505D01*
G01X338544Y1514243D02*
X336214D01*
G01X340938D02*
X340731Y1511505D01*
G01X338544Y1514243D02*
X340938D01*
G01X343268D02*
X340938D01*
G01X345663D02*
X345456Y1511505D01*
G01X343268Y1514243D02*
X345663D01*
G01X347993D02*
X345663D01*
G01X350387D02*
X350180Y1511505D01*
G01X347993Y1514243D02*
X350387D01*
G01Y1522200D02*
X347663Y1521453D01*
G01X345663Y1522200D02*
X342938Y1521453D01*
G01X336214Y1522200D02*
X338214Y1521453D01*
G01X347663D02*
X345663Y1522200D01*
G01X342938Y1521453D02*
X340938Y1522200D01*
G01X338214Y1521453D02*
X340938Y1522200D01*
G01X348999Y1509459D02*
Y1510324D01*
X350180Y1511505D01*
G01X344275Y1509459D02*
Y1510324D01*
X345456Y1511505D01*
G01X339550Y1509459D02*
Y1510324D01*
X340731Y1511505D01*
G01X336214Y1536063D02*
X336007Y1538431D01*
G01X340731D02*
X340938Y1536063D01*
G01X345456Y1538431D02*
X345663Y1536063D01*
G01X336214D02*
X338264D01*
G01X340938D02*
X342988D01*
G01X345663D02*
X347713D01*
G01X338264D02*
X340938D01*
G01X342988D02*
X345663D01*
G01X347713D02*
X350387D01*
G01Y1528106D02*
X348214Y1528853D01*
G01X345663Y1528106D02*
X343489Y1528853D01*
G01X340938Y1528106D02*
X338765Y1528853D01*
G01X348214D02*
X345663Y1528106D01*
G01X343489Y1528853D02*
X340938Y1528106D01*
G01X338765Y1528853D02*
X336214Y1528106D01*
G01X352387Y1521453D02*
X350387Y1522200D01*
G01X339938Y1542641D02*
Y1540865D01*
X339550Y1540477D01*
G01X344663Y1542641D02*
Y1540865D01*
X344275Y1540477D01*
G01X350387Y1536063D02*
X350180Y1538431D01*
G01X339550Y1540477D02*
X340731Y1538431D01*
G01X344275Y1540477D02*
X345456Y1538431D01*
G01X348999Y1540477D02*
X349387Y1540865D01*
Y1542641D01*
G01X350180Y1538431D02*
X348999Y1540477D01*
G01X367621Y701647D02*
X364753D01*
G01X363172Y1509459D02*
Y1507683D01*
X363560Y1507295D01*
G01X358448Y1509459D02*
Y1507683D01*
X358836Y1507295D01*
G01X353723Y1509459D02*
Y1507683D01*
X354111Y1507295D01*
G01X352717Y1514243D02*
X350387D01*
G01X355112D02*
X354905Y1511505D01*
G01X352717Y1514243D02*
X355112D01*
G01X357442D02*
X355112D01*
G01X359836D02*
X359629Y1511505D01*
G01X357442Y1514243D02*
X359836D01*
G01X362166D02*
X359836D01*
G01X364560D02*
X364353Y1511505D01*
G01X362166Y1514243D02*
X364560D01*
G01X366890D02*
X364560D01*
G01X359836Y1522200D02*
X361836Y1521453D01*
G01X359836Y1522200D02*
X357111Y1521453D01*
G01X355112Y1522200D02*
X352387Y1521453D01*
G01X361836D02*
X364560Y1522200D01*
G01X357111Y1521453D02*
X355112Y1522200D01*
G01X366560Y1521453D02*
X364560Y1522200D01*
G01X363172Y1509459D02*
Y1510324D01*
X364353Y1511505D01*
G01X358448Y1509459D02*
Y1510324D01*
X359629Y1511505D01*
G01X354905D02*
X353723Y1510323D01*
Y1509459D01*
G01X354905Y1538431D02*
X355112Y1536063D01*
G01X359629Y1538431D02*
X359836Y1536063D01*
G01X364353Y1538431D02*
X364560Y1536063D01*
G01X350387D02*
X352437D01*
G01X355112D02*
X357162D01*
G01X359836D02*
X361886D01*
G01X364560D02*
X366610D01*
G01X352437D02*
X355112D01*
G01X357162D02*
X359836D01*
G01X361886D02*
X364560D01*
G01Y1528106D02*
X362387Y1528853D01*
G01X359836Y1528106D02*
X357662Y1528853D01*
G01X355112Y1528106D02*
X352938Y1528853D01*
G01X362387D02*
X359836Y1528106D01*
G01X357662Y1528853D02*
X355112Y1528106D01*
G01X352938Y1528853D02*
X350387Y1528106D01*
G01X367111Y1528853D02*
X364560Y1528106D01*
G01X354111Y1542641D02*
Y1540865D01*
X353723Y1540477D01*
G01X358836Y1542641D02*
Y1540865D01*
X358448Y1540477D01*
G01X363560Y1542641D02*
Y1540865D01*
X363172Y1540477D01*
G01X353723D02*
X354905Y1538431D01*
G01X358448Y1540477D02*
X359629Y1538431D01*
G01X363172Y1540477D02*
X364353Y1538431D01*
G01X377130Y239615D02*
X380012D01*
G01X368063Y1336562D02*
X365195D01*
G01X372621Y1509459D02*
Y1507683D01*
X373009Y1507295D01*
G01X367897Y1509459D02*
Y1507683D01*
X368285Y1507295D01*
G01X377345Y1509459D02*
Y1507683D01*
X377733Y1507295D01*
G01X369285Y1514243D02*
X369078Y1511505D01*
G01X366890Y1514243D02*
X369285D01*
G01X371615D02*
X369285D01*
G01X374009D02*
X373802Y1511505D01*
G01X376339Y1514243D02*
X374009D01*
G01D02*
X371615D01*
G01X378734D02*
X378527Y1511505D01*
G01X376339Y1514243D02*
X378734D01*
G01X381064D02*
X378734D01*
G01X374009Y1522200D02*
X376009Y1521453D01*
G01X378734Y1522200D02*
X380734Y1521453D01*
G01X369285Y1522200D02*
X366560Y1521453D01*
G01X374009Y1522200D02*
X371285Y1521453D01*
G01X376009D02*
X378734Y1522200D01*
G01X371285Y1521453D02*
X369285Y1522200D01*
G01X372621Y1509459D02*
Y1510324D01*
X373802Y1511505D01*
G01X367897Y1509459D02*
Y1510324D01*
X369078Y1511505D01*
G01X378527D02*
X377345Y1510323D01*
Y1509459D01*
G01X369078Y1538431D02*
X369285Y1536063D01*
G01X373802Y1538431D02*
X374009Y1536063D01*
G01X378527Y1538431D02*
X378734Y1536063D01*
G01X369285D02*
X371335D01*
G01X374009D02*
X376059D01*
G01X378734D02*
X380784D01*
G01X366610D02*
X369285D01*
G01X371335D02*
X374009D01*
G01X376059D02*
X378734D01*
G01X374009Y1528106D02*
X376560Y1528853D01*
G01X369285Y1528106D02*
X367111Y1528853D01*
G01X374009Y1528106D02*
X371836Y1528853D01*
G01X378734Y1528106D02*
X381285Y1528853D01*
G01X376560D02*
X378734Y1528106D01*
G01X371836Y1528853D02*
X369285Y1528106D01*
G01X368285Y1542641D02*
Y1540865D01*
X367897Y1540477D01*
G01X373009Y1542641D02*
Y1540865D01*
X372621Y1540477D01*
G01X377733Y1542641D02*
Y1540865D01*
X377345Y1540477D01*
G01X367897D02*
X369078Y1538431D01*
G01X372621Y1540477D02*
X373802Y1538431D01*
G01X377345Y1540477D02*
X378527Y1538431D01*
G01X371850Y1579400D02*
Y1582600D01*
G01D02*
X374432D01*
G01X370850Y1639400D02*
Y1640296D01*
X372313Y1641759D01*
G01X399796Y555915D02*
X398719D01*
X395171Y559463D01*
G01X390732Y565915D02*
X396796D01*
X397085Y566204D01*
G01X383889Y1055710D02*
X382051Y1056757D01*
G01X386794Y1509459D02*
X387182Y1509071D01*
Y1507295D01*
G01X382070Y1509459D02*
Y1507683D01*
X382458Y1507295D01*
G01X391519Y1509459D02*
X391383Y1509323D01*
Y1507355D01*
G01X393483D02*
Y1509061D01*
X393881Y1509459D01*
G01X391190Y1516264D02*
Y1513902D01*
G01X383458Y1514243D02*
X383251Y1511505D01*
G01X385788Y1514243D02*
X383458D01*
G01D02*
X381064D01*
G01X385788D02*
X388304D01*
G01D02*
Y1511834D01*
X387975Y1511505D01*
G01D02*
X386794Y1509459D01*
G01X389144Y1515083D02*
X388304Y1514243D01*
G01X389144Y1524532D02*
X388183Y1523571D01*
Y1522200D01*
G01X391190Y1513902D02*
X390325D01*
X389144Y1515083D01*
G01D02*
Y1516580D01*
X391190Y1518626D01*
G01X388183Y1522200D02*
X390203Y1521453D01*
G01X388183Y1522200D02*
X385458Y1521453D01*
G01X380734D02*
X383458Y1522200D01*
G01X390203Y1521453D02*
X391190Y1518626D01*
G01X385458Y1521453D02*
X383458Y1522200D01*
G01X382070Y1509459D02*
Y1510324D01*
X383251Y1511505D01*
G01X391519Y1509459D02*
X392700Y1511505D01*
G01X383251Y1538431D02*
X383458Y1536063D01*
G01X387975Y1538431D02*
X388183Y1536063D01*
G01X389144Y1526894D02*
X390009D01*
X391190Y1528075D01*
G01D02*
X390009Y1529256D01*
X389144D01*
G01Y1524532D02*
Y1526894D01*
G01X393235Y1524532D02*
X392597Y1523894D01*
X389782D01*
X389144Y1524532D01*
G01X383458Y1536063D02*
X385508D01*
G01X388183D02*
X390839D01*
G01X380784D02*
X383458D01*
G01X385508D02*
X388183D01*
G01X389144Y1526894D02*
X386009Y1528853D01*
G01X381285D02*
X383458Y1528106D01*
G01X386009Y1528853D02*
X383458Y1528106D01*
G01X382458Y1542641D02*
Y1540865D01*
X382070Y1540477D01*
G01X387182Y1542641D02*
Y1540865D01*
X386794Y1540477D01*
G01X382070D02*
X383251Y1538431D01*
G01X386794Y1540477D02*
X387975Y1538431D01*
G01X390082Y1551550D02*
Y1549178D01*
G01X392700Y1538431D02*
Y1539296D01*
X391519Y1540477D01*
G01X394600Y1538658D02*
X394373Y1538431D01*
X392700D01*
G01X406243Y110851D02*
X405718Y110326D01*
X403734D01*
G01X406243Y118451D02*
X405718Y118976D01*
X403734D01*
G01X409443Y131701D02*
X410493Y132751D01*
X411952D01*
G01X409443Y124101D02*
X410493Y123051D01*
X411952D01*
G01X399796Y555915D02*
Y551915D01*
G01X397085Y566204D02*
Y564872D01*
X395669Y563456D01*
Y563328D01*
G01X397101Y566188D02*
X397085Y566204D01*
G01X395669Y563328D02*
X397582Y561415D01*
X399796D01*
G01X400661Y701715D02*
X397793D01*
G01X400645Y1355893D02*
X397777D01*
G01X401583Y1504872D02*
X403355Y1503100D01*
X404312D01*
G01X409150Y1538000D02*
Y1536638D01*
X410108Y1535680D01*
G01X399642Y1551550D02*
X398891Y1550799D01*
Y1549253D01*
X398201Y1548563D01*
G01X396442Y1551550D02*
Y1550322D01*
X398201Y1548563D01*
G01X408943Y1605835D02*
X408325D01*
X406697Y1604207D01*
G01X408943Y1613709D02*
X406481D01*
X406343Y1613847D01*
G01X426767Y111212D02*
X424457D01*
X424084Y110839D01*
G01X410477Y873246D02*
X410464Y877482D01*
G01X421567D02*
X421579Y873246D01*
G01X423417Y880671D02*
X427130Y882813D01*
G01X413712Y1505000D02*
X414577D01*
X415862Y1503715D01*
G01X411062Y1523850D02*
X414262D01*
G01D02*
Y1524437D01*
X413616Y1525996D01*
X412862Y1526750D01*
G01X426850Y1557096D02*
X421927D01*
X421294Y1557729D01*
G01X419277Y1603375D02*
Y1600725D01*
G01X425000Y1626900D02*
X423214Y1625114D01*
G01D02*
Y1622075D01*
G01X433661Y683915D02*
X430793D01*
G01X434326Y1285694D02*
X434234Y1285602D01*
Y1283710D01*
X435580Y1282364D01*
Y1279986D01*
G01X431176Y1289694D02*
X427676D01*
X427251Y1289269D01*
G01X436903Y1285694D02*
X434326D01*
G01Y1289694D02*
X436903D01*
G01X435561Y1514420D02*
X437661D01*
G01X435561Y1510800D02*
X437661D01*
G01X435606Y1521331D02*
Y1518085D01*
X435561Y1518040D01*
G01D02*
X437661D01*
G01X435606Y1528731D02*
X438153D01*
G01X440610Y1550788D02*
Y1548855D01*
X438732Y1546977D01*
G01X429963Y1557147D02*
X426901D01*
X426850Y1557096D01*
G01X429963Y1557147D02*
X432176D01*
X434619Y1559590D01*
Y1561199D01*
X436658Y1563238D01*
Y1563907D01*
G01X427643Y1605835D02*
X430500D01*
G01X427643Y1613709D02*
X430500D01*
G01X447315Y1509459D02*
Y1507707D01*
X447120Y1507512D01*
G01X452039Y1509459D02*
Y1507683D01*
X452427Y1507295D01*
G01X447721Y1522169D02*
Y1524532D01*
G01Y1519807D02*
Y1522169D01*
G01Y1519807D02*
Y1517445D01*
G01D02*
Y1515225D01*
X448703Y1514243D01*
G01X448496Y1511505D02*
X448703Y1511712D01*
Y1514243D01*
G01D02*
X451033D01*
G01D02*
X453427D01*
G01D02*
X453220Y1511505D01*
G01X453427Y1514243D02*
X455757D01*
G01X449861Y1519195D02*
X449249Y1519807D01*
X447721D01*
G01X453427Y1522200D02*
X450703Y1521453D01*
G01D02*
X447721Y1522169D01*
G01X455427Y1521453D02*
X453427Y1522200D01*
G01X452039Y1509459D02*
Y1510324D01*
X453220Y1511505D01*
G01X447315Y1509459D02*
Y1510324D01*
X448496Y1511505D01*
G01X446134D02*
X443771D01*
G01X444953Y1507509D02*
Y1509459D01*
G01X443771Y1511505D02*
X442753Y1510487D01*
Y1507509D01*
G01X453427Y1536063D02*
X453220Y1538431D01*
G01X447721Y1536343D02*
Y1533980D01*
G01D02*
Y1531618D01*
G01X448703Y1527880D02*
X447721Y1528862D01*
G01X448703Y1527880D02*
X447721Y1526898D01*
Y1524532D01*
G01X445676Y1523351D02*
X446857Y1524532D01*
X447721D01*
G01X443630D02*
X445676Y1523351D01*
G01X443630Y1524532D02*
X441752Y1523810D01*
G01X447721Y1531618D02*
Y1528862D01*
G01X445676Y1528075D02*
X444461Y1528995D01*
X443630Y1529256D01*
G01D02*
X441752Y1528725D01*
G01X447721Y1536343D02*
Y1537656D01*
X448496Y1538431D01*
G01X447721Y1528862D02*
X446463D01*
X445676Y1528075D01*
G01X453427Y1536063D02*
X450752D01*
G01D02*
Y1536343D01*
X447721D01*
G01X455477Y1536063D02*
X453427D01*
G01Y1528106D02*
X451254Y1528853D01*
G01D02*
X448703Y1527880D01*
G01X455978Y1528853D02*
X453427Y1528106D01*
G01X453220Y1538431D02*
X452039Y1540477D01*
G01D02*
X452427Y1540865D01*
Y1542641D01*
G01X448496Y1538431D02*
X447315Y1540477D01*
G01X447224Y1542425D02*
Y1540568D01*
X447315Y1540477D01*
G01X443810Y1550788D02*
X440610D01*
G01X446134Y1538431D02*
X444953Y1540477D01*
G01X443153Y1540317D02*
Y1539755D01*
X443771Y1539137D01*
Y1538431D01*
G01X447224Y1544625D02*
X446600D01*
X444953Y1542978D01*
Y1540477D01*
G01X449597Y1554939D02*
Y1554577D01*
X447587Y1552567D01*
G01X465699Y285485D02*
Y282833D01*
G01X468540Y293270D02*
X472521Y297251D01*
X474464D01*
G01X465699Y288635D02*
Y290429D01*
X468540Y293270D01*
G01X463193Y659315D02*
X466061D01*
G01X461488Y1509459D02*
Y1507683D01*
X461876Y1507295D01*
G01X456764Y1509459D02*
Y1507683D01*
X457152Y1507295D01*
G01X458152Y1514243D02*
X455757D01*
G01X458152D02*
X457945Y1511505D01*
G01X460482Y1514243D02*
X458152D01*
G01X462876D02*
X460482D01*
G01X462669Y1511505D02*
X462876Y1514243D01*
G01X465206D02*
X462876D01*
G01X467601D02*
X465206D01*
G01X467601D02*
X467394Y1511505D01*
G01X469931Y1514243D02*
X467601D01*
G01X472325Y1522200D02*
X469600Y1521453D01*
G01X467601Y1522200D02*
X464876Y1521453D01*
G01X462876Y1522200D02*
X460152Y1521453D01*
G01X458152Y1522200D02*
X455427Y1521453D01*
G01X469600D02*
X467601Y1522200D01*
G01X464876Y1521453D02*
X462876Y1522200D01*
G01X460152Y1521453D02*
X458152Y1522200D01*
G01X456764Y1509459D02*
Y1510324D01*
X457945Y1511505D01*
G01X461488Y1509459D02*
Y1510324D01*
X462669Y1511505D01*
G01X467601Y1536063D02*
X467394Y1538431D01*
G01X458152Y1536063D02*
X457945Y1538431D01*
G01X462669D02*
X462876Y1536063D01*
G01X467601D02*
X464926D01*
G01X462876D02*
X460202D01*
G01X458152D02*
X455477D01*
G01X469651D02*
X467601D01*
G01X464926D02*
X462876D01*
G01X460202D02*
X458152D01*
G01X467601Y1528106D02*
X465427Y1528853D01*
G01X462876Y1528106D02*
X460703Y1528853D01*
G01X458152Y1528106D02*
X455978Y1528853D01*
G01X470151D02*
X467601Y1528106D01*
G01X465427Y1528853D02*
X462876Y1528106D01*
G01X460703Y1528853D02*
X458152Y1528106D01*
G01X467394Y1538431D02*
X466212Y1540477D01*
G01D02*
X466600Y1540865D01*
Y1542641D01*
G01X457945Y1538431D02*
X456764Y1540477D01*
G01D02*
X457152Y1540865D01*
Y1542641D01*
G01X461488Y1540477D02*
X462669Y1538431D01*
G01X461876Y1542641D02*
Y1540865D01*
X461488Y1540477D01*
G01X463950Y1579400D02*
Y1579775D01*
X462215Y1581510D01*
G01X463950Y1576200D02*
Y1579400D01*
G01X481161Y214077D02*
Y211545D01*
X480715Y211099D01*
G01X514298Y280721D02*
Y278258D01*
X512867Y276827D01*
X485451D01*
X481420Y280858D01*
X476503D01*
G01D02*
Y284738D01*
G01X473353D02*
Y288569D01*
G01Y280858D02*
Y284738D01*
G01X474808Y291492D02*
X476826Y293510D01*
G01X473353Y288569D02*
Y290037D01*
X474808Y291492D01*
G01X482893Y291293D02*
X483375Y290811D01*
Y288469D01*
G01X482893Y291293D02*
Y294626D01*
X482237Y295282D01*
X481550D01*
G01X488544Y291949D02*
X488030D01*
X486116Y293863D01*
Y296788D01*
X483685Y299219D01*
X481156D01*
G01X480386Y1509459D02*
Y1507683D01*
X480774Y1507295D01*
G01X475661Y1509459D02*
Y1507683D01*
X476049Y1507295D01*
G01X469931Y1514243D02*
X472325D01*
G01D02*
X472118Y1511505D01*
G01X472325Y1514243D02*
X474655D01*
G01D02*
X477049D01*
G01X476842Y1511505D02*
X477049Y1514243D01*
G01X479379D02*
X477049D01*
G01X479379D02*
X481774D01*
G01D02*
X484104D01*
G01D02*
X486498D01*
G01X481567Y1511505D02*
X481774Y1514243D01*
G01X486498Y1522200D02*
X483774Y1521453D01*
G01X481774Y1522200D02*
X479049Y1521453D01*
G01X477049Y1522200D02*
X474325Y1521453D01*
G01X483774D02*
X481774Y1522200D01*
G01X479049Y1521453D02*
X477049Y1522200D01*
G01X474325Y1521453D02*
X472325Y1522200D01*
G01X480386Y1509459D02*
Y1510324D01*
X481567Y1511505D01*
G01X475661Y1509459D02*
Y1510324D01*
X476842Y1511505D01*
G01Y1538431D02*
X477049Y1536063D01*
G01X472118Y1538431D02*
X472325Y1536063D01*
G01X481567Y1538431D02*
X481774Y1536063D01*
G01X472325D02*
X469651D01*
G01X486498D02*
X483824D01*
G01X481774D02*
X479099D01*
G01X477049D02*
X474375D01*
G01X483824D02*
X481774D01*
G01X479099D02*
X477049D01*
G01X474375D02*
X472325D01*
G01Y1528106D02*
X470151Y1528853D01*
G01X481774Y1528106D02*
X484325Y1528853D01*
G01X481774Y1528106D02*
X479600Y1528853D01*
G01X477049Y1528106D02*
X474876Y1528853D01*
G01X484325D02*
X486498Y1528106D01*
G01X479600Y1528853D02*
X477049Y1528106D01*
G01X474876Y1528853D02*
X472325Y1528106D01*
G01X475661Y1540477D02*
X476842Y1538431D01*
G01X476049Y1542641D02*
Y1540865D01*
X475661Y1540477D01*
G01X470937D02*
X472118Y1538431D01*
G01X471325Y1542641D02*
Y1540865D01*
X470937Y1540477D01*
G01X480386D02*
X481567Y1538431D01*
G01X480774Y1542641D02*
Y1540865D01*
X480386Y1540477D01*
G01X488544Y295099D02*
Y298622D01*
X488538Y298628D01*
G01X485040Y578572D02*
X488405D01*
G01X498661Y632815D02*
X495793D01*
G01X485110Y1509459D02*
Y1507683D01*
X485498Y1507295D01*
G01X494559Y1509459D02*
Y1507683D01*
X494947Y1507295D01*
G01X489834Y1509459D02*
Y1507683D01*
X490222Y1507295D01*
G01X486498Y1514243D02*
X486291Y1511505D01*
G01X488828Y1514243D02*
X486498D01*
G01X491223D02*
X488828D01*
G01X491016Y1511505D02*
X491223Y1514243D01*
G01X493553D02*
X491223D01*
G01X493553D02*
X495947D01*
G01D02*
X498277D01*
G01D02*
X500671D01*
G01X495740Y1511505D02*
X495947Y1514243D01*
G01X500671Y1522200D02*
X497947Y1521453D01*
G01X495947Y1522200D02*
X493222Y1521453D01*
G01X491223Y1522200D02*
X488498Y1521453D01*
G01X497947D02*
X495947Y1522200D01*
G01X493222Y1521453D02*
X491223Y1522200D01*
G01X488498Y1521453D02*
X486498Y1522200D01*
G01X485110Y1509459D02*
Y1510324D01*
X486291Y1511505D01*
G01X499283Y1509459D02*
Y1507683D01*
X499671Y1507295D01*
G01X499283Y1509459D02*
Y1510324D01*
X500464Y1511505D01*
G01X494559Y1509459D02*
Y1510324D01*
X495740Y1511505D01*
G01X491016D02*
X489834Y1510323D01*
Y1509459D01*
G01X495947Y1536063D02*
X495740Y1538431D01*
G01X486291D02*
X486498Y1536063D01*
G01X491016Y1538431D02*
X491223Y1536063D01*
G01X500671D02*
X497997D01*
G01X495947D02*
X493273D01*
G01X491223D02*
X488548D01*
G01X497997D02*
X495947D01*
G01X493273D02*
X491223D01*
G01X488548D02*
X486498D01*
G01X500671Y1528106D02*
X498498Y1528853D01*
G01X495947Y1528106D02*
X493773Y1528853D01*
G01X491223Y1528106D02*
X489049Y1528853D01*
G01X498498D02*
X495947Y1528106D01*
G01X493773Y1528853D02*
X491223Y1528106D01*
G01X489049Y1528853D02*
X486498Y1528106D01*
G01X495740Y1538431D02*
X494559Y1540477D01*
G01D02*
X494947Y1540865D01*
Y1542641D01*
G01X485110Y1540477D02*
X486291Y1538431D01*
G01X485498Y1542641D02*
Y1540865D01*
X485110Y1540477D01*
G01X489834D02*
X491016Y1538431D01*
G01X490222Y1542641D02*
Y1540865D01*
X489834Y1540477D01*
G01X499283D02*
X500464Y1538431D01*
G01X499671Y1542641D02*
Y1540865D01*
X499283Y1540477D01*
G01X511140Y109829D02*
Y107850D01*
X511670Y107320D01*
G01X508732Y1509459D02*
Y1507683D01*
X509120Y1507295D01*
G01X504008Y1509459D02*
Y1507683D01*
X504396Y1507295D01*
G01X513456Y1509459D02*
Y1507683D01*
X513844Y1507295D01*
G01X500671Y1514243D02*
X500464Y1511505D01*
G01X503001Y1514243D02*
X500671D01*
G01X505396D02*
X503001D01*
G01X505189Y1511505D02*
X505396Y1514243D01*
G01X507726D02*
X505396D01*
G01X510120D02*
X507726D01*
G01X509913Y1511505D02*
X510120Y1514243D01*
G01D02*
X512450D01*
G01D02*
X514845D01*
G01Y1522200D02*
X512120Y1521453D01*
G01X510120Y1522200D02*
X507396Y1521453D01*
G01X505396Y1522200D02*
X502671Y1521453D01*
G01X512120D02*
X510120Y1522200D01*
G01X507396Y1521453D02*
X505396Y1522200D01*
G01X502671Y1521453D02*
X500671Y1522200D01*
G01X508732Y1509459D02*
Y1510324D01*
X509913Y1511505D01*
G01X504008Y1509459D02*
Y1510324D01*
X505189Y1511505D01*
G01X514638D02*
X513456Y1510323D01*
Y1509459D01*
G01X500464Y1538431D02*
X500671Y1536063D01*
G01X505396D02*
X505189Y1538431D01*
G01X509913D02*
X510120Y1536063D01*
G01X514845D02*
X512170D01*
G01X510120D02*
X507446D01*
G01X505396D02*
X502721D01*
G01X512170D02*
X510120D01*
G01X507446D02*
X505396D01*
G01X502721D02*
X500671D01*
G01X514845Y1528106D02*
X512671Y1528853D01*
G01X510120Y1528106D02*
X507947Y1528853D01*
G01X505396Y1528106D02*
X503222Y1528853D01*
G01X512671D02*
X510120Y1528106D01*
G01X507947Y1528853D02*
X505396Y1528106D01*
G01X503222Y1528853D02*
X500671Y1528106D01*
G01X513456Y1540477D02*
X514638Y1538431D01*
G01X513844Y1542641D02*
Y1540865D01*
X513456Y1540477D01*
G01X505189Y1538431D02*
X504008Y1540477D01*
G01D02*
X504396Y1540865D01*
Y1542641D01*
G01X508732Y1540477D02*
X509913Y1538431D01*
G01X509120Y1542641D02*
Y1540865D01*
X508732Y1540477D01*
G01X520370Y107320D02*
X521420Y108370D01*
Y109829D01*
G01X529153Y598735D02*
X529173Y598715D01*
X531961D01*
G01X529235Y601543D02*
X529139Y601639D01*
Y601646D01*
X528040Y602745D01*
G01X525139Y600778D02*
Y601929D01*
X524231Y602837D01*
G01X555897Y662605D02*
X557694Y660808D01*
X561963D01*
X564523Y663368D01*
Y771726D01*
X517984Y818265D01*
Y844820D01*
X524530Y851366D01*
X525906D01*
X526474Y851934D01*
G01X555897Y657605D02*
X557600Y659308D01*
X562586D01*
X566023Y662745D01*
Y772349D01*
X519484Y818888D01*
Y844198D01*
X525043Y849757D01*
X526151D01*
X526474Y849434D01*
G01X522905Y1509459D02*
X523293Y1509071D01*
Y1507295D01*
G01X518181Y1509459D02*
Y1507683D01*
X518569Y1507295D01*
G01X527630Y1509459D02*
X527494Y1509323D01*
Y1507355D01*
G01X514845Y1514243D02*
X517175D01*
G01X519569D02*
X517175D01*
G01X519362Y1511505D02*
X519569Y1514243D01*
G01D02*
X521899D01*
G01X525255Y1515083D02*
X524415Y1514243D01*
G01X527301Y1513902D02*
X526436D01*
X525255Y1515083D01*
G01X527301Y1516264D02*
Y1513902D01*
G01X525255Y1515083D02*
Y1516580D01*
X527301Y1518626D01*
G01X525255Y1524532D02*
X524294Y1523571D01*
Y1522200D01*
G01X521899Y1514243D02*
X524415D01*
G01X524086Y1511505D02*
X522905Y1509459D01*
G01X514845Y1514243D02*
X514638Y1511505D01*
G01X524415Y1514243D02*
Y1511834D01*
X524086Y1511505D01*
G01X527301Y1518626D02*
X526314Y1521453D01*
G01X524294Y1522200D02*
X521569Y1521453D01*
G01X519569Y1522200D02*
X516845Y1521453D01*
G01X526314D02*
X524294Y1522200D01*
G01X521569Y1521453D02*
X519569Y1522200D01*
G01X516845Y1521453D02*
X514845Y1522200D01*
G01X518181Y1509459D02*
Y1510324D01*
X519362Y1511505D01*
G01X527630Y1509459D02*
X528811Y1511505D01*
G01X524086Y1538431D02*
X524294Y1536063D01*
G01X514638Y1538431D02*
X514845Y1536063D01*
G01X525255Y1524532D02*
Y1526894D01*
G01D02*
X526120D01*
X527301Y1528075D01*
G01D02*
X526120Y1529256D01*
X525255D01*
G01X529346Y1524532D02*
X528708Y1523894D01*
X525893D01*
X525255Y1524532D01*
G01X519362Y1538431D02*
X519569Y1536063D01*
G01X524294D02*
X521619D01*
G01X519569D02*
X516895D01*
G01X526950D02*
X524294D01*
G01X521619D02*
X519569D01*
G01X516895D02*
X514845D01*
G01X525255Y1526894D02*
X522120Y1528853D01*
G01X519569Y1528106D02*
X517396Y1528853D01*
G01X522120D02*
X519569Y1528106D01*
G01X517396Y1528853D02*
X514845Y1528106D01*
G01X522905Y1540477D02*
X524086Y1538431D01*
G01X523293Y1542641D02*
Y1540865D01*
X522905Y1540477D01*
G01X518181D02*
X519362Y1538431D01*
G01X518569Y1542641D02*
Y1540865D01*
X518181Y1540477D01*
G01X528811Y1538431D02*
Y1539296D01*
X527630Y1540477D01*
G01X530711Y1538658D02*
X529038D01*
X528811Y1538431D01*
G01X535855Y612290D02*
Y614696D01*
G01X533366Y610851D02*
X534468Y609749D01*
X535855D01*
G01X529594Y1507355D02*
Y1509061D01*
X529992Y1509459D01*
G01X552699Y294485D02*
Y291833D01*
G01X555755Y302485D02*
X552699Y299429D01*
Y297635D01*
G01X561464Y306251D02*
X559521D01*
X555755Y302485D01*
G01X549957Y658478D02*
X550697Y659218D01*
X554284D01*
X555897Y657605D01*
G01X547312Y663689D02*
Y663323D01*
X549157Y661478D01*
X549957D01*
G01D02*
X550717Y660718D01*
X554010D01*
X555897Y662605D01*
G01X547312Y659489D02*
X548146D01*
X549157Y658478D01*
X549957D01*
G01X544623Y1503100D02*
Y1500253D01*
X544794Y1500082D01*
G01X550438Y1503960D02*
X551168D01*
X552748Y1505540D01*
Y1506080D01*
G01X547173Y1523850D02*
X550373D01*
G01X550540Y1526910D02*
Y1526074D01*
X550660Y1525954D01*
Y1524137D01*
X550373Y1523850D01*
G01X565210Y122785D02*
Y125819D01*
G01X601298Y289721D02*
Y287258D01*
X599867Y285827D01*
X571671D01*
X567640Y289858D01*
X563503D01*
G01Y293738D02*
Y289858D01*
G01X560353Y297569D02*
Y293738D01*
G01Y297569D02*
Y299037D01*
X561808Y300492D01*
G01X560353Y293738D02*
Y289858D01*
G01X569893Y300293D02*
Y297951D01*
X570375Y297469D01*
G01X561808Y300492D02*
X563826Y302510D01*
G01X568550Y304282D02*
X569293D01*
X569893Y303682D01*
Y300293D01*
G01X575567Y301093D02*
X574732D01*
X573455Y302370D01*
Y305908D01*
X571144Y308219D01*
X568156D01*
G01X571448Y880671D02*
X572239D01*
X573286Y879624D01*
G01X569598Y877482D02*
X570645Y876435D01*
X571436D01*
G01X567748Y880671D02*
X568539D01*
X569586Y879624D01*
G01X570779Y1160946D02*
X571826Y1161993D01*
X572617D01*
G01X568929Y1157757D02*
X570767Y1158804D01*
X571019Y1159056D01*
X571618Y1159306D01*
X572718Y1159896D01*
X573954Y1160721D01*
X574659Y1161426D01*
Y1184884D01*
X623770Y1233995D01*
Y1283321D01*
X619073Y1288018D01*
X601497D01*
X595327Y1281848D01*
X590721D01*
X589161Y1283408D01*
Y1285698D01*
X590291Y1286828D01*
X593745D01*
X594991Y1285582D01*
G01Y1289582D02*
X593737Y1288328D01*
X589669D01*
X587661Y1286320D01*
Y1282786D01*
X590099Y1280348D01*
X595949D01*
X602119Y1286518D01*
X618451D01*
X622270Y1282699D01*
Y1234617D01*
X573159Y1185506D01*
Y1166216D01*
X572125Y1165182D01*
X570767D01*
G01X563623Y1510800D02*
X565723D01*
G01X563623Y1514420D02*
X565723D01*
G01X563668Y1521331D02*
Y1518085D01*
X563623Y1518040D01*
G01D02*
X565723D01*
G01X571833Y1511505D02*
X570815Y1510487D01*
Y1507509D01*
G01X574196Y1511505D02*
X571833D01*
G01X573015Y1509459D02*
Y1508311D01*
X573066Y1508260D01*
Y1507460D01*
G01X573738Y1523351D02*
X574919Y1524532D01*
X575783D01*
G01X571692D02*
X573738Y1523351D01*
G01X571692Y1524532D02*
X569814Y1523810D01*
G01X573738Y1528075D02*
X572523Y1528995D01*
X571692Y1529256D01*
G01D02*
X569814Y1528725D01*
G01X563668Y1528731D02*
X566215D01*
G01X575783Y1528862D02*
X574525D01*
X573738Y1528075D01*
G01X560380Y1532851D02*
Y1531761D01*
X559215Y1530596D01*
G01X571372Y1550788D02*
X568172D01*
G01D02*
Y1546940D01*
X568779Y1546333D01*
G01X574196Y1538431D02*
X573015Y1540477D01*
G01X575286Y1544625D02*
X574662D01*
X573015Y1542978D01*
Y1540477D01*
G01X571215Y1540317D02*
Y1539755D01*
X571833Y1539137D01*
Y1538431D01*
G01X576510Y122785D02*
Y125819D01*
G01X579478Y227071D02*
X580420D01*
X582045Y228696D01*
X582816D01*
G01X575567Y304243D02*
Y307599D01*
X575538Y307628D01*
G01X580101Y1509459D02*
Y1507683D01*
X580489Y1507295D01*
G01X584826Y1509459D02*
Y1507683D01*
X585214Y1507295D01*
G01X575377Y1509459D02*
Y1507709D01*
X575182Y1507514D01*
G01X575783Y1522169D02*
Y1524532D01*
G01Y1519807D02*
Y1522169D01*
G01Y1519807D02*
Y1517445D01*
G01D02*
Y1515225D01*
X576765Y1514243D01*
G01X576558Y1511505D02*
X576765Y1511712D01*
Y1514243D01*
G01D02*
X579095D01*
G01D02*
X581489D01*
G01D02*
X581282Y1511505D01*
G01X583819Y1514243D02*
X581489D01*
G01X583819D02*
X586214D01*
G01D02*
X586007Y1511505D01*
G01X588544Y1514243D02*
X586214D01*
G01X588544D02*
X590938D01*
G01X577923Y1519195D02*
X577311Y1519807D01*
X575783D01*
G01X590938Y1522200D02*
X588214Y1521453D01*
G01X586214Y1522200D02*
X583489Y1521453D01*
G01X581489Y1522200D02*
X578765Y1521453D01*
G01X588214D02*
X586214Y1522200D01*
G01X583489Y1521453D02*
X581489Y1522200D01*
G01X578765Y1521453D02*
X575783Y1522169D01*
G01X580101Y1509459D02*
Y1510324D01*
X581282Y1511505D01*
G01X575377Y1509459D02*
Y1510324D01*
X576558Y1511505D01*
G01X584826Y1509459D02*
Y1510324D01*
X586007Y1511505D01*
G01Y1538431D02*
X586214Y1536063D01*
G01X581489D02*
X581282Y1538431D01*
G01X575783Y1536343D02*
Y1533980D01*
G01D02*
Y1531618D01*
G01X576765Y1527880D02*
X575783Y1528862D01*
G01X576765Y1527880D02*
X575783Y1526898D01*
Y1524532D01*
G01Y1531618D02*
Y1528862D01*
G01Y1536343D02*
Y1537656D01*
X576558Y1538431D01*
G01X590938Y1536063D02*
X588264D01*
G01X586214D02*
X583539D01*
G01X581489D02*
X578814D01*
G01X588264D02*
X586214D01*
G01X583539D02*
X581489D01*
G01X578814D02*
Y1536343D01*
X575783D01*
G01X590938Y1528106D02*
X588765Y1528853D01*
G01X586214Y1528106D02*
X584040Y1528853D01*
G01X581489Y1528106D02*
X579316Y1528853D01*
G01X588765D02*
X586214Y1528106D01*
G01X584040Y1528853D02*
X581489Y1528106D01*
G01X579316Y1528853D02*
X576765Y1527880D01*
G01X584826Y1540477D02*
X586007Y1538431D01*
G01X585214Y1542641D02*
Y1540865D01*
X584826Y1540477D01*
G01X581282Y1538431D02*
X580101Y1540477D01*
G01D02*
X580489Y1540865D01*
Y1542641D01*
G01X576558Y1538431D02*
X575377Y1540477D01*
G01X575286Y1542425D02*
Y1540568D01*
X575377Y1540477D01*
G01X575649Y1554939D02*
Y1552567D01*
G01X589550Y1509459D02*
Y1507683D01*
X589938Y1507295D01*
G01X590938Y1514243D02*
X590731Y1511505D01*
G01X593268Y1514243D02*
X590938D01*
G01X593268D02*
X595663D01*
G01D02*
X595456Y1511505D01*
G01X597993Y1514243D02*
X595663D01*
G01X597993D02*
X600387D01*
G01D02*
X600180Y1511505D01*
G01X602717Y1514243D02*
X600387D01*
G01X602717D02*
X605111D01*
G01Y1522200D02*
X602387Y1521453D01*
G01X600387Y1522200D02*
X597662Y1521453D01*
G01X595663Y1522200D02*
X592938Y1521453D01*
G01X602387D02*
X600387Y1522200D01*
G01X597662Y1521453D02*
X595663Y1522200D01*
G01X592938Y1521453D02*
X590938Y1522200D01*
G01X589550Y1509459D02*
Y1510324D01*
X590731Y1511505D01*
G01X603723Y1509459D02*
Y1507683D01*
X604111Y1507295D01*
G01X603723Y1509459D02*
Y1510324D01*
X604904Y1511505D01*
G01X600387Y1536063D02*
X600180Y1538431D01*
G01X595456D02*
X595663Y1536063D01*
G01X590731Y1538431D02*
X590938Y1536063D01*
G01X605111D02*
X602437D01*
G01X600387D02*
X597713D01*
G01X595663D02*
X592988D01*
G01X602437D02*
X600387D01*
G01X597713D02*
X595663D01*
G01X592988D02*
X590938D01*
G01X605111Y1528106D02*
X602938Y1528853D01*
G01X600387Y1528106D02*
X598213Y1528853D01*
G01X595663Y1528106D02*
X593489Y1528853D01*
G01X602938D02*
X600387Y1528106D01*
G01X598213Y1528853D02*
X595663Y1528106D01*
G01X593489Y1528853D02*
X590938Y1528106D01*
G01X603723Y1540477D02*
X604904Y1538431D01*
G01X604111Y1542641D02*
Y1540865D01*
X603723Y1540477D01*
G01X600180Y1538431D02*
X598999Y1540477D01*
G01D02*
X599387Y1540865D01*
Y1542641D01*
G01X594274Y1540477D02*
X595456Y1538431D01*
G01X594662Y1542641D02*
Y1540865D01*
X594274Y1540477D01*
G01X589550D02*
X590731Y1538431D01*
G01X589938Y1542641D02*
Y1540865D01*
X589550Y1540477D01*
G01X615741Y225861D02*
X620038D01*
X620454Y226277D01*
G01X615741Y227830D02*
X615742D01*
G01D02*
X616443D01*
X620233Y231620D01*
X624354D01*
X628574Y227400D01*
X630609D01*
G01Y230550D02*
X627566D01*
X622960Y235156D01*
X616669D01*
G01X613182Y230389D02*
Y231669D01*
X616669Y235156D01*
G01X613172Y1509459D02*
Y1507683D01*
X613560Y1507295D01*
G01X608448Y1509459D02*
Y1507683D01*
X608836Y1507295D01*
G01X617896Y1509459D02*
Y1507683D01*
X618284Y1507295D01*
G01X605111Y1514243D02*
X604904Y1511505D01*
G01X607441Y1514243D02*
X605111D01*
G01X607441D02*
X609836D01*
G01D02*
X609629Y1511505D01*
G01X612166Y1514243D02*
X609836D01*
G01X612166D02*
X614560D01*
G01D02*
X614353Y1511505D01*
G01X616890Y1514243D02*
X614560D01*
G01X616890D02*
X619285D01*
G01Y1522200D02*
X616560Y1521453D01*
G01X614560Y1522200D02*
X611836Y1521453D01*
G01X609836Y1522200D02*
X607111Y1521453D01*
G01X616560D02*
X614560Y1522200D01*
G01X611836Y1521453D02*
X609836Y1522200D01*
G01X607111Y1521453D02*
X605111Y1522200D01*
G01X613172Y1509459D02*
Y1510324D01*
X614353Y1511505D01*
G01X608448Y1509459D02*
Y1510324D01*
X609629Y1511505D01*
G01X619078D02*
X617896Y1510323D01*
Y1509459D01*
G01X609629Y1538431D02*
X609836Y1536063D01*
G01X604904Y1538431D02*
X605111Y1536063D01*
G01X614560D02*
X614353Y1538431D01*
G01X619285Y1536063D02*
X616610D01*
G01X614560D02*
X611886D01*
G01X609836D02*
X607161D01*
G01X616610D02*
X614560D01*
G01X611886D02*
X609836D01*
G01X607161D02*
X605111D01*
G01X619285Y1528106D02*
X617111Y1528853D01*
G01X614560Y1528106D02*
X612387Y1528853D01*
G01X609836Y1528106D02*
X607662Y1528853D01*
G01X617111D02*
X614560Y1528106D01*
G01X612387Y1528853D02*
X609836Y1528106D01*
G01X607662Y1528853D02*
X605111Y1528106D01*
G01X617896Y1540477D02*
X619078Y1538431D01*
G01X618284Y1542641D02*
Y1540865D01*
X617896Y1540477D01*
G01X608448D02*
X609629Y1538431D01*
G01X608836Y1542641D02*
Y1540865D01*
X608448Y1540477D01*
G01X614353Y1538431D02*
X613172Y1540477D01*
G01D02*
X613560Y1540865D01*
Y1542641D01*
G01X634534Y226975D02*
X631034D01*
X630609Y227400D01*
G01X634534Y230975D02*
X631034D01*
X630609Y230550D01*
G01X626703Y1350109D02*
X630477D01*
G01X626703Y1353259D02*
Y1356490D01*
X627327Y1357114D01*
G01X630477D02*
Y1353109D01*
G01X627345Y1509459D02*
Y1507683D01*
X627733Y1507295D01*
G01X622621Y1509459D02*
Y1507683D01*
X623009Y1507295D01*
G01X632070Y1509459D02*
Y1507683D01*
X632458Y1507295D01*
G01X619285Y1514243D02*
X619078Y1511505D01*
G01X621615Y1514243D02*
X619285D01*
G01X621615D02*
X624009D01*
G01D02*
X623802Y1511505D01*
G01X626339Y1514243D02*
X624009D01*
G01X626339D02*
X628733D01*
G01D02*
X628526Y1511505D01*
G01X631063Y1514243D02*
X628733D01*
G01X631063D02*
X633458D01*
G01D02*
X633251Y1511505D01*
G01X635788Y1514243D02*
X633458D01*
G01Y1522200D02*
X630733Y1521453D01*
G01X628733Y1522200D02*
X626009Y1521453D01*
G01X624009Y1522200D02*
X621284Y1521453D01*
G01X630733D02*
X628733Y1522200D01*
G01X626009Y1521453D02*
X624009Y1522200D01*
G01X621284Y1521453D02*
X619285Y1522200D01*
G01X627345Y1509459D02*
Y1510324D01*
X628526Y1511505D01*
G01X622621Y1509459D02*
Y1510324D01*
X623802Y1511505D01*
G01X632070Y1509459D02*
Y1510324D01*
X633251Y1511505D01*
G01Y1538431D02*
X633458Y1536063D01*
G01X628526Y1538431D02*
X628733Y1536063D01*
G01X623802Y1538431D02*
X624009Y1536063D01*
G01X619078Y1538431D02*
X619285Y1536063D01*
G01X633458D02*
X630783D01*
G01X628733D02*
X626059D01*
G01X624009D02*
X621335D01*
G01X630783D02*
X628733D01*
G01X626059D02*
X624009D01*
G01X621335D02*
X619285D01*
G01X635508D02*
X633458D01*
G01Y1528106D02*
X631284Y1528853D01*
G01X628733Y1528106D02*
X626560Y1528853D01*
G01X619285Y1528106D02*
X621835Y1528853D01*
G01X631284D02*
X628733Y1528106D01*
G01X626560Y1528853D02*
X624009Y1528106D01*
G01X621835Y1528853D02*
X624009Y1528106D01*
G01X635458Y1521453D02*
X633458Y1522200D01*
G01X636009Y1528853D02*
X633458Y1528106D01*
G01X632070Y1540477D02*
X633251Y1538431D01*
G01X632458Y1542641D02*
Y1540865D01*
X632070Y1540477D01*
G01X627345D02*
X628526Y1538431D01*
G01X627733Y1542641D02*
Y1540865D01*
X627345Y1540477D01*
G01X622621D02*
X623802Y1538431D01*
G01X623009Y1542641D02*
Y1540865D01*
X622621Y1540477D01*
G01X646239Y166053D02*
X643800D01*
G01X636794Y1509459D02*
Y1507683D01*
X637182Y1507295D01*
G01X641518Y1509459D02*
Y1507683D01*
X641906Y1507295D01*
G01X646243Y1509459D02*
Y1507683D01*
X646631Y1507295D01*
G01X638182Y1514243D02*
X635788D01*
G01X638182D02*
X637975Y1511505D01*
G01X640512Y1514243D02*
X638182D01*
G01X640512D02*
X642907D01*
G01D02*
X642700Y1511505D01*
G01X645237Y1514243D02*
X642907D01*
G01X647631D02*
X645237D01*
G01X647631D02*
X647424Y1511505D01*
G01X649961Y1514243D02*
X647631D01*
G01Y1522200D02*
X644907Y1521453D01*
G01X642907Y1522200D02*
X640182Y1521453D01*
G01X638182Y1522200D02*
X635458Y1521453D01*
G01X644907D02*
X642907Y1522200D01*
G01X640182Y1521453D02*
X638182Y1522200D01*
G01X649631Y1521453D02*
X647631Y1522200D01*
G01X636794Y1509459D02*
Y1510324D01*
X637975Y1511505D01*
G01X642700D02*
X641518Y1510323D01*
Y1509459D01*
G01X646243D02*
Y1510324D01*
X647424Y1511505D01*
G01X642700Y1538431D02*
X642907Y1536063D01*
G01X637975Y1538431D02*
X638182Y1536063D01*
G01X647424Y1538431D02*
X647631Y1536063D01*
G01D02*
X644957D01*
G01X642907D02*
X640232D01*
G01X638182D02*
X635508D01*
G01X647631D02*
X649681D01*
G01X644957D02*
X642907D01*
G01X640232D02*
X638182D01*
G01X647631Y1528106D02*
X645458Y1528853D01*
G01X642907Y1528106D02*
X640733Y1528853D01*
G01X638182Y1528106D02*
X636009Y1528853D01*
G01X645458D02*
X642907Y1528106D01*
G01X640733Y1528853D02*
X638182Y1528106D01*
G01X650182Y1528853D02*
X647631Y1528106D01*
G01X641518Y1540477D02*
X642700Y1538431D01*
G01X641906Y1542641D02*
Y1540865D01*
X641518Y1540477D01*
G01X636794D02*
X637975Y1538431D01*
G01X637182Y1542641D02*
Y1540865D01*
X636794Y1540477D01*
G01X646243D02*
X647424Y1538431D01*
G01X646631Y1542641D02*
Y1540865D01*
X646243Y1540477D01*
G01X666100Y1312502D02*
X664558Y1310960D01*
X663142D01*
X662600Y1311502D01*
G01X666100Y1308048D02*
X664831Y1309317D01*
X663415D01*
X662600Y1308502D01*
G01X653149Y1372500D02*
X654360D01*
X655661Y1371199D01*
G01X660644Y1385290D02*
X663224Y1387870D01*
G01X659559Y1385290D02*
X660644D01*
G01X650967Y1509459D02*
X651355Y1509071D01*
Y1507295D01*
G01X655692Y1509459D02*
X655556Y1509323D01*
Y1507355D01*
G01X657656D02*
Y1509061D01*
X658054Y1509459D01*
G01X653317Y1515083D02*
X652477Y1514243D01*
G01X655363Y1513902D02*
X654498D01*
X653317Y1515083D01*
G01X655363Y1516264D02*
Y1513902D01*
G01X653317Y1515083D02*
Y1516580D01*
X655363Y1518626D01*
G01X653317Y1524532D02*
X652356Y1523571D01*
Y1522200D01*
G01X649961Y1514243D02*
X652477D01*
G01X652148Y1511505D02*
X650967Y1509459D01*
G01X652477Y1514243D02*
Y1511834D01*
X652148Y1511505D01*
G01X655363Y1518626D02*
X654376Y1521453D01*
G01X652356Y1522200D02*
X649631Y1521453D01*
G01X654376D02*
X652356Y1522200D01*
G01X655692Y1509459D02*
X656873Y1511505D01*
G01X653317Y1524532D02*
Y1526894D01*
G01D02*
X654182D01*
X655363Y1528075D01*
G01D02*
X654182Y1529256D01*
X653317D01*
G01X657408Y1524532D02*
X656770Y1523894D01*
X653955D01*
X653317Y1524532D01*
G01X652148Y1538431D02*
X652356Y1536063D01*
G01D02*
X655012D01*
G01X649681D02*
X652356D01*
G01X653317Y1526894D02*
X650182Y1528853D01*
G01X650967Y1540477D02*
X652148Y1538431D01*
G01X651355Y1542641D02*
Y1540865D01*
X650967Y1540477D01*
G01X660615Y1551550D02*
Y1550322D01*
X662374Y1548563D01*
G01X663815Y1551550D02*
X663064Y1550799D01*
Y1549253D01*
X662374Y1548563D01*
G01X654255Y1551550D02*
Y1549249D01*
X654005Y1548999D01*
G01X658773Y1538658D02*
X658546Y1538431D01*
X656873D01*
G01D02*
Y1539296D01*
X655692Y1540477D01*
G01X693492Y88732D02*
X683405D01*
G01X683453Y128093D02*
X678072D01*
G01X671025Y1312502D02*
X669525Y1311002D01*
X667600D01*
X666100Y1312502D01*
G01X671025Y1308002D02*
X669525Y1309502D01*
X667554D01*
X666100Y1308048D01*
G01X674199Y1505135D02*
Y1503575D01*
X672856Y1502232D01*
Y1500082D01*
G01X666050Y1501670D02*
X667334D01*
X668206Y1502542D01*
Y1503039D01*
G01X691058Y131408D02*
X691154Y131312D01*
G01D02*
Y126036D01*
X695647Y121543D01*
Y119441D01*
X695646Y119440D01*
G01X687453Y128093D02*
X683453D01*
G01X687453D02*
Y127306D01*
X693678Y121081D01*
Y119441D01*
X693677Y119440D01*
G01X684111Y1540720D02*
X683669D01*
X682016Y1539067D01*
G01X684111Y1537520D02*
X683563D01*
X682016Y1539067D01*
G01X693965Y89205D02*
X693492Y88732D01*
G01X703520Y119440D02*
Y122102D01*
X704020Y122602D01*
X704144D01*
G01X707243Y123946D02*
Y122872D01*
X705489Y121118D01*
Y119440D01*
G01X701927Y166535D02*
X697277D01*
G01X701927Y172441D02*
X697277D01*
G01X701927Y178346D02*
X697277D01*
G01X701927Y184252D02*
X697277D01*
G01X701927Y190157D02*
X697277D01*
G01X701927Y196063D02*
X697277D01*
G01X701927Y201968D02*
X697277D01*
G01X701927Y207874D02*
X697277D01*
G01X701927Y213779D02*
X697277D01*
G01X701927Y219685D02*
X697277D01*
G01X697331Y419893D02*
X695796Y418358D01*
G01X703630Y423043D02*
X702095Y421508D01*
G01X700481Y438791D02*
X698946Y437256D01*
G01X703630Y438791D02*
X702095Y437256D01*
G01X703630Y451389D02*
X702095Y449854D01*
G01X703630Y454539D02*
X702095Y456074D01*
G01X700481Y467137D02*
X698946Y468672D01*
G01X703630Y467137D02*
X702095Y468672D01*
G01X697331Y486035D02*
X695796Y487570D01*
G01X701925Y1556500D02*
X699500Y1558925D01*
Y1559000D01*
G01X702035Y1580523D02*
X699610D01*
G01X702035Y1584523D02*
X699610D01*
G01X702035Y1588523D02*
X699523D01*
X699500Y1588500D01*
G01X705185Y1588523D02*
Y1584523D01*
G01D02*
X706477D01*
X709317Y1581683D01*
X710080D01*
G01X701925Y1600500D02*
X700500D01*
X699500Y1599500D01*
G01X709930Y432492D02*
X708395Y430957D01*
G01X713079Y423043D02*
X711544Y421508D01*
G01X713079Y426192D02*
X711544Y424657D01*
G01X722528Y445090D02*
X720993Y443555D01*
G01X722528Y448240D02*
X720993Y446705D01*
G01X719378Y448240D02*
X717843Y446705D01*
G01X719378Y441940D02*
X717843Y440405D01*
G01X719378Y445090D02*
X717843Y443555D01*
G01X716229Y448240D02*
X714694Y446705D01*
G01X722528Y441940D02*
X720993Y440405D01*
G01X719378Y463988D02*
X717843Y465523D01*
G01X722528Y451389D02*
X720993Y449854D01*
G01X722528Y460838D02*
X720993Y462373D01*
G01X722528Y457688D02*
X720993Y459223D01*
G01X722528Y454539D02*
X720993Y456074D01*
G01X719378Y457688D02*
X717843Y459223D01*
G01X719378Y460838D02*
X717843Y462373D01*
G01X716229Y457688D02*
X714694Y459223D01*
G01X719378Y454539D02*
X717843Y456074D01*
G01X719378Y451389D02*
X717843Y449854D01*
G01X709930Y473436D02*
X708395Y474971D01*
G01X722528Y463988D02*
X720993Y465523D01*
G01X713079Y482885D02*
X711544Y484420D01*
G01X713079Y479736D02*
X711544Y481271D01*
G01X709551Y1400602D02*
X712419D01*
G01X714110Y1581475D02*
X716697D01*
G01X710080Y1581683D02*
X711270D01*
X713096Y1583509D01*
G01X731977Y429342D02*
X733512Y427807D01*
G01X728827Y423043D02*
X727292Y421508D01*
G01X731977Y426192D02*
X733512Y424657D01*
G01X735126Y445090D02*
X736661Y443555D01*
G01X731977Y448240D02*
X733512Y446705D01*
G01X731977Y445090D02*
X733512Y443555D01*
G01X728827Y448240D02*
X727292Y446705D01*
G01X728827Y445090D02*
X727292Y443555D01*
G01X725678Y445090D02*
X724143Y443555D01*
G01X728827Y441940D02*
X727292Y440405D01*
G01X725678Y448240D02*
X724143Y446705D01*
G01X735126Y448240D02*
X736661Y446705D01*
G01X731977Y441940D02*
X733512Y440405D01*
G01X735126Y441940D02*
X736661Y440405D01*
G01X725678Y441940D02*
X724143Y440405D01*
G01X725678Y460838D02*
X724143Y462373D01*
G01X728827Y460838D02*
X727292Y462373D01*
G01X731977Y457688D02*
X733512Y459223D01*
G01X728827Y457688D02*
X727292Y459223D01*
G01X731977Y460838D02*
X733512Y462373D01*
G01X735126Y460838D02*
X736661Y462373D01*
G01X725678Y451389D02*
X724143Y449854D01*
G01X731977Y454539D02*
X733512Y456074D01*
G01X735126Y454539D02*
X736661Y456074D01*
G01X735126Y457688D02*
X736661Y459223D01*
G01X731977Y451389D02*
X733512Y449854D01*
G01X735126Y451389D02*
X736661Y449854D01*
G01X728827Y454539D02*
X727292Y456074D01*
G01X725678Y457688D02*
X724143Y459223D01*
G01X725678Y454539D02*
X724143Y456074D01*
G01X728827Y451389D02*
X727292Y449854D01*
G01X731977Y463988D02*
X733512Y465523D01*
G01X725678Y463988D02*
X724143Y465523D01*
G01X735126Y463988D02*
X736661Y465523D01*
G01X728827Y463988D02*
X727292Y465523D01*
G01X728827Y473436D02*
X727292Y474971D01*
G01X731977Y473436D02*
X733512Y474971D01*
G01X735126Y482885D02*
X736661Y484420D01*
G01X725678Y482885D02*
X724143Y484420D01*
G01X723146Y1402752D02*
X727188D01*
G01X750874Y423043D02*
X752409Y421508D01*
G01X750874Y426192D02*
X752409Y424657D01*
G01X738276Y445090D02*
X739811Y443555D01*
G01X738276Y448240D02*
X739811Y446705D01*
G01X741426Y441940D02*
X742961Y440405D01*
G01X738276Y441940D02*
X739811Y440405D01*
G01X741426Y445090D02*
X742961Y443555D01*
G01X741426Y448240D02*
X742961Y446705D01*
G01X741426Y463988D02*
X742961Y465523D01*
G01X738276Y451389D02*
X739811Y449854D01*
G01X738276Y454539D02*
X739811Y456074D01*
G01X738276Y457688D02*
X739811Y459223D01*
G01X738276Y460838D02*
X739811Y462373D01*
G01X741426Y460838D02*
X742961Y462373D01*
G01X741426Y457688D02*
X742961Y459223D01*
G01X741426Y454539D02*
X742961Y456074D01*
G01X741426Y451389D02*
X742961Y449854D01*
G01X738276Y463988D02*
X739811Y465523D01*
G01X750874Y482885D02*
X752409Y484420D01*
G01X750874Y479736D02*
X752409Y481271D01*
G01X742333Y1400702D02*
X745201D01*
G01X765285Y276374D02*
X766369Y275290D01*
X769829D01*
G01X763473Y419893D02*
X765008Y418358D01*
G01X757174Y438791D02*
X758709Y437256D01*
G01X754024Y438791D02*
X755559Y437256D01*
G01X754024Y454539D02*
X755559Y456074D01*
G01X754024Y451389D02*
X755559Y449854D01*
G01X757174Y467137D02*
X758709Y468672D01*
G01X754024Y467137D02*
X755559Y468672D01*
G01X763473Y486035D02*
X765008Y487570D01*
G01X755928Y1402852D02*
X759970D01*
G01X763062Y1570633D02*
X760650D01*
G01X763075Y1578733D02*
X760650D01*
G01X763075Y1574733D02*
X760650D01*
G01X766950Y1581233D02*
X767225Y1580958D01*
X770450D01*
G01X763075Y1587733D02*
X760650D01*
G01X782115Y1334173D02*
X782107Y1334181D01*
X779447D01*
G01X785252Y1334469D02*
X782411D01*
X782115Y1334173D01*
G01X779527Y1496695D02*
X784277D01*
X785495Y1495477D01*
X790398D01*
X795008Y1500087D01*
Y1513136D01*
X810906Y1529034D01*
X815964D01*
X816714Y1529784D01*
G01X779527Y1492758D02*
X784277D01*
X785496Y1493977D01*
X791020D01*
X796508Y1499465D01*
Y1512514D01*
X811528Y1527534D01*
X815964D01*
X816714Y1526784D01*
G01X779527Y1504569D02*
X784277D01*
G01X779527Y1500632D02*
X784277D01*
G01Y1508506D02*
X779527D01*
G01X784277Y1512443D02*
X779527D01*
G01X776768Y1581379D02*
X770871D01*
X770450Y1580958D01*
G01X776768Y1583347D02*
X771211D01*
X770450Y1584108D01*
G01X804457Y1348328D02*
X800201Y1345388D01*
G01X824714Y1529784D02*
X825127Y1529371D01*
X826879D01*
X827879Y1530371D01*
Y1533149D01*
X826679Y1534349D01*
X812006D01*
X787381Y1509724D01*
X785495D01*
X784277Y1508506D01*
G01X824714Y1526784D02*
X825801Y1527871D01*
X827501D01*
X829379Y1529749D01*
Y1533771D01*
X827301Y1535849D01*
X811384D01*
X786759Y1511224D01*
X785496D01*
X784277Y1512443D01*
G01X812526Y1345178D02*
Y1303643D01*
X810671Y1301788D01*
X807748D01*
G01X808526Y1345178D02*
X812526D01*
G01Y1348328D02*
X808526D01*
G01D02*
X804457D01*
G01X804575Y1570633D02*
X802150D01*
G01X810050Y1584033D02*
X812225Y1581858D01*
X812750D01*
G01X802150Y1582833D02*
X804375D01*
X804575Y1582633D01*
G01Y1594633D02*
X802150D01*
G01X807725Y1590633D02*
X810150D01*
G01X807725Y1602633D02*
X810150D01*
G01X824498Y142410D02*
Y145197D01*
X824499Y145198D01*
G01X820901Y147112D02*
Y145312D01*
X822531Y143682D01*
Y142411D01*
X822530Y142410D01*
G01X814571Y145952D02*
X818113Y142410D01*
X820561D01*
G01X818002Y139851D02*
X814532D01*
G01X818768Y1581379D02*
X814305D01*
X813826Y1581858D01*
X812750D01*
G01X818768Y1583347D02*
X815035D01*
X813374Y1585008D01*
X812750D01*
G01X855859Y212425D02*
X854872Y211438D01*
X852991D01*
G01Y215375D02*
X855934D01*
G01X858783Y224408D02*
X857958Y225233D01*
X855554D01*
X852991Y222670D01*
Y217344D01*
G01X858783Y227558D02*
X857958Y226733D01*
X854932D01*
X851491Y223292D01*
X851490D01*
X850432Y222234D01*
Y219903D01*
G01X846575Y1570633D02*
X844150D01*
G01X860768Y1581379D02*
X856305D01*
X855826Y1581858D01*
X854750D01*
G01X852050Y1584033D02*
X854225Y1581858D01*
X854750D01*
G01X846575Y1594633D02*
X844150D01*
G01X860768Y1583347D02*
X857035D01*
X855374Y1585008D01*
X854750D01*
G01X849725Y1590633D02*
X852150D01*
G01X844150Y1582833D02*
X846375D01*
X846575Y1582633D01*
G01X849725Y1602633D02*
X852150D01*
G01X871145Y166362D02*
X869283D01*
X868271Y165350D01*
G01X858783Y224408D02*
X859327Y224952D01*
X864129D01*
X865318Y223763D01*
G01Y227763D02*
X864007Y226452D01*
X859889D01*
X858783Y227558D01*
G01X888575Y1570633D02*
X886150D01*
G01X888575Y1594633D02*
X886150D01*
G01Y1582833D02*
X888375D01*
X888575Y1582633D01*
G01X893368Y1141503D02*
X889368D01*
G01X893368D02*
X897437D01*
G01X900240Y1143460D02*
X898805Y1142448D01*
X897437Y1141503D01*
G01X900240Y1143460D02*
X901693Y1144443D01*
G01X894050Y1584033D02*
X896225Y1581858D01*
X896750D01*
G01D02*
X897826D01*
X898305Y1581379D01*
X902768D01*
G01X891725Y1590633D02*
X894150D01*
G01X896750Y1585008D02*
X897374D01*
X899035Y1583347D01*
X902768D01*
G01X891725Y1602633D02*
X894150D01*
G01X916642Y1155362D02*
X919483D01*
X919779Y1155658D01*
G01X922341Y263875D02*
Y265551D01*
X924012Y267222D01*
X925468D01*
G01X922447Y1155650D02*
X919787D01*
X919779Y1155658D01*
G01X944462Y1141503D02*
X940393D01*
G01D02*
X936393D01*
G01X947265Y1143460D02*
X945830Y1142448D01*
X944462Y1141503D01*
G01X933725Y1582233D02*
X936150D01*
G01X933725Y1590233D02*
X936150D01*
G01X961200Y198171D02*
X962481Y199452D01*
Y201165D01*
X961550Y202096D01*
G01D02*
X962357Y202903D01*
Y204175D01*
X961407Y205125D01*
G01X947265Y1143460D02*
X948718Y1144443D01*
G01X962584Y1550824D02*
X961084Y1549324D01*
Y1547766D01*
G01Y1553882D02*
Y1552324D01*
X959584Y1550824D01*
G01X994337Y225233D02*
X993104Y226466D01*
Y226467D01*
X990918Y228653D01*
X977956D01*
X973757Y224454D01*
Y208862D01*
G01D02*
X973956Y208663D01*
G01X965050Y198171D02*
X963981Y199240D01*
Y201377D01*
X964700Y202096D01*
G01D02*
X963857Y202939D01*
Y204175D01*
X964807Y205125D01*
G01X963667Y1155362D02*
X966508D01*
X966804Y1155658D01*
G01D02*
X966812Y1155650D01*
X969472D01*
G01X991196Y1550840D02*
X992696Y1552340D01*
Y1553898D01*
G01X1004967Y198356D02*
X1008037D01*
X1008068Y198387D01*
G01X1017106Y210723D02*
X1011162D01*
X1006669Y206230D01*
X1004967D01*
G01Y196387D02*
X1008543D01*
X1009606Y195324D01*
X1011358D01*
G01X1004967Y208199D02*
X1006515D01*
X1008759Y210443D01*
Y212443D01*
X1010024Y213708D01*
X1010909D01*
G01X994196Y1550840D02*
X992696Y1549340D01*
Y1547782D01*
G01X1016770Y222423D02*
X1019356D01*
G01X1013620D02*
Y226423D01*
G01Y218423D02*
Y222423D01*
G01Y214423D02*
Y218423D01*
G01X1010909Y213708D02*
X1011624Y214423D01*
X1013620D01*
G01Y230423D02*
X1008707D01*
G01X1016770Y233573D02*
X1011847D01*
X1011721Y233699D01*
G01X1016770Y226423D02*
X1021440D01*
G01X1025796Y1550840D02*
X1024296Y1549340D01*
Y1547782D01*
G01Y1553898D02*
Y1552340D01*
X1022796Y1550840D01*
G01X1050639Y1307149D02*
X1050693Y1307203D01*
X1055171D01*
G01X1050639Y1311149D02*
X1050693Y1311203D01*
X1055171D01*
G01Y1307203D02*
X1057571D01*
G01X1055171Y1311203D02*
X1057571D01*
G01X1057396Y1550840D02*
X1055896Y1549340D01*
Y1547782D01*
G01X1054396Y1550840D02*
X1055896Y1552340D01*
Y1553898D01*
G01X1073733Y1382574D02*
X1076601D01*
G01X1089934Y1550784D02*
X1091434Y1549284D01*
Y1542225D01*
G01X1092934Y1550784D02*
X1091434Y1552284D01*
Y1559343D01*
G01X1106333Y1382574D02*
X1109201D01*
G01X1125156Y1573436D02*
X1123656Y1571936D01*
Y1565767D01*
X1124186Y1565237D01*
G01X1120656Y1573436D02*
X1122156Y1571936D01*
Y1565767D01*
X1121626Y1565237D01*
G01X1125868Y1580298D02*
X1123681Y1578111D01*
Y1574836D01*
X1125081Y1573436D01*
X1125156D01*
G01X1125868Y1580298D02*
X1125756D01*
X1123839Y1582215D01*
Y1587652D01*
X1125010Y1588823D01*
G01X1120264Y1580298D02*
X1122181Y1578381D01*
Y1574836D01*
X1120781Y1573436D01*
X1120656D01*
G01X1120110Y1580298D02*
X1120264D01*
G01D02*
X1122181Y1582215D01*
Y1587652D01*
X1121010Y1588823D01*
G01X1120152Y1597498D02*
X1120264D01*
X1122181Y1595581D01*
Y1593144D01*
X1121010Y1591973D01*
G01X1125756Y1597498D02*
X1123839Y1595581D01*
Y1593144D01*
X1125010Y1591973D01*
G01X1122250Y1615727D02*
X1122236Y1615713D01*
Y1599582D01*
X1120152Y1597498D01*
G01X1126250Y1606927D02*
X1123736Y1604413D01*
Y1599518D01*
X1125756Y1597498D01*
G01X1139033Y1382574D02*
X1141901D01*
G01X1137320Y1554012D02*
X1135684D01*
X1135043Y1553371D01*
G01X1141930Y1556029D02*
X1137403D01*
X1137320Y1556112D01*
G01D02*
X1135033D01*
G01X1138480Y1571996D02*
X1137815D01*
X1136173Y1573638D01*
G01X1125910Y1580298D02*
X1125868D01*
G01X1126250Y1606927D02*
X1130250Y1610927D01*
Y1615727D01*
G01X1148544Y1556029D02*
X1151384D01*
G01X1141310Y1565312D02*
Y1567117D01*
X1140655Y1567772D01*
Y1569256D01*
G01X1148727Y1565315D02*
Y1568248D01*
X1149467Y1568988D01*
G01X1152186Y1567524D02*
Y1570567D01*
G01X1162184Y1541913D02*
X1161522Y1542575D01*
G01D02*
Y1544575D01*
G01X1161704Y1556656D02*
X1160818Y1555770D01*
G01D02*
Y1554023D01*
G01X1162615Y1591163D02*
X1160031D01*
G01X1171933Y1382574D02*
X1174801D01*
G01X1179261Y1547420D02*
X1181361D01*
G01X1179261Y1543800D02*
X1181361D01*
G01X1179261Y1551040D02*
X1181361D01*
G01X1179306Y1554331D02*
Y1551085D01*
X1179261Y1551040D01*
G01X1179306Y1561731D02*
X1181853D01*
G01X1172523Y1564600D02*
Y1562350D01*
G01Y1571000D02*
Y1573250D01*
G01D02*
Y1575500D01*
G01X1199988Y470376D02*
X1195783D01*
X1195767Y470392D01*
G01X1188267Y574322D02*
Y571807D01*
G01X1188192Y579015D02*
Y574397D01*
X1188267Y574322D01*
G01X1200923Y601734D02*
X1199647Y603010D01*
X1196782D01*
X1195645Y601873D01*
G01X1200923Y606134D02*
X1199299Y604510D01*
X1197108D01*
X1195645Y605973D01*
G01X1191421Y1552807D02*
Y1550445D01*
G01D02*
Y1548225D01*
X1192403Y1547243D01*
G01X1192196Y1544505D02*
X1192403Y1544712D01*
Y1547243D01*
G01D02*
X1194733D01*
G01D02*
X1197127D01*
G01D02*
X1196920Y1544505D01*
G01X1197127Y1547243D02*
X1199457D01*
G01X1201852D02*
X1199457D01*
G01X1193561Y1552195D02*
X1192949Y1552807D01*
X1191421D01*
G01X1191015Y1542459D02*
Y1540707D01*
X1190820Y1540512D01*
G01X1195739Y1542459D02*
Y1540683D01*
X1196127Y1540295D01*
G01X1195739Y1542459D02*
Y1543324D01*
X1196920Y1544505D01*
G01X1191015Y1542459D02*
Y1543324D01*
X1192196Y1544505D01*
G01X1189834D02*
X1187471D01*
G01X1188653Y1540509D02*
Y1542459D01*
G01X1187471Y1544505D02*
X1186453Y1543487D01*
Y1540509D01*
G01X1191421Y1569343D02*
Y1566980D01*
G01D02*
Y1564618D01*
G01X1192403Y1560880D02*
X1191421Y1561862D01*
G01X1192403Y1560880D02*
X1191421Y1559898D01*
Y1557532D01*
G01Y1555169D02*
Y1557532D01*
G01Y1552807D02*
Y1555169D01*
G01X1189376Y1556351D02*
X1190557Y1557532D01*
X1191421D01*
G01X1187330D02*
X1189376Y1556351D01*
G01X1187330Y1557532D02*
X1185452Y1556810D01*
G01X1191421Y1564618D02*
Y1561862D01*
G01X1189376Y1561075D02*
X1188161Y1561995D01*
X1187330Y1562256D01*
G01D02*
X1185452Y1561725D01*
G01X1191421Y1561862D02*
X1190163D01*
X1189376Y1561075D01*
G01X1201852Y1555200D02*
X1199127Y1554453D01*
G01X1197127Y1555200D02*
X1194403Y1554453D01*
G01X1201852Y1561106D02*
X1199678Y1561853D01*
G01X1197127Y1561106D02*
X1194954Y1561853D01*
G01X1199127Y1554453D02*
X1197127Y1555200D01*
G01X1194403Y1554453D02*
X1191421Y1555169D01*
G01X1199678Y1561853D02*
X1197127Y1561106D01*
G01X1194954Y1561853D02*
X1192403Y1560880D01*
G01X1197127Y1569063D02*
X1196920Y1571431D01*
G01D02*
X1195739Y1573477D01*
G01D02*
X1196127Y1573865D01*
Y1575641D01*
G01X1191421Y1569343D02*
Y1570656D01*
X1192196Y1571431D01*
G01D02*
X1191015Y1573477D01*
G01X1190924Y1575425D02*
Y1573568D01*
X1191015Y1573477D01*
G01X1201852Y1569063D02*
X1199177D01*
G01X1197127D02*
X1194452D01*
G01X1199177D02*
X1197127D01*
G01X1194452D02*
Y1569343D01*
X1191421D01*
G01X1186853Y1573317D02*
Y1572755D01*
X1187471Y1572137D01*
Y1571431D01*
G01X1190924Y1577625D02*
X1190300D01*
X1188653Y1575978D01*
Y1573477D01*
G01X1189834Y1571431D02*
X1188653Y1573477D01*
G01X1286685Y877481D02*
X1285191Y877877D01*
X1284274Y877345D01*
Y869713D01*
X1286499Y867488D01*
X1294635D01*
X1315241Y846882D01*
Y830046D01*
X1286090Y800895D01*
X1280990D01*
X1246371Y766276D01*
Y723530D01*
X1222251Y699410D01*
Y610697D01*
X1214738Y603184D01*
X1202373D01*
X1200923Y601734D01*
G01X1284835Y880670D02*
X1284438Y879175D01*
X1282774Y878211D01*
Y869091D01*
X1285877Y865988D01*
X1294013D01*
X1313741Y846260D01*
Y830668D01*
X1285468Y802395D01*
X1280368D01*
X1244871Y766898D01*
Y724152D01*
X1220751Y700032D01*
Y611319D01*
X1214116Y604684D01*
X1202373D01*
X1200923Y606134D01*
G01X1204733Y1382574D02*
X1207601D01*
G01X1208000Y1393925D02*
X1209800Y1392125D01*
X1211000D01*
G01X1207925Y1401000D02*
Y1403425D01*
X1211000Y1406500D01*
G01X1208000Y1397075D02*
Y1400925D01*
X1207925Y1401000D01*
G01X1211075D02*
Y1395200D01*
G01Y1401000D02*
Y1403575D01*
X1212500Y1405000D01*
G01X1201852Y1547243D02*
X1201645Y1544505D01*
G01X1204182Y1547243D02*
X1201852D01*
G01X1206576D02*
X1204182D01*
G01X1206369Y1544505D02*
X1206576Y1547243D01*
G01X1208906D02*
X1206576D01*
G01X1211301D02*
X1208906D01*
G01X1211301D02*
X1211094Y1544505D01*
G01X1213631Y1547243D02*
X1211301D01*
G01X1213631D02*
X1216025D01*
G01X1205188Y1542459D02*
Y1540683D01*
X1205576Y1540295D01*
G01X1200464Y1542459D02*
Y1540683D01*
X1200852Y1540295D01*
G01X1200464Y1542459D02*
Y1543324D01*
X1201645Y1544505D01*
G01X1205188Y1542459D02*
Y1543324D01*
X1206369Y1544505D01*
G01X1216025Y1555200D02*
X1213300Y1554453D01*
G01X1211301Y1555200D02*
X1208576Y1554453D01*
G01X1206576Y1555200D02*
X1203852Y1554453D01*
G01X1216025Y1561106D02*
X1213851Y1561853D01*
G01X1211301Y1561106D02*
X1209127Y1561853D01*
G01X1206576Y1561106D02*
X1204403Y1561853D01*
G01X1213300Y1554453D02*
X1211301Y1555200D01*
G01X1208576Y1554453D02*
X1206576Y1555200D01*
G01X1203852Y1554453D02*
X1201852Y1555200D01*
G01X1213851Y1561853D02*
X1211301Y1561106D01*
G01X1209127Y1561853D02*
X1206576Y1561106D01*
G01X1204403Y1561853D02*
X1201852Y1561106D01*
G01X1211301Y1569063D02*
X1211094Y1571431D01*
G01D02*
X1209912Y1573477D01*
G01D02*
X1210300Y1573865D01*
Y1575641D01*
G01X1201852Y1569063D02*
X1201645Y1571431D01*
G01D02*
X1200464Y1573477D01*
G01D02*
X1200852Y1573865D01*
Y1575641D01*
G01X1206369Y1571431D02*
X1206576Y1569063D01*
G01X1205188Y1573477D02*
X1206369Y1571431D01*
G01X1205576Y1575641D02*
Y1573865D01*
X1205188Y1573477D01*
G01X1214637D02*
X1215818Y1571431D01*
G01X1215025Y1575641D02*
Y1573865D01*
X1214637Y1573477D01*
G01X1216025Y1569063D02*
X1213351D01*
G01X1211301D02*
X1208626D01*
G01X1206576D02*
X1203902D01*
G01X1213351D02*
X1211301D01*
G01X1208626D02*
X1206576D01*
G01X1203902D02*
X1201852D01*
G01X1224968Y132739D02*
X1222902D01*
X1221411Y134230D01*
G01X1224968Y128239D02*
X1221512D01*
G01X1228118Y132739D02*
Y131489D01*
X1229118Y130489D01*
X1243502D01*
X1244768Y131755D01*
Y132739D01*
G01X1228118Y128239D02*
Y126989D01*
X1229118Y125989D01*
X1243502D01*
X1244768Y127255D01*
Y128239D01*
G01X1216025Y1547243D02*
X1215818Y1544505D01*
G01X1216025Y1547243D02*
X1218355D01*
G01D02*
X1220749D01*
G01X1220542Y1544505D02*
X1220749Y1547243D01*
G01X1223079D02*
X1220749D01*
G01X1223079D02*
X1225474D01*
G01D02*
X1227804D01*
G01D02*
X1230198D01*
G01X1225267Y1544505D02*
X1225474Y1547243D01*
G01X1228810Y1542459D02*
Y1540683D01*
X1229198Y1540295D01*
G01X1228810Y1542459D02*
Y1543324D01*
X1229991Y1544505D01*
G01X1224086Y1542459D02*
Y1540683D01*
X1224474Y1540295D01*
G01X1224086Y1542459D02*
Y1543324D01*
X1225267Y1544505D01*
G01X1219361Y1542459D02*
Y1540683D01*
X1219749Y1540295D01*
G01X1219361Y1542459D02*
Y1543324D01*
X1220542Y1544505D01*
G01X1230198Y1555200D02*
X1227474Y1554453D01*
G01X1225474Y1555200D02*
X1222749Y1554453D01*
G01X1220749Y1555200D02*
X1218025Y1554453D01*
G01X1225474Y1561106D02*
X1228025Y1561853D01*
G01X1225474Y1561106D02*
X1223300Y1561853D01*
G01X1220749Y1561106D02*
X1218576Y1561853D01*
G01X1227474Y1554453D02*
X1225474Y1555200D01*
G01X1222749Y1554453D02*
X1220749Y1555200D01*
G01X1218025Y1554453D02*
X1216025Y1555200D01*
G01X1228025Y1561853D02*
X1230198Y1561106D01*
G01X1223300Y1561853D02*
X1220749Y1561106D01*
G01X1218576Y1561853D02*
X1216025Y1561106D01*
G01X1220542Y1571431D02*
X1220749Y1569063D01*
G01X1219361Y1573477D02*
X1220542Y1571431D01*
G01X1219749Y1575641D02*
Y1573865D01*
X1219361Y1573477D01*
G01X1215818Y1571431D02*
X1216025Y1569063D01*
G01X1225267Y1571431D02*
X1225474Y1569063D01*
G01X1224086Y1573477D02*
X1225267Y1571431D01*
G01X1224474Y1575641D02*
Y1573865D01*
X1224086Y1573477D01*
G01X1228810D02*
X1229991Y1571431D01*
G01X1229198Y1575641D02*
Y1573865D01*
X1228810Y1573477D01*
G01X1230198Y1569063D02*
X1227524D01*
G01X1225474D02*
X1222799D01*
G01X1220749D02*
X1218075D01*
G01X1227524D02*
X1225474D01*
G01X1222799D02*
X1220749D01*
G01X1218075D02*
X1216025D01*
G01X1231268Y132739D02*
X1233668D01*
G01X1231268Y128239D02*
X1233668D01*
G01X1252693Y133549D02*
X1245578D01*
X1244768Y132739D01*
G01X1249693Y129239D02*
X1245768D01*
X1244768Y128239D01*
G01X1242226Y162158D02*
X1242338Y162270D01*
X1245408D01*
X1247834Y159844D01*
G01X1253107Y180551D02*
X1248608D01*
X1245570Y177513D01*
X1242226D01*
G01X1249107Y177051D02*
X1247947D01*
X1245850Y174954D01*
X1242226D01*
G01X1242724Y1336428D02*
X1245592D01*
G01X1243075Y1406500D02*
Y1408925D01*
X1239000Y1413000D01*
G01X1243075Y1406500D02*
X1245325D01*
X1245400Y1406575D01*
X1247000D01*
G01X1244300Y1403500D02*
X1241000D01*
X1239925Y1404575D01*
Y1406500D01*
G01D02*
Y1409075D01*
X1237500Y1411500D01*
G01X1245000Y1433925D02*
X1240925D01*
X1237000Y1430000D01*
G01X1234000Y1431500D02*
X1239550Y1437050D01*
G01X1245000Y1426925D02*
X1240584D01*
X1239965Y1427544D01*
G01D02*
X1237544D01*
X1236750Y1426750D01*
G01X1248859Y1423075D02*
X1247434Y1424500D01*
X1237499D01*
G01X1239550Y1437050D02*
Y1439475D01*
X1241000Y1440925D01*
G01X1245000D02*
X1241000D01*
G01X1230198Y1547243D02*
X1229991Y1544505D01*
G01X1232528Y1547243D02*
X1230198D01*
G01X1234923D02*
X1232528D01*
G01X1234716Y1544505D02*
X1234923Y1547243D01*
G01X1237253D02*
X1234923D01*
G01X1237253D02*
X1239647D01*
G01D02*
X1241977D01*
G01D02*
X1244371D01*
G01D02*
X1244164Y1544505D01*
G01X1246701Y1547243D02*
X1244371D01*
G01X1239440Y1544505D02*
X1239647Y1547243D01*
G01X1242983Y1542459D02*
Y1540683D01*
X1243371Y1540295D01*
G01X1242983Y1542459D02*
Y1543324D01*
X1244164Y1544505D01*
G01X1238259Y1542459D02*
Y1540683D01*
X1238647Y1540295D01*
G01X1238259Y1542459D02*
Y1543324D01*
X1239440Y1544505D01*
G01X1233534Y1542459D02*
Y1540683D01*
X1233922Y1540295D01*
G01X1234716Y1544505D02*
X1233534Y1543323D01*
Y1542459D01*
G01X1244371Y1555200D02*
X1241647Y1554453D01*
G01X1239647Y1555200D02*
X1236922Y1554453D01*
G01X1234923Y1555200D02*
X1232198Y1554453D01*
G01X1244371Y1561106D02*
X1242198Y1561853D01*
G01X1239647Y1561106D02*
X1237473Y1561853D01*
G01X1234923Y1561106D02*
X1232749Y1561853D01*
G01X1241647Y1554453D02*
X1239647Y1555200D01*
G01X1236922Y1554453D02*
X1234923Y1555200D01*
G01X1232198Y1554453D02*
X1230198Y1555200D01*
G01X1242198Y1561853D02*
X1239647Y1561106D01*
G01X1237473Y1561853D02*
X1234923Y1561106D01*
G01X1232749Y1561853D02*
X1230198Y1561106D01*
G01X1246371Y1554453D02*
X1244371Y1555200D01*
G01X1246922Y1561853D02*
X1244371Y1561106D01*
G01X1239647Y1569063D02*
X1239440Y1571431D01*
G01D02*
X1238259Y1573477D01*
G01D02*
X1238647Y1573865D01*
Y1575641D01*
G01X1229991Y1571431D02*
X1230198Y1569063D01*
G01X1234716Y1571431D02*
X1234923Y1569063D01*
G01X1233534Y1573477D02*
X1234716Y1571431D01*
G01X1233922Y1575641D02*
Y1573865D01*
X1233534Y1573477D01*
G01X1244164Y1571431D02*
X1244371Y1569063D01*
G01X1242983Y1573477D02*
X1244164Y1571431D01*
G01X1243371Y1575641D02*
Y1573865D01*
X1242983Y1573477D01*
G01X1244371Y1569063D02*
X1241697D01*
G01X1239647D02*
X1236973D01*
G01X1234923D02*
X1232248D01*
G01X1241697D02*
X1239647D01*
G01X1236973D02*
X1234923D01*
G01X1232248D02*
X1230198D01*
G01X1246421D02*
X1244371D01*
G01X1252693Y133549D02*
X1255383D01*
X1256379Y132553D01*
X1259835D01*
G01X1249693Y129239D02*
X1254693D01*
X1255507Y130053D01*
X1259835D01*
G01X1247834Y159844D02*
X1251825Y155853D01*
X1257909D01*
X1258032Y155730D01*
G01X1253107Y180551D02*
X1258032D01*
G01X1272587Y180565D02*
Y181561D01*
X1271364Y182784D01*
X1259033D01*
X1258032Y181783D01*
Y180551D01*
G01X1249107Y177051D02*
X1257032D01*
X1258032Y176051D01*
G01X1272587D02*
Y177219D01*
X1271587Y178219D01*
X1259994D01*
X1258032Y176257D01*
Y176051D01*
G01X1247000Y1403425D02*
X1249600D01*
G01X1249000Y1426925D02*
X1245000D01*
G01X1253000D02*
X1249000D01*
G01X1252859Y1423075D02*
X1256859D01*
G01X1248859D02*
X1252859D01*
G01X1245000Y1433925D02*
X1249000D01*
G01D02*
X1253000D01*
G01X1249096Y1547243D02*
X1246701D01*
G01X1248889Y1544505D02*
X1249096Y1547243D01*
G01X1251426D02*
X1249096D01*
G01X1253820D02*
X1251426D01*
G01X1253613Y1544505D02*
X1253820Y1547243D01*
G01D02*
X1256150D01*
G01D02*
X1258545D01*
G01D02*
X1260875D01*
G01X1258545D02*
X1258338Y1544505D01*
G01X1252432Y1542459D02*
Y1540683D01*
X1252820Y1540295D01*
G01X1252432Y1542459D02*
Y1543324D01*
X1253613Y1544505D01*
G01X1247708Y1542459D02*
Y1540683D01*
X1248096Y1540295D01*
G01X1247708Y1542459D02*
Y1543324D01*
X1248889Y1544505D01*
G01X1257156Y1542459D02*
Y1540683D01*
X1257544Y1540295D01*
G01X1258338Y1544505D02*
X1257156Y1543323D01*
Y1542459D01*
G01X1258545Y1555200D02*
X1255820Y1554453D01*
G01X1253820Y1555200D02*
X1251096Y1554453D01*
G01X1249096Y1555200D02*
X1246371Y1554453D01*
G01X1258545Y1561106D02*
X1256371Y1561853D01*
G01X1253820Y1561106D02*
X1251647Y1561853D01*
G01X1249096Y1561106D02*
X1246922Y1561853D01*
G01X1255820Y1554453D02*
X1253820Y1555200D01*
G01X1251096Y1554453D02*
X1249096Y1555200D01*
G01X1256371Y1561853D02*
X1253820Y1561106D01*
G01X1251647Y1561853D02*
X1249096Y1561106D01*
G01X1260545Y1554453D02*
X1258545Y1555200D01*
G01X1261096Y1561853D02*
X1258545Y1561106D01*
G01X1258338Y1571431D02*
X1258545Y1569063D01*
G01X1257156Y1573477D02*
X1258338Y1571431D01*
G01X1257544Y1575641D02*
Y1573865D01*
X1257156Y1573477D01*
G01X1249096Y1569063D02*
X1248889Y1571431D01*
G01D02*
X1247708Y1573477D01*
G01D02*
X1248096Y1573865D01*
Y1575641D01*
G01X1253613Y1571431D02*
X1253820Y1569063D01*
G01X1252432Y1573477D02*
X1253613Y1571431D01*
G01X1252820Y1575641D02*
Y1573865D01*
X1252432Y1573477D01*
G01X1258545Y1569063D02*
X1255870D01*
G01X1253820D02*
X1251146D01*
G01X1249096D02*
X1246421D01*
G01X1255870D02*
X1253820D01*
G01X1251146D02*
X1249096D01*
G01X1260595D02*
X1258545D01*
G01X1269437Y180565D02*
X1267037D01*
G01X1269437Y176051D02*
X1268058D01*
X1267037Y175030D01*
G01X1263269Y1547243D02*
X1260875D01*
G01X1263062Y1544505D02*
X1263269Y1547243D01*
G01D02*
X1265599D01*
G01X1268955Y1548083D02*
X1268115Y1547243D01*
G01X1271001Y1546902D02*
X1270136D01*
X1268955Y1548083D01*
G01X1271001Y1549264D02*
Y1546902D01*
G01X1268955Y1548083D02*
Y1549580D01*
X1271001Y1551626D01*
G01X1265599Y1547243D02*
X1268115D01*
G01X1267786Y1544505D02*
X1266605Y1542459D01*
G01D02*
X1266993Y1542071D01*
Y1540295D01*
G01X1268115Y1547243D02*
Y1544834D01*
X1267786Y1544505D01*
G01X1271001Y1551626D02*
X1270014Y1554453D01*
G01X1261881Y1542459D02*
Y1540683D01*
X1262269Y1540295D01*
G01X1261881Y1542459D02*
Y1543324D01*
X1263062Y1544505D01*
G01X1271330Y1542459D02*
X1272511Y1544505D01*
G01X1271330Y1542459D02*
X1271194Y1542323D01*
Y1540355D01*
G01X1273294D02*
Y1542061D01*
X1273692Y1542459D01*
G01X1268955Y1557532D02*
X1267994Y1556571D01*
Y1555200D01*
G01X1268955Y1557532D02*
Y1559894D01*
G01D02*
X1269820D01*
X1271001Y1561075D01*
G01D02*
X1269820Y1562256D01*
X1268955D01*
G01X1273046Y1557532D02*
X1272408Y1556894D01*
X1269593D01*
X1268955Y1557532D01*
G01X1267994Y1555200D02*
X1265269Y1554453D01*
G01X1263269Y1555200D02*
X1260545Y1554453D01*
G01X1268955Y1559894D02*
X1265820Y1561853D01*
G01X1263269Y1561106D02*
X1261096Y1561853D01*
G01X1270014Y1554453D02*
X1267994Y1555200D01*
G01X1265269Y1554453D02*
X1263269Y1555200D01*
G01X1265820Y1561853D02*
X1263269Y1561106D01*
G01X1267786Y1571431D02*
X1267994Y1569063D01*
G01X1266605Y1573477D02*
X1267786Y1571431D01*
G01X1266993Y1575641D02*
Y1573865D01*
X1266605Y1573477D01*
G01X1263062Y1571431D02*
X1263269Y1569063D01*
G01X1261881Y1573477D02*
X1263062Y1571431D01*
G01X1262269Y1575641D02*
Y1573865D01*
X1261881Y1573477D01*
G01X1267994Y1569063D02*
X1265319D01*
G01X1263269D02*
X1260595D01*
G01X1270650D02*
X1267994D01*
G01X1265319D02*
X1263269D01*
G01X1272511Y1571431D02*
Y1572296D01*
X1271330Y1573477D01*
G01X1274411Y1571658D02*
X1274184Y1571431D01*
X1272511D01*
G01X1269153Y1586410D02*
X1269310Y1586253D01*
Y1583170D01*
G01X1287486Y134165D02*
X1285648D01*
X1284760Y135053D01*
X1280741D01*
G01X1275737Y180565D02*
X1278137D01*
G01X1275737Y176051D02*
X1278137D01*
G01X1290127Y408125D02*
X1287721D01*
X1287305Y407709D01*
X1285414D01*
G01Y409678D02*
Y416154D01*
X1287810Y418550D01*
X1289352D01*
G01Y421950D02*
X1288920D01*
X1282855Y415885D01*
Y412237D01*
G01X1293181Y552147D02*
Y553205D01*
X1289574Y556812D01*
Y558732D01*
G01Y562834D02*
Y579426D01*
X1285479Y583521D01*
Y593687D01*
X1287815Y596023D01*
X1290801D01*
X1291791Y597013D01*
G01X1291695Y567536D02*
Y580400D01*
X1287600Y584495D01*
Y592808D01*
X1288795Y594003D01*
X1290627D01*
X1291759Y592871D01*
G01X1275620Y1336400D02*
X1278488D01*
G01X1288323Y1536100D02*
Y1533253D01*
X1288494Y1533082D01*
G01X1276253Y1584550D02*
Y1583322D01*
X1278012Y1581563D01*
G01D02*
X1278702Y1582253D01*
Y1584499D01*
X1279453Y1585250D01*
G01X1300691Y552813D02*
Y554437D01*
X1301667Y555413D01*
G01X1299986Y545248D02*
X1296386D01*
G01X1303765Y545238D02*
X1303755Y545248D01*
X1299986D01*
G01Y548398D02*
X1296386D01*
G01D02*
X1292786D01*
G01D02*
Y551752D01*
X1293181Y552147D01*
G01X1307366Y549638D02*
X1306116Y548388D01*
X1303767D01*
G01X1296331Y552147D02*
Y555698D01*
X1296156Y555873D01*
G01X1303767Y548388D02*
X1303684D01*
X1301514Y550563D01*
X1297915D01*
X1296331Y552147D01*
G01X1293581Y542716D02*
X1292786Y543511D01*
Y545248D01*
G01X1304148Y560209D02*
X1304183Y560174D01*
Y556545D01*
G01X1307766Y563013D02*
X1304966D01*
X1304148Y562195D01*
Y560209D01*
G01X1301666Y555413D02*
X1301667D01*
G01D02*
X1302799Y556545D01*
X1304183D01*
G01X1289574Y558732D02*
Y562834D01*
G01X1296156Y555873D02*
X1293498D01*
X1291695Y557676D01*
G01D02*
Y567536D01*
G01X1294938Y561331D02*
X1296156Y560113D01*
Y559023D01*
G01X1293523Y1538000D02*
X1295368D01*
X1296448Y1539080D01*
G01X1290873Y1556850D02*
X1294073D01*
G01D02*
Y1558350D01*
X1292673Y1559750D01*
G01X1304080Y1565851D02*
Y1564761D01*
X1302915Y1563596D01*
G01X1337257Y678765D02*
X1336105Y677613D01*
X1319513D01*
X1309947Y687179D01*
Y791456D01*
X1347099Y828608D01*
X1410169D01*
X1434599Y853038D01*
X1477889D01*
X1485836Y860985D01*
X1498806D01*
X1499469Y860322D01*
G01X1340257Y675111D02*
X1339911D01*
X1339757Y675265D01*
X1339221D01*
X1338373Y676113D01*
X1318891D01*
X1308447Y686557D01*
Y792078D01*
X1346477Y830108D01*
X1409547D01*
X1433977Y854538D01*
X1477267D01*
X1485214Y862485D01*
X1498632D01*
X1499469Y863322D01*
G01X1308524Y1336343D02*
X1311392D01*
G01X1319483Y1550445D02*
Y1548225D01*
X1320465Y1547243D01*
G01X1307323Y1543800D02*
X1309423D01*
G01X1307323Y1547420D02*
X1309423D01*
G01X1307323Y1551040D02*
X1309423D01*
G01X1307368Y1554331D02*
Y1551085D01*
X1307323Y1551040D01*
G01X1319077Y1542459D02*
Y1543324D01*
X1320258Y1544505D01*
G01X1319077Y1542459D02*
Y1540709D01*
X1318882Y1540514D01*
G01X1317896Y1544505D02*
X1315533D01*
G01X1316715Y1542459D02*
Y1541311D01*
X1316766Y1541260D01*
Y1540460D01*
G01X1315533Y1544505D02*
X1314515Y1543487D01*
Y1540509D01*
G01X1320465Y1560880D02*
X1319483Y1561862D01*
G01X1320465Y1560880D02*
X1319483Y1559898D01*
Y1557532D01*
G01X1317438Y1556351D02*
X1318619Y1557532D01*
X1319483D01*
G01X1315392D02*
X1317438Y1556351D01*
G01X1315392Y1557532D02*
X1313514Y1556810D01*
G01X1317438Y1561075D02*
X1316223Y1561995D01*
X1315392Y1562256D01*
G01D02*
X1313514Y1561725D01*
G01X1307368Y1561731D02*
X1309915D01*
G01X1319483Y1561862D02*
X1318225D01*
X1317438Y1561075D01*
G01X1319483Y1569343D02*
Y1570656D01*
X1320258Y1571431D01*
G01D02*
X1319077Y1573477D01*
G01X1318986Y1575425D02*
Y1573568D01*
X1319077Y1573477D01*
G01X1312700Y1579596D02*
X1311872Y1580424D01*
Y1583788D01*
G01X1314915Y1573317D02*
Y1572755D01*
X1315533Y1572137D01*
Y1571431D01*
G01X1318986Y1577625D02*
X1318362D01*
X1316715Y1575978D01*
Y1573477D01*
G01X1317896Y1571431D02*
X1316715Y1573477D01*
G01X1315072Y1583788D02*
X1311872D01*
G01X1326435Y561302D02*
X1329081D01*
X1329585Y561806D01*
G01X1319483Y1552807D02*
Y1550445D01*
G01X1320258Y1544505D02*
X1320465Y1544712D01*
Y1547243D01*
G01D02*
X1322795D01*
G01D02*
X1325189D01*
G01D02*
X1324982Y1544505D01*
G01X1327519Y1547243D02*
X1325189D01*
G01X1327519D02*
X1329914D01*
G01D02*
X1329707Y1544505D01*
G01X1332244Y1547243D02*
X1329914D01*
G01X1332244D02*
X1334638D01*
G01X1321623Y1552195D02*
X1321011Y1552807D01*
X1319483D01*
G01X1323801Y1542459D02*
Y1540683D01*
X1324189Y1540295D01*
G01X1323801Y1542459D02*
Y1543324D01*
X1324982Y1544505D01*
G01X1333250Y1542459D02*
Y1540683D01*
X1333638Y1540295D01*
G01X1328526Y1542459D02*
Y1540683D01*
X1328914Y1540295D01*
G01X1328526Y1542459D02*
Y1543324D01*
X1329707Y1544505D01*
G01X1333250Y1542459D02*
Y1543324D01*
X1334431Y1544505D01*
G01X1319483Y1569343D02*
Y1566980D01*
G01D02*
Y1564618D01*
G01Y1555169D02*
Y1557532D01*
G01Y1552807D02*
Y1555169D01*
G01Y1564618D02*
Y1561862D01*
G01X1334638Y1555200D02*
X1331914Y1554453D01*
G01X1329914Y1555200D02*
X1327189Y1554453D01*
G01X1325189Y1555200D02*
X1322465Y1554453D01*
G01X1334638Y1561106D02*
X1332465Y1561853D01*
G01X1329914Y1561106D02*
X1327740Y1561853D01*
G01X1325189Y1561106D02*
X1323016Y1561853D01*
G01X1331914Y1554453D02*
X1329914Y1555200D01*
G01X1327189Y1554453D02*
X1325189Y1555200D01*
G01X1322465Y1554453D02*
X1319483Y1555169D01*
G01X1332465Y1561853D02*
X1329914Y1561106D01*
G01X1327740Y1561853D02*
X1325189Y1561106D01*
G01X1323016Y1561853D02*
X1320465Y1560880D01*
G01X1333250Y1573477D02*
X1334431Y1571431D01*
G01X1333638Y1575641D02*
Y1573865D01*
X1333250Y1573477D01*
G01X1329707Y1571431D02*
X1329914Y1569063D01*
G01X1328526Y1573477D02*
X1329707Y1571431D01*
G01X1328914Y1575641D02*
Y1573865D01*
X1328526Y1573477D01*
G01X1325189Y1569063D02*
X1324982Y1571431D01*
G01D02*
X1323801Y1573477D01*
G01D02*
X1324189Y1573865D01*
Y1575641D01*
G01X1334638Y1569063D02*
X1331964D01*
G01X1329914D02*
X1327239D01*
G01X1325189D02*
X1322514D01*
G01X1331964D02*
X1329914D01*
G01X1327239D02*
X1325189D01*
G01X1322514D02*
Y1569343D01*
X1319483D01*
G01X1319349Y1587939D02*
Y1585567D01*
G01X1350772Y674593D02*
X1350622Y674443D01*
X1346335D01*
G01X1346371Y678393D02*
X1350122D01*
X1350772Y677743D01*
G01X1343221Y678393D02*
X1342593Y677765D01*
X1340257D01*
G01X1337257Y678765D02*
X1338257Y677765D01*
X1340257D01*
G01X1343185Y674443D02*
X1342517Y675111D01*
X1340257D01*
G01X1341324Y1336543D02*
X1344192D01*
G01X1334638Y1547243D02*
X1334431Y1544505D01*
G01X1336968Y1547243D02*
X1334638D01*
G01X1336968D02*
X1339363D01*
G01D02*
X1339156Y1544505D01*
G01X1341693Y1547243D02*
X1339363D01*
G01X1341693D02*
X1344087D01*
G01D02*
X1343880Y1544505D01*
G01X1346417Y1547243D02*
X1344087D01*
G01X1346417D02*
X1348811D01*
G01D02*
X1348604Y1544505D01*
G01X1351141Y1547243D02*
X1348811D01*
G01X1347423Y1542459D02*
Y1540683D01*
X1347811Y1540295D01*
G01X1347423Y1542459D02*
Y1543324D01*
X1348604Y1544505D01*
G01X1348811Y1555200D02*
X1346087Y1554453D01*
G01X1344087Y1555200D02*
X1341362Y1554453D01*
G01X1339363Y1555200D02*
X1336638Y1554453D01*
G01X1348811Y1561106D02*
X1346638Y1561853D01*
G01X1344087Y1561106D02*
X1341913Y1561853D01*
G01X1339363Y1561106D02*
X1337189Y1561853D01*
G01X1346087Y1554453D02*
X1344087Y1555200D01*
G01X1341362Y1554453D02*
X1339363Y1555200D01*
G01X1336638Y1554453D02*
X1334638Y1555200D01*
G01X1346638Y1561853D02*
X1344087Y1561106D01*
G01X1341913Y1561853D02*
X1339363Y1561106D01*
G01X1337189Y1561853D02*
X1334638Y1561106D01*
G01X1350811Y1554453D02*
X1348811Y1555200D01*
G01X1351362Y1561853D02*
X1348811Y1561106D01*
G01X1348604Y1571431D02*
X1348811Y1569063D01*
G01X1347423Y1573477D02*
X1348604Y1571431D01*
G01X1347811Y1575641D02*
Y1573865D01*
X1347423Y1573477D01*
G01X1344087Y1569063D02*
X1343880Y1571431D01*
G01D02*
X1342699Y1573477D01*
G01D02*
X1343087Y1573865D01*
Y1575641D01*
G01X1339156Y1571431D02*
X1339363Y1569063D01*
G01X1337974Y1573477D02*
X1339156Y1571431D01*
G01X1338362Y1575641D02*
Y1573865D01*
X1337974Y1573477D01*
G01X1334431Y1571431D02*
X1334638Y1569063D01*
G01X1348811D02*
X1346137D01*
G01X1344087D02*
X1341413D01*
G01X1339363D02*
X1336688D01*
G01X1346137D02*
X1344087D01*
G01X1341413D02*
X1339363D01*
G01X1336688D02*
X1334638D01*
G01X1350861D02*
X1348811D01*
G01X1354257Y675765D02*
X1353085Y674593D01*
X1350772D01*
G01Y677743D02*
X1354477Y681448D01*
G01X1363732Y1055709D02*
X1362685Y1056756D01*
X1361894D01*
G01X1360031Y1055709D02*
X1358984Y1056756D01*
X1358193D01*
G01X1351141Y1547243D02*
X1353536D01*
G01D02*
X1353329Y1544505D01*
G01X1355866Y1547243D02*
X1353536D01*
G01X1355866D02*
X1358260D01*
G01D02*
X1358053Y1544505D01*
G01X1360590Y1547243D02*
X1358260D01*
G01X1360590D02*
X1362985D01*
G01D02*
X1362778Y1544505D01*
G01X1365315Y1547243D02*
X1362985D01*
G01X1356872Y1542459D02*
Y1540683D01*
X1357260Y1540295D01*
G01X1356872Y1542459D02*
Y1543324D01*
X1358053Y1544505D01*
G01X1352148Y1542459D02*
Y1540683D01*
X1352536Y1540295D01*
G01X1352148Y1542459D02*
Y1543324D01*
X1353329Y1544505D01*
G01X1361596Y1542459D02*
Y1540683D01*
X1361984Y1540295D01*
G01X1362778Y1544505D02*
X1361596Y1543323D01*
Y1542459D01*
G01X1362985Y1555200D02*
X1360260Y1554453D01*
G01X1358260Y1555200D02*
X1355536Y1554453D01*
G01X1353536Y1555200D02*
X1350811Y1554453D01*
G01X1362985Y1561106D02*
X1360811Y1561853D01*
G01X1358260Y1561106D02*
X1356087Y1561853D01*
G01X1353536Y1561106D02*
X1351362Y1561853D01*
G01X1362985Y1561106D02*
X1365535Y1561853D01*
G01X1360260Y1554453D02*
X1358260Y1555200D01*
G01X1355536Y1554453D02*
X1353536Y1555200D01*
G01X1360811Y1561853D02*
X1358260Y1561106D01*
G01X1356087Y1561853D02*
X1353536Y1561106D01*
G01X1364984Y1554453D02*
X1362985Y1555200D01*
G01X1362778Y1571431D02*
X1362985Y1569063D01*
G01X1361596Y1573477D02*
X1362778Y1571431D01*
G01X1361984Y1575641D02*
Y1573865D01*
X1361596Y1573477D01*
G01X1353329Y1571431D02*
X1353536Y1569063D01*
G01X1352148Y1573477D02*
X1353329Y1571431D01*
G01X1352536Y1575641D02*
Y1573865D01*
X1352148Y1573477D01*
G01X1358260Y1569063D02*
X1358053Y1571431D01*
G01D02*
X1356872Y1573477D01*
G01D02*
X1357260Y1573865D01*
Y1575641D01*
G01X1362985Y1569063D02*
X1360310D01*
G01X1358260D02*
X1355586D01*
G01X1353536D02*
X1350861D01*
G01X1360310D02*
X1358260D01*
G01X1355586D02*
X1353536D01*
G01X1365035D02*
X1362985D01*
G01X1379613Y616858D02*
X1376745D01*
G01X1373906Y1355874D02*
X1376774D01*
G01X1365315Y1547243D02*
X1367709D01*
G01D02*
X1367502Y1544505D01*
G01X1370039Y1547243D02*
X1367709D01*
G01X1370039D02*
X1372433D01*
G01D02*
X1372226Y1544505D01*
G01X1374763Y1547243D02*
X1372433D01*
G01X1374763D02*
X1377158D01*
G01D02*
X1376951Y1544505D01*
G01X1379488Y1547243D02*
X1377158D01*
G01X1371045Y1542459D02*
Y1540683D01*
X1371433Y1540295D01*
G01X1371045Y1542459D02*
Y1543324D01*
X1372226Y1544505D01*
G01X1366321Y1542459D02*
Y1540683D01*
X1366709Y1540295D01*
G01X1366321Y1542459D02*
Y1543324D01*
X1367502Y1544505D01*
G01X1375770Y1542459D02*
Y1540683D01*
X1376158Y1540295D01*
G01X1375770Y1542459D02*
Y1543324D01*
X1376951Y1544505D01*
G01X1377158Y1555200D02*
X1374433Y1554453D01*
G01X1372433Y1555200D02*
X1369709Y1554453D01*
G01X1367709Y1555200D02*
X1364984Y1554453D01*
G01X1377158Y1561106D02*
X1374984Y1561853D01*
G01X1372433Y1561106D02*
X1370260Y1561853D01*
G01X1379158Y1554453D02*
X1377158Y1555200D01*
G01X1374433Y1554453D02*
X1372433Y1555200D01*
G01X1369709Y1554453D02*
X1367709Y1555200D01*
G01X1374984Y1561853D02*
X1372433Y1561106D01*
G01X1370260Y1561853D02*
X1367709Y1561106D01*
G01X1365535Y1561853D02*
X1367709Y1561106D01*
G01X1379709Y1561853D02*
X1377158Y1561106D01*
G01X1376951Y1571431D02*
X1377158Y1569063D01*
G01X1375770Y1573477D02*
X1376951Y1571431D01*
G01X1376158Y1575641D02*
Y1573865D01*
X1375770Y1573477D01*
G01X1372226Y1571431D02*
X1372433Y1569063D01*
G01X1371045Y1573477D02*
X1372226Y1571431D01*
G01X1371433Y1575641D02*
Y1573865D01*
X1371045Y1573477D01*
G01X1367502Y1571431D02*
X1367709Y1569063D01*
G01X1366321Y1573477D02*
X1367502Y1571431D01*
G01X1366709Y1575641D02*
Y1573865D01*
X1366321Y1573477D01*
G01X1377158Y1569063D02*
X1374483D01*
G01X1372433D02*
X1369759D01*
G01X1367709D02*
X1365035D01*
G01X1379208D02*
X1377158D01*
G01X1374483D02*
X1372433D01*
G01X1369759D02*
X1367709D01*
G01X1381882Y1547243D02*
X1379488D01*
G01X1381882D02*
X1381675Y1544505D01*
G01X1384212Y1547243D02*
X1381882D01*
G01X1384212D02*
X1386607D01*
G01D02*
X1386400Y1544505D01*
G01X1388937Y1547243D02*
X1386607D01*
G01X1391331D02*
X1388937D01*
G01X1391331D02*
X1391124Y1544505D01*
G01X1393661Y1547243D02*
X1391331D01*
G01X1393661D02*
X1396177D01*
G01X1380494Y1542459D02*
Y1540683D01*
X1380882Y1540295D01*
G01X1380494Y1542459D02*
Y1543324D01*
X1381675Y1544505D01*
G01X1385218Y1542459D02*
Y1540683D01*
X1385606Y1540295D01*
G01X1386400Y1544505D02*
X1385218Y1543323D01*
Y1542459D01*
G01X1389943D02*
Y1540683D01*
X1390331Y1540295D01*
G01X1389943Y1542459D02*
Y1543324D01*
X1391124Y1544505D01*
G01X1381882Y1555200D02*
X1379158Y1554453D01*
G01X1396056Y1555200D02*
X1393331Y1554453D01*
G01X1391331Y1555200D02*
X1388607Y1554453D01*
G01X1386607Y1555200D02*
X1383882Y1554453D01*
G01X1397017Y1559894D02*
X1393882Y1561853D01*
G01X1391331Y1561106D02*
X1389158Y1561853D01*
G01X1386607Y1561106D02*
X1384433Y1561853D01*
G01X1381882Y1561106D02*
X1379709Y1561853D01*
G01X1393331Y1554453D02*
X1391331Y1555200D01*
G01X1388607Y1554453D02*
X1386607Y1555200D01*
G01X1383882Y1554453D02*
X1381882Y1555200D01*
G01X1393882Y1561853D02*
X1391331Y1561106D01*
G01X1389158Y1561853D02*
X1386607Y1561106D01*
G01X1384433Y1561853D02*
X1381882Y1561106D01*
G01X1386400Y1571431D02*
X1386607Y1569063D01*
G01X1385218Y1573477D02*
X1386400Y1571431D01*
G01X1385606Y1575641D02*
Y1573865D01*
X1385218Y1573477D01*
G01X1381675Y1571431D02*
X1381882Y1569063D01*
G01X1380494Y1573477D02*
X1381675Y1571431D01*
G01X1380882Y1575641D02*
Y1573865D01*
X1380494Y1573477D01*
G01X1391124Y1571431D02*
X1391331Y1569063D01*
G01X1389943Y1573477D02*
X1391124Y1571431D01*
G01X1390331Y1575641D02*
Y1573865D01*
X1389943Y1573477D01*
G01X1381882Y1569063D02*
X1379208D01*
G01X1391331D02*
X1388657D01*
G01X1386607D02*
X1383932D01*
G01X1391331D02*
X1393381D01*
G01X1388657D02*
X1386607D01*
G01X1383932D02*
X1381882D01*
G01X1393381D02*
X1396056D01*
G01X1397017Y1548083D02*
X1396177Y1547243D01*
G01X1399063Y1546902D02*
X1398198D01*
X1397017Y1548083D01*
G01X1399063Y1549264D02*
Y1546902D01*
G01X1397017Y1548083D02*
Y1549580D01*
X1399063Y1551626D01*
G01X1395848Y1544505D02*
X1394667Y1542459D01*
G01D02*
X1395055Y1542071D01*
Y1540295D01*
G01X1396177Y1547243D02*
Y1544834D01*
X1395848Y1544505D01*
G01X1399063Y1551626D02*
X1398076Y1554453D01*
G01X1399392Y1542459D02*
X1400573Y1544505D01*
G01X1399392Y1542459D02*
X1399256Y1542323D01*
Y1540355D01*
G01X1401356D02*
Y1542061D01*
X1401754Y1542459D01*
G01X1397017Y1557532D02*
X1396056Y1556571D01*
Y1555200D01*
G01X1397017Y1557532D02*
Y1559894D01*
G01D02*
X1397882D01*
X1399063Y1561075D01*
G01D02*
X1397882Y1562256D01*
X1397017D01*
G01X1401108Y1557532D02*
X1400470Y1556894D01*
X1397655D01*
X1397017Y1557532D01*
G01X1398076Y1554453D02*
X1396056Y1555200D01*
G01X1395848Y1571431D02*
X1396056Y1569063D01*
G01X1394667Y1573477D02*
X1395848Y1571431D01*
G01X1395055Y1575641D02*
Y1573865D01*
X1394667Y1573477D01*
G01X1404315Y1584550D02*
Y1583322D01*
X1406074Y1581563D01*
G01X1407515Y1584550D02*
X1406764Y1583799D01*
Y1582253D01*
X1406074Y1581563D01*
G01X1396056Y1569063D02*
X1398712D01*
G01X1400573Y1571431D02*
Y1572296D01*
X1399392Y1573477D01*
G01X1402473Y1571658D02*
X1402246Y1571431D01*
X1400573D01*
G01X1397955Y1584550D02*
Y1582178D01*
G01X1412313Y649758D02*
X1409445D01*
G01X1410765Y1285765D02*
Y1280947D01*
X1410961Y1280751D01*
G01X1414165Y1289564D02*
X1413964Y1289765D01*
X1410765D01*
G01X1414172Y1286188D02*
X1413914Y1285930D01*
X1410930D01*
X1410765Y1285765D01*
G01X1421585Y1538000D02*
X1422450D01*
X1423735Y1536715D01*
G01X1409456Y1537872D02*
X1411228Y1536100D01*
X1412185D01*
G01X1422135Y1556850D02*
Y1558350D01*
X1420735Y1559750D01*
G01X1418935Y1556850D02*
X1422135D01*
G01X1417023Y1571000D02*
Y1569638D01*
X1417981Y1568680D01*
G01X1439050Y1679544D02*
X1438124D01*
X1435508Y1676928D01*
Y1668207D01*
X1436311Y1667404D01*
Y1665948D01*
G01X1439067Y1689273D02*
Y1691172D01*
X1435904Y1694335D01*
G01X1444913Y682338D02*
X1442045D01*
G01X1443435Y1551040D02*
X1445535D01*
G01X1443480Y1554331D02*
Y1551085D01*
X1443435Y1551040D01*
G01Y1547420D02*
X1445535D01*
G01X1443435Y1543800D02*
X1445535D01*
G01X1451645Y1544505D02*
X1450627Y1543487D01*
Y1540509D01*
G01X1454008Y1544505D02*
X1451645D01*
G01X1452827Y1540509D02*
Y1542459D01*
G01X1453550Y1556351D02*
X1454731Y1557532D01*
X1455595D01*
G01X1451504D02*
X1453550Y1556351D01*
G01X1451504Y1557532D02*
X1449626Y1556810D01*
G01X1453550Y1561075D02*
X1452335Y1561995D01*
X1451504Y1562256D01*
G01D02*
X1449626Y1561725D01*
G01X1443480Y1561731D02*
X1446027D01*
G01X1455595Y1561862D02*
X1454337D01*
X1453550Y1561075D01*
G01X1447984Y1583788D02*
Y1580225D01*
X1448484Y1579725D01*
X1448505D01*
G01X1451027Y1573317D02*
Y1572755D01*
X1451645Y1572137D01*
Y1571431D01*
G01X1454008D02*
X1452827Y1573477D01*
G01X1455098Y1577625D02*
X1454474D01*
X1452827Y1575978D01*
Y1573477D01*
G01X1451184Y1583788D02*
X1447984D01*
G01X1455595Y1552807D02*
Y1550445D01*
G01D02*
Y1548225D01*
X1456577Y1547243D01*
G01X1456370Y1544505D02*
X1456577Y1544712D01*
Y1547243D01*
G01D02*
X1458907D01*
G01D02*
X1461301D01*
G01D02*
X1461094Y1544505D01*
G01X1461301Y1547243D02*
X1463631D01*
G01X1466026D02*
X1463631D01*
G01X1466026D02*
X1465819Y1544505D01*
G01X1468356Y1547243D02*
X1466026D01*
G01X1457735Y1552195D02*
X1457123Y1552807D01*
X1455595D01*
G01X1455189Y1542459D02*
Y1540707D01*
X1454994Y1540512D01*
G01X1459913Y1542459D02*
Y1540683D01*
X1460301Y1540295D01*
G01X1459913Y1542459D02*
Y1543324D01*
X1461094Y1544505D01*
G01X1455189Y1542459D02*
Y1543324D01*
X1456370Y1544505D01*
G01X1464638Y1542459D02*
Y1540683D01*
X1465026Y1540295D01*
G01X1464638Y1542459D02*
Y1543324D01*
X1465819Y1544505D01*
G01X1455595Y1569343D02*
Y1566980D01*
G01D02*
Y1564618D01*
G01X1456577Y1560880D02*
X1455595Y1561862D01*
G01X1456577Y1560880D02*
X1455595Y1559898D01*
Y1557532D01*
G01Y1555169D02*
Y1557532D01*
G01Y1552807D02*
Y1555169D01*
G01Y1564618D02*
Y1561862D01*
G01X1470750Y1555200D02*
X1468026Y1554453D01*
G01X1466026Y1555200D02*
X1463301Y1554453D01*
G01X1461301Y1555200D02*
X1458577Y1554453D01*
G01X1466026Y1561106D02*
X1463852Y1561853D01*
G01X1461301Y1561106D02*
X1459128Y1561853D01*
G01X1468026Y1554453D02*
X1466026Y1555200D01*
G01X1463301Y1554453D02*
X1461301Y1555200D01*
G01X1458577Y1554453D02*
X1455595Y1555169D01*
G01X1468577Y1561853D02*
X1466026Y1561106D01*
G01X1463852Y1561853D02*
X1461301Y1561106D01*
G01X1459128Y1561853D02*
X1456577Y1560880D01*
G01X1461301Y1569063D02*
X1461094Y1571431D01*
G01D02*
X1459913Y1573477D01*
G01D02*
X1460301Y1573865D01*
Y1575641D01*
G01X1455595Y1569343D02*
Y1570656D01*
X1456370Y1571431D01*
G01D02*
X1455189Y1573477D01*
G01X1455098Y1575425D02*
Y1573568D01*
X1455189Y1573477D01*
G01X1466026Y1569063D02*
X1465819Y1571431D01*
G01D02*
X1464638Y1573477D01*
G01D02*
X1465026Y1573865D01*
Y1575641D01*
G01X1470750Y1569063D02*
X1468076D01*
G01X1466026D02*
X1463351D01*
G01X1461301D02*
X1458626D01*
G01X1468076D02*
X1466026D01*
G01X1463351D02*
X1461301D01*
G01X1458626D02*
Y1569343D01*
X1455595D01*
G01X1455461Y1587939D02*
Y1585567D01*
G01X1465500Y1668450D02*
Y1667000D01*
X1466500Y1666000D01*
G01X1477831Y701915D02*
X1474963D01*
G01X1470750Y1547243D02*
X1468356D01*
G01X1470543Y1544505D02*
X1470750Y1547243D01*
G01X1473080D02*
X1470750D01*
G01X1475475D02*
X1473080D01*
G01X1475475D02*
X1475268Y1544505D01*
G01X1477805Y1547243D02*
X1475475D01*
G01X1477805D02*
X1480199D01*
G01D02*
X1479992Y1544505D01*
G01X1480199Y1547243D02*
X1482529D01*
G01D02*
X1484923D01*
G01X1469362Y1542459D02*
Y1540683D01*
X1469750Y1540295D01*
G01X1469362Y1542459D02*
Y1543324D01*
X1470543Y1544505D01*
G01X1470750Y1561106D02*
X1468577Y1561853D01*
G01X1484923Y1555200D02*
X1482199Y1554453D01*
G01X1480199Y1555200D02*
X1477474Y1554453D01*
G01X1475475Y1555200D02*
X1472750Y1554453D01*
G01X1484923Y1561106D02*
X1482750Y1561853D01*
G01X1480199Y1561106D02*
X1478025Y1561853D01*
G01X1475475Y1561106D02*
X1473301Y1561853D01*
G01X1482199Y1554453D02*
X1480199Y1555200D01*
G01X1477474Y1554453D02*
X1475475Y1555200D01*
G01X1472750Y1554453D02*
X1470750Y1555200D01*
G01X1482750Y1561853D02*
X1480199Y1561106D01*
G01X1478025Y1561853D02*
X1475475Y1561106D01*
G01X1473301Y1561853D02*
X1470750Y1561106D01*
G01X1475475Y1569063D02*
X1475268Y1571431D01*
G01D02*
X1474086Y1573477D01*
G01D02*
X1474474Y1573865D01*
Y1575641D01*
G01X1470543Y1571431D02*
X1470750Y1569063D01*
G01X1469362Y1573477D02*
X1470543Y1571431D01*
G01X1469750Y1575641D02*
Y1573865D01*
X1469362Y1573477D01*
G01X1479992Y1571431D02*
X1480199Y1569063D01*
G01X1478811Y1573477D02*
X1479992Y1571431D01*
G01X1479199Y1575641D02*
Y1573865D01*
X1478811Y1573477D01*
G01X1484923Y1569063D02*
X1482249D01*
G01X1480199D02*
X1477525D01*
G01X1475475D02*
X1472800D01*
G01X1482249D02*
X1480199D01*
G01X1477525D02*
X1475475D01*
G01X1472800D02*
X1470750D01*
G01X1480580Y1668917D02*
X1472797D01*
X1471616Y1670098D01*
G01X1481000Y1684050D02*
Y1684359D01*
X1479375Y1685984D01*
G01X1476266Y1679401D02*
X1478451D01*
X1481000Y1681950D01*
G01D02*
X1482298D01*
X1482798Y1682450D01*
Y1685982D01*
G01X1484716Y1544505D02*
X1484923Y1547243D01*
G01X1487253D02*
X1484923D01*
G01X1487253D02*
X1489648D01*
G01D02*
X1491978D01*
G01D02*
X1494372D01*
G01D02*
X1494165Y1544505D01*
G01X1496702Y1547243D02*
X1494372D01*
G01X1499097D02*
X1496702D01*
G01X1489441Y1544505D02*
X1489648Y1547243D01*
G01X1492984Y1542459D02*
Y1540683D01*
X1493372Y1540295D01*
G01X1492984Y1542459D02*
Y1543324D01*
X1494165Y1544505D01*
G01X1488260Y1542459D02*
Y1540683D01*
X1488648Y1540295D01*
G01X1488260Y1542459D02*
Y1543324D01*
X1489441Y1544505D01*
G01X1483535Y1542459D02*
Y1540683D01*
X1483923Y1540295D01*
G01X1483535Y1542459D02*
Y1543324D01*
X1484716Y1544505D01*
G01X1497708Y1542459D02*
Y1540683D01*
X1498096Y1540295D01*
G01X1498890Y1544505D02*
X1497708Y1543323D01*
Y1542459D01*
G01X1499097Y1555200D02*
X1496372Y1554453D01*
G01X1494372Y1555200D02*
X1491648Y1554453D01*
G01X1489648Y1555200D02*
X1486923Y1554453D01*
G01X1499097Y1561106D02*
X1496923Y1561853D01*
G01X1489648Y1561106D02*
X1492199Y1561853D01*
G01X1489648Y1561106D02*
X1487474Y1561853D01*
G01X1496372Y1554453D02*
X1494372Y1555200D01*
G01X1491648Y1554453D02*
X1489648Y1555200D01*
G01X1486923Y1554453D02*
X1484923Y1555200D01*
G01X1496923Y1561853D02*
X1494372Y1561106D01*
G01X1492199Y1561853D02*
X1494372Y1561106D01*
G01X1487474Y1561853D02*
X1484923Y1561106D01*
G01X1484716Y1571431D02*
X1484923Y1569063D01*
G01X1483535Y1573477D02*
X1484716Y1571431D01*
G01X1483923Y1575641D02*
Y1573865D01*
X1483535Y1573477D01*
G01X1489441Y1571431D02*
X1489648Y1569063D01*
G01X1488260Y1573477D02*
X1489441Y1571431D01*
G01X1488648Y1575641D02*
Y1573865D01*
X1488260Y1573477D01*
G01X1494165Y1571431D02*
X1494372Y1569063D01*
G01X1492984Y1573477D02*
X1494165Y1571431D01*
G01X1493372Y1575641D02*
Y1573865D01*
X1492984Y1573477D01*
G01X1497708D02*
X1498890Y1571431D01*
G01X1498096Y1575641D02*
Y1573865D01*
X1497708Y1573477D01*
G01X1499097Y1569063D02*
X1496422D01*
G01X1494372D02*
X1491698D01*
G01X1489648D02*
X1486973D01*
G01X1496422D02*
X1494372D01*
G01X1491698D02*
X1489648D01*
G01X1486973D02*
X1484923D01*
G01X1507644Y554372D02*
X1510039Y551977D01*
X1510682D01*
G01X1503832Y556477D02*
X1505429D01*
X1507534Y554372D01*
X1507644D01*
G01X1508142Y708215D02*
Y707296D01*
X1510913Y704525D01*
G01Y701915D02*
X1508045D01*
G01X1498890Y1544505D02*
X1499097Y1547243D01*
G01X1501427D02*
X1499097D01*
G01X1501427D02*
X1503821D01*
G01D02*
X1506151D01*
G01D02*
X1508545D01*
G01D02*
X1508338Y1544505D01*
G01X1510875Y1547243D02*
X1508545D01*
G01X1513270D02*
X1510875D01*
G01X1513063Y1544505D02*
X1513270Y1547243D01*
G01X1503614Y1544505D02*
X1503821Y1547243D01*
G01X1507157Y1542459D02*
Y1540683D01*
X1507545Y1540295D01*
G01X1507157Y1542459D02*
Y1543324D01*
X1508338Y1544505D01*
G01X1502433Y1542459D02*
Y1540683D01*
X1502821Y1540295D01*
G01X1502433Y1542459D02*
Y1543324D01*
X1503614Y1544505D01*
G01X1511882Y1542459D02*
Y1540683D01*
X1512270Y1540295D01*
G01X1511882Y1542459D02*
Y1543324D01*
X1513063Y1544505D01*
G01X1513270Y1555200D02*
X1510545Y1554453D01*
G01X1508545Y1555200D02*
X1505821Y1554453D01*
G01X1503821Y1555200D02*
X1501096Y1554453D01*
G01X1513270Y1561106D02*
X1511096Y1561853D01*
G01X1508545Y1561106D02*
X1506372Y1561853D01*
G01X1503821Y1561106D02*
X1501647Y1561853D01*
G01X1510545Y1554453D02*
X1508545Y1555200D01*
G01X1505821Y1554453D02*
X1503821Y1555200D01*
G01X1501096Y1554453D02*
X1499097Y1555200D01*
G01X1511096Y1561853D02*
X1508545Y1561106D01*
G01X1506372Y1561853D02*
X1503821Y1561106D01*
G01X1501647Y1561853D02*
X1499097Y1561106D01*
G01X1503821Y1569063D02*
X1503614Y1571431D01*
G01D02*
X1502433Y1573477D01*
G01D02*
X1502821Y1573865D01*
Y1575641D01*
G01X1498890Y1571431D02*
X1499097Y1569063D01*
G01X1508338Y1571431D02*
X1508545Y1569063D01*
G01X1507157Y1573477D02*
X1508338Y1571431D01*
G01X1507545Y1575641D02*
Y1573865D01*
X1507157Y1573477D01*
G01X1513270Y1569063D02*
X1513063Y1571431D01*
G01D02*
X1511882Y1573477D01*
G01D02*
X1512270Y1573865D01*
Y1575641D01*
G01X1513270Y1569063D02*
X1510595D01*
G01X1508545D02*
X1505871D01*
G01X1503821D02*
X1501147D01*
G01X1510595D02*
X1508545D01*
G01X1505871D02*
X1503821D01*
G01X1501147D02*
X1499097D01*
G01X1545740Y877481D02*
X1548301Y874920D01*
Y864887D01*
X1541679Y858265D01*
X1531593D01*
X1518527Y845199D01*
Y831258D01*
X1529782Y820003D01*
X1545147D01*
X1550097Y824953D01*
X1559522D01*
X1606694Y777781D01*
Y749617D01*
X1615271Y741040D01*
X1638230D01*
X1644752Y734518D01*
Y723556D01*
X1666962Y701346D01*
Y696658D01*
X1665962Y695658D01*
X1663019D01*
X1662377Y696300D01*
G01X1547460Y878124D02*
X1549801Y875783D01*
Y864265D01*
X1542301Y856765D01*
X1532215D01*
X1520027Y844577D01*
Y831880D01*
X1530404Y821503D01*
X1544525D01*
X1549475Y826453D01*
X1560144D01*
X1608194Y778403D01*
Y750239D01*
X1615893Y742540D01*
X1638852D01*
X1646252Y735140D01*
Y724178D01*
X1668462Y701968D01*
Y696036D01*
X1666584Y694158D01*
X1663235D01*
X1662377Y693300D01*
G01X1515600Y1547243D02*
X1513270D01*
G01X1517994D02*
X1515600D01*
G01X1517787Y1544505D02*
X1517994Y1547243D01*
G01D02*
X1520324D01*
G01D02*
X1522719D01*
G01D02*
X1525049D01*
G01X1527443D02*
X1525049D01*
G01X1527236Y1544505D02*
X1527443Y1547243D01*
G01D02*
X1529773D01*
G01X1522719D02*
X1522512Y1544505D01*
G01X1516606Y1542459D02*
Y1540683D01*
X1516994Y1540295D01*
G01X1516606Y1542459D02*
Y1543324D01*
X1517787Y1544505D01*
G01X1521330Y1542459D02*
Y1540683D01*
X1521718Y1540295D01*
G01X1522512Y1544505D02*
X1521330Y1543323D01*
Y1542459D01*
G01X1526055D02*
Y1540683D01*
X1526443Y1540295D01*
G01X1526055Y1542459D02*
Y1543324D01*
X1527236Y1544505D01*
G01X1527443Y1555200D02*
X1524719Y1554453D01*
G01X1522719Y1555200D02*
X1519994Y1554453D01*
G01X1517994Y1555200D02*
X1515270Y1554453D01*
G01X1527443Y1561106D02*
X1525270Y1561853D01*
G01X1522719Y1561106D02*
X1520545Y1561853D01*
G01X1517994Y1561106D02*
X1515821Y1561853D01*
G01X1524719Y1554453D02*
X1522719Y1555200D01*
G01X1519994Y1554453D02*
X1517994Y1555200D01*
G01X1515270Y1554453D02*
X1513270Y1555200D01*
G01X1525270Y1561853D02*
X1522719Y1561106D01*
G01X1520545Y1561853D02*
X1517994Y1561106D01*
G01X1515821Y1561853D02*
X1513270Y1561106D01*
G01X1529443Y1554453D02*
X1527443Y1555200D01*
G01X1529994Y1561853D02*
X1527443Y1561106D01*
G01X1522512Y1571431D02*
X1522719Y1569063D01*
G01X1521330Y1573477D02*
X1522512Y1571431D01*
G01X1521718Y1575641D02*
Y1573865D01*
X1521330Y1573477D01*
G01X1517787Y1571431D02*
X1517994Y1569063D01*
G01X1516606Y1573477D02*
X1517787Y1571431D01*
G01X1516994Y1575641D02*
Y1573865D01*
X1516606Y1573477D01*
G01X1527236Y1571431D02*
X1527443Y1569063D01*
G01X1526055Y1573477D02*
X1527236Y1571431D01*
G01X1526443Y1575641D02*
Y1573865D01*
X1526055Y1573477D01*
G01X1527443Y1569063D02*
X1524769D01*
G01X1522719D02*
X1520044D01*
G01X1517994D02*
X1515320D01*
G01X1524769D02*
X1522719D01*
G01X1520044D02*
X1517994D01*
G01X1515320D02*
X1513270D01*
G01X1529493D02*
X1527443D01*
G01X1542675Y547341D02*
Y543868D01*
X1542902Y543641D01*
G01X1543713Y701915D02*
X1540845D01*
G01X1533129Y1548083D02*
X1532289Y1547243D01*
G01X1535175Y1546902D02*
X1534310D01*
X1533129Y1548083D01*
G01X1535175Y1549264D02*
Y1546902D01*
G01X1533129Y1548083D02*
Y1549580D01*
X1535175Y1551626D01*
G01X1529773Y1547243D02*
X1532289D01*
G01X1531960Y1544505D02*
X1530779Y1542459D01*
G01D02*
X1531167Y1542071D01*
Y1540295D01*
G01X1532289Y1547243D02*
Y1544834D01*
X1531960Y1544505D01*
G01X1535175Y1551626D02*
X1534188Y1554453D01*
G01X1535504Y1542459D02*
X1536685Y1544505D01*
G01X1535504Y1542459D02*
X1535368Y1542323D01*
Y1540355D01*
G01X1537468D02*
Y1542061D01*
X1537866Y1542459D01*
G01X1533129Y1557532D02*
X1532168Y1556571D01*
Y1555200D01*
G01X1533129Y1557532D02*
Y1559894D01*
G01D02*
X1533994D01*
X1535175Y1561075D01*
G01D02*
X1533994Y1562256D01*
X1533129D01*
G01X1537220Y1557532D02*
X1536582Y1556894D01*
X1533767D01*
X1533129Y1557532D01*
G01X1532168Y1555200D02*
X1529443Y1554453D01*
G01X1533129Y1559894D02*
X1529994Y1561853D01*
G01X1534188Y1554453D02*
X1532168Y1555200D01*
G01X1531960Y1571431D02*
X1532168Y1569063D01*
G01X1530779Y1573477D02*
X1531960Y1571431D01*
G01X1531167Y1575641D02*
Y1573865D01*
X1530779Y1573477D01*
G01X1540427Y1584550D02*
Y1583322D01*
X1542186Y1581563D01*
G01X1532168Y1569063D02*
X1529493D01*
G01X1534824D02*
X1532168D01*
G01X1542186Y1581563D02*
X1542876Y1582253D01*
Y1584499D01*
X1543627Y1585250D01*
G01X1536685Y1571431D02*
Y1572296D01*
X1535504Y1573477D01*
G01X1538585Y1571658D02*
X1538358Y1571431D01*
X1536685D01*
G01X1534067Y1584550D02*
Y1582178D01*
G01X1547590Y880670D02*
X1548381D01*
X1549428Y879623D01*
G01X1543890Y880670D02*
X1544681D01*
X1545728Y879623D01*
G01X1546921Y1160945D02*
X1547968Y1161992D01*
X1548759D01*
G01X1545071Y1157756D02*
X1545862D01*
X1547155Y1159049D01*
X1547766Y1159302D01*
X1548914Y1159916D01*
X1549765Y1160485D01*
X1550801Y1161521D01*
Y1171018D01*
X1550551Y1171268D01*
Y1185970D01*
X1554477Y1189896D01*
Y1193836D01*
X1600032Y1239391D01*
Y1248081D01*
X1618177Y1266226D01*
Y1327894D01*
X1612900Y1333171D01*
X1608836D01*
X1608418Y1333589D01*
G01X1545071Y1164134D02*
X1545862D01*
X1546909Y1165181D01*
G01X1608418Y1331089D02*
X1609000Y1331671D01*
X1612278D01*
X1616677Y1327272D01*
Y1266848D01*
X1598532Y1248703D01*
Y1240013D01*
X1552977Y1194458D01*
Y1190518D01*
X1549051Y1186592D01*
Y1171268D01*
X1548801Y1171018D01*
Y1167073D01*
X1546909Y1165181D01*
G01X1552496Y1536100D02*
Y1533254D01*
X1552668Y1533082D01*
G01X1557696Y1538000D02*
X1559542D01*
X1560622Y1539080D01*
G01X1555047Y1556850D02*
X1558247D01*
G01D02*
Y1558350D01*
X1556847Y1559750D01*
G01X1566442Y301816D02*
X1564036D01*
X1563620Y301400D01*
X1561729D01*
G01X1564506Y310334D02*
Y310300D01*
X1562826Y308620D01*
Y303869D01*
X1562326Y303369D01*
X1561729D01*
G01X1564506Y313734D02*
X1561792Y311020D01*
Y309708D01*
X1559170Y307086D01*
Y305928D01*
G01X1571497Y1543800D02*
X1573597D01*
G01X1571497Y1547420D02*
X1573597D01*
G01X1571497Y1551040D02*
X1573597D01*
G01X1571542Y1554331D02*
Y1551085D01*
X1571497Y1551040D01*
G01X1571542Y1561731D02*
X1574089D01*
G01X1568253Y1565851D02*
Y1564760D01*
X1567089Y1563596D01*
G01X1573975Y679975D02*
X1576843D01*
G01X1583657Y1552807D02*
Y1550445D01*
G01D02*
Y1548225D01*
X1584639Y1547243D01*
G01X1584432Y1544505D02*
X1584639Y1544712D01*
Y1547243D01*
G01D02*
X1586969D01*
G01D02*
X1589363D01*
G01X1585797Y1552195D02*
X1585185Y1552807D01*
X1583657D01*
G01X1583251Y1542459D02*
Y1543324D01*
X1584432Y1544505D01*
G01X1583251Y1542459D02*
Y1540709D01*
X1583056Y1540514D01*
G01X1582070Y1544505D02*
X1579707D01*
G01X1580889Y1542459D02*
Y1541311D01*
X1580940Y1541260D01*
Y1540460D01*
G01X1579707Y1544505D02*
X1578689Y1543487D01*
Y1540509D01*
G01X1583657Y1569343D02*
Y1566980D01*
G01D02*
Y1564618D01*
G01X1584639Y1560880D02*
X1583657Y1561862D01*
G01X1584639Y1560880D02*
X1583657Y1559898D01*
Y1557532D01*
G01X1581612Y1556351D02*
X1582793Y1557532D01*
X1583657D01*
G01X1579566D02*
X1581612Y1556351D01*
G01X1579566Y1557532D02*
X1577688Y1556810D01*
G01X1583657Y1555169D02*
Y1557532D01*
G01Y1552807D02*
Y1555169D01*
G01Y1564618D02*
Y1561862D01*
G01X1581612Y1561075D02*
X1580397Y1561995D01*
X1579566Y1562256D01*
G01D02*
X1577688Y1561725D01*
G01X1583657Y1561862D02*
X1582399D01*
X1581612Y1561075D01*
G01X1589363Y1555200D02*
X1586639Y1554453D01*
G01X1589363Y1561106D02*
X1587190Y1561853D01*
G01X1586639Y1554453D02*
X1583657Y1555169D01*
G01X1587190Y1561853D02*
X1584639Y1560880D01*
G01X1583657Y1569343D02*
Y1570656D01*
X1584432Y1571431D01*
G01D02*
X1583251Y1573477D01*
G01X1583160Y1575425D02*
Y1573568D01*
X1583251Y1573477D01*
G01X1576046Y1583788D02*
Y1579940D01*
X1576653Y1579333D01*
G01X1589363Y1569063D02*
X1586688D01*
G01D02*
Y1569343D01*
X1583657D01*
G01X1579089Y1573317D02*
Y1572755D01*
X1579707Y1572137D01*
Y1571431D01*
G01X1583160Y1577625D02*
X1582536D01*
X1580889Y1575978D01*
Y1573477D01*
G01X1582070Y1571431D02*
X1580889Y1573477D01*
G01X1583523Y1587939D02*
Y1585567D01*
G01X1579246Y1583788D02*
X1576046D01*
G01X1601874Y531226D02*
X1604890D01*
G01X1589363Y1547243D02*
X1589156Y1544505D01*
G01X1591693Y1547243D02*
X1589363D01*
G01X1591693D02*
X1594088D01*
G01D02*
X1593881Y1544505D01*
G01X1596418Y1547243D02*
X1594088D01*
G01X1596418D02*
X1598812D01*
G01D02*
X1598605Y1544505D01*
G01X1601142Y1547243D02*
X1598812D01*
G01X1601142D02*
X1603537D01*
G01X1587975Y1542459D02*
Y1540683D01*
X1588363Y1540295D01*
G01X1587975Y1542459D02*
Y1543324D01*
X1589156Y1544505D01*
G01X1597424Y1542459D02*
Y1540683D01*
X1597812Y1540295D01*
G01X1592700Y1542459D02*
Y1540683D01*
X1593088Y1540295D01*
G01X1592700Y1542459D02*
Y1543324D01*
X1593881Y1544505D01*
G01X1597424Y1542459D02*
Y1543324D01*
X1598605Y1544505D01*
G01X1603537Y1555200D02*
X1600812Y1554453D01*
G01X1598812Y1555200D02*
X1596088Y1554453D01*
G01X1594088Y1555200D02*
X1591363Y1554453D01*
G01X1603537Y1561106D02*
X1601363Y1561853D01*
G01X1598812Y1561106D02*
X1596639Y1561853D01*
G01X1594088Y1561106D02*
X1591914Y1561853D01*
G01X1600812Y1554453D02*
X1598812Y1555200D01*
G01X1596088Y1554453D02*
X1594088Y1555200D01*
G01X1591363Y1554453D02*
X1589363Y1555200D01*
G01X1601363Y1561853D02*
X1598812Y1561106D01*
G01X1596639Y1561853D02*
X1594088Y1561106D01*
G01X1591914Y1561853D02*
X1589363Y1561106D01*
G01X1602148Y1573477D02*
X1603330Y1571431D01*
G01X1602536Y1575641D02*
Y1573865D01*
X1602148Y1573477D01*
G01X1598605Y1571431D02*
X1598812Y1569063D01*
G01X1597424Y1573477D02*
X1598605Y1571431D01*
G01X1597812Y1575641D02*
Y1573865D01*
X1597424Y1573477D01*
G01X1593881Y1571431D02*
X1594088Y1569063D01*
G01X1592700Y1573477D02*
X1593881Y1571431D01*
G01X1593088Y1575641D02*
Y1573865D01*
X1592700Y1573477D01*
G01X1589363Y1569063D02*
X1589156Y1571431D01*
G01D02*
X1587975Y1573477D01*
G01D02*
X1588363Y1573865D01*
Y1575641D01*
G01X1603537Y1569063D02*
X1600862D01*
G01X1598812D02*
X1596138D01*
G01X1594088D02*
X1591413D01*
G01X1600862D02*
X1598812D01*
G01X1596138D02*
X1594088D01*
G01X1591413D02*
X1589363D01*
G01X1609286Y547098D02*
X1605286D01*
G01X1604621Y596563D02*
Y561765D01*
X1603168Y560312D01*
Y548718D01*
X1604788Y547098D01*
X1605286D01*
G01X1616084Y549105D02*
X1614077Y547098D01*
X1613355D01*
G01X1617322Y549664D02*
X1616643D01*
X1616084Y549105D01*
G01X1609286Y550248D02*
X1609590D01*
X1612740Y547098D01*
X1613355D01*
G01X1605286Y550248D02*
X1609286D01*
G01X1606380Y598322D02*
X1604621Y596563D01*
G01X1606380Y598322D02*
X1609044Y600986D01*
G01X1606745Y646206D02*
X1609613D01*
G01X1603537Y1547243D02*
X1603330Y1544505D01*
G01X1605867Y1547243D02*
X1603537D01*
G01X1605867D02*
X1608261D01*
G01D02*
X1608054Y1544505D01*
G01X1610591Y1547243D02*
X1608261D01*
G01X1610591D02*
X1612985D01*
G01D02*
X1612778Y1544505D01*
G01X1615315Y1547243D02*
X1612985D01*
G01X1615315D02*
X1617710D01*
G01X1616322Y1542459D02*
Y1540683D01*
X1616710Y1540295D01*
G01X1616322Y1542459D02*
Y1543324D01*
X1617503Y1544505D01*
G01X1611597Y1542459D02*
Y1540683D01*
X1611985Y1540295D01*
G01X1611597Y1542459D02*
Y1543324D01*
X1612778Y1544505D01*
G01X1617710Y1555200D02*
X1614985Y1554453D01*
G01X1612985Y1555200D02*
X1610261Y1554453D01*
G01X1608261Y1555200D02*
X1605536Y1554453D01*
G01X1617710Y1561106D02*
X1615536Y1561853D01*
G01X1612985Y1561106D02*
X1610812Y1561853D01*
G01X1608261Y1561106D02*
X1606087Y1561853D01*
G01X1614985Y1554453D02*
X1612985Y1555200D01*
G01X1610261Y1554453D02*
X1608261Y1555200D01*
G01X1605536Y1554453D02*
X1603537Y1555200D01*
G01X1615536Y1561853D02*
X1612985Y1561106D01*
G01X1610812Y1561853D02*
X1608261Y1561106D01*
G01X1606087Y1561853D02*
X1603537Y1561106D01*
G01X1616322Y1573477D02*
X1617503Y1571431D01*
G01X1616710Y1575641D02*
Y1573865D01*
X1616322Y1573477D01*
G01X1612778Y1571431D02*
X1612985Y1569063D01*
G01X1611597Y1573477D02*
X1612778Y1571431D01*
G01X1611985Y1575641D02*
Y1573865D01*
X1611597Y1573477D01*
G01X1608261Y1569063D02*
X1608054Y1571431D01*
G01D02*
X1606873Y1573477D01*
G01D02*
X1607261Y1573865D01*
Y1575641D01*
G01X1603330Y1571431D02*
X1603537Y1569063D01*
G01X1617710D02*
X1615035D01*
G01X1612985D02*
X1610311D01*
G01X1608261D02*
X1605587D01*
G01X1615035D02*
X1612985D01*
G01X1610311D02*
X1608261D01*
G01X1605587D02*
X1603537D01*
G01X1629833Y1312091D02*
X1628333Y1310591D01*
X1626833D01*
X1626333Y1311091D01*
G01X1634758Y1311874D02*
X1633112Y1310228D01*
X1631696D01*
X1629833Y1312091D01*
G01X1634758Y1306874D02*
X1633041Y1308591D01*
X1631211D01*
X1630711Y1309091D01*
X1627333D01*
X1626333Y1308091D01*
G01X1617710Y1547243D02*
X1617503Y1544505D01*
G01X1620040Y1547243D02*
X1617710D01*
G01X1620040D02*
X1622434D01*
G01D02*
X1622227Y1544505D01*
G01X1624764Y1547243D02*
X1622434D01*
G01X1624764D02*
X1627159D01*
G01D02*
X1626952Y1544505D01*
G01X1629489Y1547243D02*
X1627159D01*
G01X1629489D02*
X1631883D01*
G01D02*
X1631676Y1544505D01*
G01X1634213Y1547243D02*
X1631883D01*
G01X1621046Y1542459D02*
Y1540683D01*
X1621434Y1540295D01*
G01X1621046Y1542459D02*
Y1543324D01*
X1622227Y1544505D01*
G01X1630495Y1542459D02*
Y1540683D01*
X1630883Y1540295D01*
G01X1630495Y1542459D02*
Y1543324D01*
X1631676Y1544505D01*
G01X1625770Y1542459D02*
Y1540683D01*
X1626158Y1540295D01*
G01X1626952Y1544505D02*
X1625770Y1543323D01*
Y1542459D01*
G01X1631883Y1555200D02*
X1629158Y1554453D01*
G01X1627159Y1555200D02*
X1624434Y1554453D01*
G01X1622434Y1555200D02*
X1619710Y1554453D01*
G01X1627159Y1561106D02*
X1629709Y1561853D01*
G01X1627159Y1561106D02*
X1624985Y1561853D01*
G01X1622434Y1561106D02*
X1620261Y1561853D01*
G01X1629158Y1554453D02*
X1627159Y1555200D01*
G01X1624434Y1554453D02*
X1622434Y1555200D01*
G01X1619710Y1554453D02*
X1617710Y1555200D01*
G01X1629709Y1561853D02*
X1631883Y1561106D01*
G01X1624985Y1561853D02*
X1622434Y1561106D01*
G01X1620261Y1561853D02*
X1617710Y1561106D01*
G01X1633883Y1554453D02*
X1631883Y1555200D01*
G01X1634434Y1561853D02*
X1631883Y1561106D01*
G01X1631676Y1571431D02*
X1631883Y1569063D01*
G01X1630495Y1573477D02*
X1631676Y1571431D01*
G01X1630883Y1575641D02*
Y1573865D01*
X1630495Y1573477D01*
G01X1626952Y1571431D02*
X1627159Y1569063D01*
G01X1625770Y1573477D02*
X1626952Y1571431D01*
G01X1626158Y1575641D02*
Y1573865D01*
X1625770Y1573477D01*
G01X1617503Y1571431D02*
X1617710Y1569063D01*
G01X1622434D02*
X1622227Y1571431D01*
G01D02*
X1621046Y1573477D01*
G01D02*
X1621434Y1573865D01*
Y1575641D01*
G01X1631883Y1569063D02*
X1629209D01*
G01X1627159D02*
X1624484D01*
G01X1622434D02*
X1619760D01*
G01X1629209D02*
X1627159D01*
G01X1624484D02*
X1622434D01*
G01X1619760D02*
X1617710D01*
G01X1633933D02*
X1631883D01*
G01X1632560Y560957D02*
X1635401D01*
X1635697Y561253D01*
G01X1639745Y627206D02*
X1642613D01*
G01X1646708Y695822D02*
X1651959D01*
G01X1644001Y1408069D02*
Y1413047D01*
G01X1641065Y1403393D02*
X1637299D01*
X1634327Y1406365D01*
G01X1637915Y1410398D02*
X1637878Y1410435D01*
Y1411851D01*
X1639685Y1413658D01*
X1640503D01*
X1641039Y1414194D01*
G01X1634327Y1409515D02*
X1635210Y1410398D01*
X1637915D01*
G01X1641065D02*
Y1406393D01*
G01X1642393Y1413350D02*
X1641065Y1412022D01*
Y1410398D01*
G01X1634213Y1547243D02*
X1636607D01*
G01D02*
X1636400Y1544505D01*
G01X1638937Y1547243D02*
X1636607D01*
G01X1638937D02*
X1641332D01*
G01D02*
X1641125Y1544505D01*
G01X1643662Y1547243D02*
X1641332D01*
G01X1646056D02*
X1643662D01*
G01X1646056D02*
X1645849Y1544505D01*
G01X1648386Y1547243D02*
X1646056D01*
G01X1635219Y1542459D02*
Y1540683D01*
X1635607Y1540295D01*
G01X1635219Y1542459D02*
Y1543324D01*
X1636400Y1544505D01*
G01X1644668Y1542459D02*
Y1540683D01*
X1645056Y1540295D01*
G01X1644668Y1542459D02*
Y1543324D01*
X1645849Y1544505D01*
G01X1639944Y1542459D02*
Y1540683D01*
X1640332Y1540295D01*
G01X1639944Y1542459D02*
Y1543324D01*
X1641125Y1544505D01*
G01X1646056Y1555200D02*
X1643332Y1554453D01*
G01X1641332Y1555200D02*
X1638607Y1554453D01*
G01X1636607Y1555200D02*
X1633883Y1554453D01*
G01X1646056Y1561106D02*
X1643883Y1561853D01*
G01X1641332Y1561106D02*
X1639158Y1561853D01*
G01X1636607Y1561106D02*
X1634434Y1561853D01*
G01X1643332Y1554453D02*
X1641332Y1555200D01*
G01X1638607Y1554453D02*
X1636607Y1555200D01*
G01X1643883Y1561853D02*
X1641332Y1561106D01*
G01X1639158Y1561853D02*
X1636607Y1561106D01*
G01X1648056Y1554453D02*
X1646056Y1555200D01*
G01X1648607Y1561853D02*
X1646056Y1561106D01*
G01X1645849Y1571431D02*
X1646056Y1569063D01*
G01X1644668Y1573477D02*
X1645849Y1571431D01*
G01X1645056Y1575641D02*
Y1573865D01*
X1644668Y1573477D01*
G01X1641125Y1571431D02*
X1641332Y1569063D01*
G01X1639944Y1573477D02*
X1641125Y1571431D01*
G01X1640332Y1575641D02*
Y1573865D01*
X1639944Y1573477D01*
G01X1636400Y1571431D02*
X1636607Y1569063D01*
G01X1635219Y1573477D02*
X1636400Y1571431D01*
G01X1635607Y1575641D02*
Y1573865D01*
X1635219Y1573477D01*
G01X1646056Y1569063D02*
X1643382D01*
G01X1641332D02*
X1638657D01*
G01X1636607D02*
X1633933D01*
G01X1643382D02*
X1641332D01*
G01X1638657D02*
X1636607D01*
G01X1648106D02*
X1646056D01*
G01X1652810Y407402D02*
X1653642Y408234D01*
Y410265D01*
G01X1651959Y692672D02*
Y689800D01*
G01X1656573Y692328D02*
X1656229Y692672D01*
X1651959D01*
G01Y695822D02*
X1656095D01*
X1656591Y696318D01*
G01X1659741D02*
X1660359D01*
X1660377Y696300D01*
X1662377D01*
G01X1659723Y692328D02*
X1659905D01*
X1660877Y693300D01*
X1662377D01*
G01X1657284Y1399891D02*
X1660152D01*
G01X1648386Y1547243D02*
X1650781D01*
G01D02*
X1650574Y1544505D01*
G01X1653111Y1547243D02*
X1650781D01*
G01X1655505D02*
X1653111D01*
G01X1655505D02*
X1655298Y1544505D01*
G01X1657835Y1547243D02*
X1655505D01*
G01X1661191Y1548083D02*
X1660351Y1547243D01*
G01X1663237Y1546902D02*
X1662372D01*
X1661191Y1548083D01*
G01D02*
Y1549580D01*
X1663237Y1551626D01*
G01X1657835Y1547243D02*
X1660351D01*
G01X1660022Y1544505D02*
X1658841Y1542459D01*
G01D02*
X1659229Y1542071D01*
Y1540295D01*
G01X1660351Y1547243D02*
Y1544834D01*
X1660022Y1544505D01*
G01X1649392Y1542459D02*
Y1540683D01*
X1649780Y1540295D01*
G01X1650574Y1544505D02*
X1649392Y1543323D01*
Y1542459D01*
G01X1654117D02*
Y1540683D01*
X1654505Y1540295D01*
G01X1654117Y1542459D02*
Y1543324D01*
X1655298Y1544505D01*
G01X1661191Y1557532D02*
X1660230Y1556571D01*
Y1555200D01*
G01X1661191Y1557532D02*
Y1559894D01*
G01D02*
X1662056D01*
X1663237Y1561075D01*
G01D02*
X1662056Y1562256D01*
X1661191D01*
G01X1665282Y1557532D02*
X1664644Y1556894D01*
X1661829D01*
X1661191Y1557532D01*
G01X1663237Y1551626D02*
X1662250Y1554453D01*
G01X1660230Y1555200D02*
X1657505Y1554453D01*
G01X1655505Y1555200D02*
X1652781Y1554453D01*
G01X1650781Y1555200D02*
X1648056Y1554453D01*
G01X1661191Y1559894D02*
X1658056Y1561853D01*
G01X1655505Y1561106D02*
X1653332Y1561853D01*
G01X1650781Y1561106D02*
X1648607Y1561853D01*
G01X1662250Y1554453D02*
X1660230Y1555200D01*
G01X1657505Y1554453D02*
X1655505Y1555200D01*
G01X1652781Y1554453D02*
X1650781Y1555200D01*
G01X1658056Y1561853D02*
X1655505Y1561106D01*
G01X1653332Y1561853D02*
X1650781Y1561106D01*
G01X1650574Y1571431D02*
X1650781Y1569063D01*
G01X1649392Y1573477D02*
X1650574Y1571431D01*
G01X1649780Y1575641D02*
Y1573865D01*
X1649392Y1573477D01*
G01X1655298Y1571431D02*
X1655505Y1569063D01*
G01X1654117Y1573477D02*
X1655298Y1571431D01*
G01X1654505Y1575641D02*
Y1573865D01*
X1654117Y1573477D01*
G01X1660022Y1571431D02*
X1660230Y1569063D01*
G01X1658841Y1573477D02*
X1660022Y1571431D01*
G01X1659229Y1575641D02*
Y1573865D01*
X1658841Y1573477D01*
G01X1655505Y1569063D02*
X1652831D01*
G01X1650781D02*
X1648106D01*
G01X1655505D02*
X1657555D01*
G01X1660230D02*
X1662886D01*
G01X1652831D02*
X1650781D01*
G01X1657555D02*
X1660230D01*
G01X1662129Y1584550D02*
Y1582178D01*
G01X1674921Y1402041D02*
X1670879D01*
G01X1664237Y1426278D02*
X1664357D01*
X1664851Y1425784D01*
X1664948D01*
X1666249Y1424483D01*
G01X1671079Y1435069D02*
X1666681D01*
X1666181Y1434569D01*
Y1432215D01*
G01X1670147Y1438574D02*
X1672514D01*
X1674640Y1440700D01*
Y1445639D01*
G01X1681000Y1436575D02*
X1674991D01*
X1673485Y1435069D01*
X1671079D01*
G01X1676345Y1533604D02*
X1674142D01*
X1673630Y1533092D01*
G01X1663237Y1549264D02*
Y1546902D01*
G01X1663566Y1542459D02*
X1664747Y1544505D01*
G01X1663566Y1542459D02*
X1663430Y1542323D01*
Y1540355D01*
G01X1665530D02*
Y1542061D01*
X1665928Y1542459D01*
G01X1668489Y1584550D02*
Y1583322D01*
X1670248Y1581563D01*
G01X1671689Y1584550D02*
X1670938Y1583799D01*
Y1582253D01*
X1670248Y1581563D01*
G01X1664747Y1571431D02*
Y1572296D01*
X1663566Y1573477D01*
G01X1666647Y1571658D02*
X1666420Y1571431D01*
X1664747D01*
G01X1668268Y1670149D02*
X1670534D01*
G01X1671400Y1667350D02*
Y1669283D01*
X1670534Y1670149D01*
G01X1666101Y1675927D02*
Y1670216D01*
X1666168Y1670149D01*
G01D02*
Y1667688D01*
G01X1690066Y1399991D02*
X1692934D01*
G01X1681000Y1439925D02*
Y1436575D01*
G01X1682072Y1538135D02*
X1684172D01*
G01X1691975Y1570520D02*
X1691427D01*
X1689880Y1572067D01*
G01X1691975Y1573720D02*
X1691533D01*
X1689880Y1572067D01*
G01X1705120Y143610D02*
Y127962D01*
X1707990Y125092D01*
X1713418D01*
G01X1704869Y373773D02*
X1706100Y372542D01*
X1714381D01*
X1716940Y369983D01*
Y365787D01*
X1717765Y364962D01*
G01X1704869Y369773D02*
X1706138Y371042D01*
X1713759D01*
X1715440Y369361D01*
Y365787D01*
X1714615Y364962D01*
G01X1707703Y1402141D02*
X1703661D01*
G01X1721418Y125092D02*
Y121677D01*
X1720019Y120278D01*
X1716876D01*
G01X1717418Y125092D02*
X1716876Y124550D01*
Y120278D01*
G01X1725418Y125092D02*
X1721418D01*
G01Y128242D02*
Y135339D01*
X1721384Y135373D01*
G01X1717418Y128242D02*
Y135339D01*
X1717384Y135373D01*
G01X1713312Y141297D02*
X1716609D01*
G01X1714615Y364962D02*
X1715500Y364077D01*
Y361202D01*
X1717560Y359142D01*
X1720590D01*
X1724970Y363522D01*
X1728491D01*
X1729234Y364265D01*
X1729956D01*
X1730333Y363888D01*
X1731055D01*
X1732039Y364872D01*
G01X1717765Y364962D02*
X1717000Y364197D01*
Y361824D01*
X1718182Y360642D01*
X1719968D01*
X1724348Y365022D01*
X1727793D01*
X1728496Y365725D01*
Y366447D01*
X1729480Y367431D01*
G01X1729418Y125092D02*
X1732099Y122411D01*
X1732111D01*
X1735642Y118880D01*
Y116439D01*
G01X1733084Y128623D02*
Y125169D01*
X1737577Y120676D01*
Y116473D01*
X1737611Y116439D01*
G01X1729418Y125092D02*
X1725418D01*
G01X1729480Y373337D02*
X1727325D01*
G01X1729480Y369400D02*
X1727038D01*
X1726425Y368787D01*
G01X1733154Y1535250D02*
X1737979D01*
G01X1735779Y1530950D02*
X1733154D01*
G01X1736979Y1529750D02*
X1735779Y1530950D01*
G01X1730004Y1540968D02*
Y1535250D01*
G01X1726604Y1540970D02*
X1727961Y1539613D01*
Y1532993D01*
X1730004Y1530950D01*
G01X1737979Y1580480D02*
X1735354D01*
G01X1739279Y1587553D02*
X1739206Y1587480D01*
X1736579D01*
G01X1736479Y1584330D02*
X1739206D01*
X1739279Y1584403D01*
G01X1742038Y1653965D02*
Y1649587D01*
X1739837Y1647386D01*
X1730381D01*
G01X1735354Y1649456D02*
X1728451D01*
X1726381Y1647386D01*
G01X1740091Y92827D02*
X1741041Y91877D01*
Y90071D01*
X1740234Y89264D01*
G01X1739884Y85339D02*
X1741165Y86620D01*
Y88333D01*
X1740234Y89264D01*
G01X1743734Y85339D02*
X1742665Y86408D01*
Y88545D01*
X1743384Y89264D01*
G01D02*
X1742541Y90107D01*
Y91877D01*
X1743491Y92827D01*
G01X1745485Y116439D02*
Y119551D01*
X1745451Y119585D01*
G01X1747454Y116439D02*
Y121407D01*
X1747448Y121413D01*
G01X1742279Y1582868D02*
Y1586217D01*
X1743767Y1587705D01*
X1746079D01*
G01X1739279Y1584403D02*
Y1583378D01*
X1743969Y1578688D01*
Y1576925D01*
X1743979Y1576915D01*
Y1576876D01*
G01X1747963Y1647940D02*
Y1652565D01*
G01X1744463Y1651229D02*
Y1653165D01*
G01X1738888Y1653965D02*
Y1649840D01*
X1738504Y1649456D01*
G01X1752054Y1585905D02*
X1754479D01*
G01X1752963Y1647940D02*
Y1652665D01*
G01X1757963Y1651040D02*
Y1652565D01*
G01X1762963Y1651040D02*
Y1652101D01*
X1761799Y1653265D01*
G01X1763163Y1679965D02*
X1764163Y1680965D01*
X1767888D01*
Y1681702D01*
G01Y1678172D02*
X1766170D01*
X1765463Y1677465D01*
G01X1778500Y194399D02*
Y197793D01*
X1778556Y197849D01*
Y197899D01*
G01X1770404Y1577905D02*
Y1575330D01*
G01X1768353Y1666984D02*
Y1664930D01*
X1767888Y1664465D01*
G01X1768233Y1674057D02*
Y1670595D01*
X1768314Y1670514D01*
G01X1767888Y1685465D02*
Y1689965D01*
G01Y1681702D02*
Y1685465D01*
G01X1795219Y185910D02*
X1794292Y186837D01*
Y189732D01*
G01X1797719Y186610D02*
X1796261Y188068D01*
Y189732D01*
G01X1793444Y183719D02*
X1793761Y183402D01*
X1796694D01*
X1797011Y183719D01*
G01X1792324Y189732D02*
Y185323D01*
X1793444Y184203D01*
Y183719D01*
G01X1790355Y189682D02*
Y184263D01*
X1789811Y183719D01*
G01X1787943Y192193D02*
Y188130D01*
X1785866Y186053D01*
X1784915D01*
G01D02*
Y185721D01*
X1784079Y184885D01*
Y182463D01*
G01X1781650Y194399D02*
X1782982Y195731D01*
X1784969D01*
X1785368Y196130D01*
X1787993D01*
G01X1781706Y197899D02*
X1781756Y197849D01*
X1783985D01*
X1784234Y198098D01*
X1787993D01*
G01X1784601Y1578967D02*
Y1578641D01*
X1785711Y1577531D01*
G01X1791794Y1583107D02*
X1795794D01*
G01X1812174Y191599D02*
X1810174Y193599D01*
Y194198D01*
X1808242Y196130D01*
X1806497D01*
G01X1797011Y183719D02*
X1800511D01*
G01X1804135Y189682D02*
Y188478D01*
X1802570Y186913D01*
G01D02*
X1802942Y186541D01*
Y184888D01*
X1804111Y183719D01*
G01X1811274Y198098D02*
X1806497D01*
G01X1817674Y197599D02*
X1811773D01*
X1811274Y198098D01*
G01X1806497Y200067D02*
X1809012D01*
X1811543Y202598D01*
X1811827D01*
G01X1813224Y194699D02*
X1812174Y193649D01*
Y191599D01*
G01X1817674Y197599D02*
Y200588D01*
X1816308Y201954D01*
G01X1811827Y202598D02*
Y202750D01*
X1814181Y205104D01*
X1816308D01*
G01X1816190Y208879D02*
X1816308Y208761D01*
Y205104D01*
G54D132*
X277098Y185236D03*
X395208D03*
G54D150*
X334339Y171170D03*
X329221D03*
Y178610D03*
X331780D03*
X334339D03*
G54D213*
X595203Y167856D03*
Y170415D03*
Y172975D03*
Y175534D03*
X612801D03*
Y172975D03*
Y170415D03*
Y167856D03*
G54D12*
X19685Y-29134D03*
Y1803261D03*
X44000Y154200D03*
X31818Y1424257D03*
X441043Y1672205D03*
Y1718465D03*
X1416437Y1672205D03*
Y1718465D03*
X1800449Y126194D03*
X1804650Y1667292D03*
X2081889Y-29134D03*
Y1803261D03*
G54D303*
X1408817Y109037D03*
Y116911D03*
X1417635Y112974D03*
G54D114*
X190861Y120502D03*
X195979D03*
Y113022D03*
X193420D03*
X190861D03*
X203061Y120502D03*
X208179D03*
Y113022D03*
X205620D03*
X203061D03*
X409000Y1662260D03*
Y1669740D03*
X406441Y1662260D03*
Y1669740D03*
X411559Y1662260D03*
Y1669740D03*
X469975Y1720053D03*
Y1727533D03*
X467416Y1720053D03*
Y1727533D03*
X472534Y1720053D03*
Y1727533D03*
X1095489Y1703764D03*
Y1711244D03*
X1092930Y1703764D03*
Y1711244D03*
X1098048Y1703764D03*
Y1711244D03*
X1413622Y1625627D03*
X1418740D03*
X1416181D03*
X1418740Y1633107D03*
X1413622D03*
G54D21*
X14092Y292892D03*
Y295452D03*
X28068D03*
Y292892D03*
X44692D03*
Y295452D03*
X58668D03*
Y292892D03*
X1632822Y224597D03*
Y227157D03*
X1646798Y224597D03*
Y227157D03*
G54D105*
X162609Y400600D03*
X157491D03*
X160050Y406900D03*
X184271Y400060D03*
X186830Y406360D03*
X189389Y400060D03*
G54D231*
X720157Y1335285D03*
Y1361269D03*
X752939Y1335385D03*
Y1361369D03*
X1667890Y1334574D03*
Y1360558D03*
X1700672Y1334674D03*
Y1360658D03*
G54D312*
X1653642Y418139D03*
X1655610D03*
X1657578D03*
Y410265D03*
X1655610D03*
X1653642D03*
G54D123*
X242215Y144320D03*
Y146879D03*
Y149438D03*
X242255Y155044D03*
Y157603D03*
Y160162D03*
X249695Y149438D03*
Y146879D03*
Y144320D03*
X249735Y160162D03*
Y157603D03*
Y155044D03*
X449760Y1632441D03*
Y1635000D03*
Y1637559D03*
X457240D03*
Y1635000D03*
Y1632441D03*
X573388Y415846D03*
Y413287D03*
Y410728D03*
X565908D03*
Y413287D03*
Y415846D03*
Y421390D03*
Y423949D03*
Y426508D03*
X573388D03*
Y423949D03*
Y421390D03*
X624760Y416441D03*
Y419000D03*
X632240D03*
Y416441D03*
X624760Y421559D03*
X632240D03*
X643785Y299730D03*
Y297171D03*
X636305D03*
Y299730D03*
X643785Y302289D03*
X636305D03*
X646984Y507479D03*
X639504D03*
X646984Y512597D03*
Y510038D03*
X639504D03*
Y512597D03*
X657173Y1727718D03*
Y1730277D03*
Y1717056D03*
Y1722174D03*
Y1719615D03*
Y1732836D03*
X664653Y1727718D03*
Y1730277D03*
Y1717056D03*
Y1719615D03*
Y1722174D03*
Y1732836D03*
X689781Y1640773D03*
Y1643332D03*
Y1645891D03*
X697261Y1640773D03*
Y1645891D03*
Y1643332D03*
X761245Y167518D03*
Y170077D03*
Y172636D03*
X768725D03*
Y170077D03*
Y167518D03*
X1005169Y268884D03*
X997689D03*
X1005169Y263340D03*
Y260781D03*
Y258222D03*
X997689D03*
Y260781D03*
Y263340D03*
X1005169Y274002D03*
Y271443D03*
X997689D03*
Y274002D03*
X1107021Y1718991D03*
Y1724109D03*
Y1721550D03*
X1114501Y1718991D03*
Y1721550D03*
Y1724109D03*
X1194267Y1712261D03*
Y1709702D03*
Y1707143D03*
X1194314Y1726261D03*
Y1723702D03*
Y1721143D03*
X1201747Y1712261D03*
Y1707143D03*
Y1709702D03*
X1201794Y1726261D03*
Y1721143D03*
Y1723702D03*
X1301705Y77748D03*
Y80307D03*
Y82866D03*
X1309185D03*
Y80307D03*
Y77748D03*
X1425569Y1596545D03*
X1433049D03*
X1425569Y1599104D03*
Y1601663D03*
X1433049D03*
Y1599104D03*
X1582927Y536344D03*
Y533785D03*
Y531226D03*
X1590407Y536344D03*
Y531226D03*
Y533785D03*
X1670500Y1714318D03*
Y1711759D03*
X1663020D03*
Y1714318D03*
X1670500Y1729468D03*
Y1726909D03*
X1663020D03*
Y1729468D03*
X1670500Y1716877D03*
X1663020D03*
X1670500Y1732027D03*
X1663020D03*
X1705500Y1714318D03*
Y1711759D03*
X1698020D03*
Y1714318D03*
X1705500Y1716877D03*
X1698020D03*
X1737140Y1708265D03*
Y1710824D03*
Y1713383D03*
Y1723415D03*
Y1725974D03*
Y1728533D03*
X1744620Y1713383D03*
Y1710824D03*
Y1708265D03*
Y1728533D03*
Y1725974D03*
Y1723415D03*
X1810045Y164393D03*
Y161834D03*
Y159275D03*
X1802565D03*
Y161834D03*
Y164393D03*
X1827636Y159275D03*
Y161834D03*
Y164393D03*
X1835116D03*
Y161834D03*
Y159275D03*
G54D141*
X285260Y227776D03*
Y237224D03*
X289000D03*
X292740Y227776D03*
Y237224D03*
X642394Y128047D03*
X638654D03*
X634914D03*
Y137495D03*
X642394D03*
X761510Y1641559D03*
X757770D03*
X754030D03*
X761510Y1651007D03*
X754030D03*
X844760Y476724D03*
X852240D03*
Y467276D03*
X848500D03*
X844760D03*
G54D321*
X1796261Y189732D03*
X1794292D03*
X1792324D03*
X1802166D03*
X1800198D03*
X1798229D03*
G54D240*
X753500Y196547D03*
Y202453D03*
X1301710Y60741D03*
Y66647D03*
X1313620Y60741D03*
Y66647D03*
X1349350Y60741D03*
Y66647D03*
G54D222*
X676509Y145866D03*
G54D30*
X26272Y1461614D03*
Y1478936D03*
X50272Y1461614D03*
Y1478936D03*
X74272Y1461614D03*
Y1478936D03*
X98272Y1461614D03*
Y1478936D03*
X692761Y1301317D03*
Y1318639D03*
X716639Y1301357D03*
Y1318679D03*
X740639Y1301357D03*
Y1318679D03*
X764639Y1301357D03*
Y1318679D03*
X891423Y1234759D03*
Y1252081D03*
X915423Y1234759D03*
Y1252081D03*
X950407Y1234759D03*
Y1252081D03*
X974407Y1234759D03*
Y1252081D03*
X1313500Y624839D03*
Y642161D03*
X1655872Y1300929D03*
Y1318251D03*
X1679872Y1300929D03*
Y1318251D03*
X1703872Y1300929D03*
Y1318251D03*
X1727667Y1300929D03*
Y1318251D03*
X1747479Y1487944D03*
Y1505266D03*
X1771479Y1487944D03*
Y1505266D03*
X1795479Y1487944D03*
Y1505266D03*
X1819479Y1487944D03*
Y1505266D03*
G54D204*
X513651Y209692D03*
G54D340*
G01X50304Y58745D02*
X51367Y57682D01*
Y55974D01*
X50185Y54792D01*
Y51023D01*
X57595Y43613D01*
Y30645D01*
X63951Y24289D01*
X68304D01*
X70111Y26096D01*
Y29941D01*
X70657Y30487D01*
Y32756D01*
G01X54616Y58745D02*
X53556D01*
X52637Y57826D01*
Y55447D01*
X51455Y54265D01*
Y51550D01*
X52443Y50562D01*
X53504D01*
X54580Y49486D01*
Y48425D01*
X55654Y47351D01*
X56715D01*
X57791Y46275D01*
Y45214D01*
X58865Y44140D01*
Y40252D01*
X59615Y39502D01*
Y37982D01*
X58865Y37232D01*
Y35712D01*
X59615Y34962D01*
Y33442D01*
X58865Y32692D01*
Y31172D01*
X60631Y29406D01*
X61691D01*
X62767Y28330D01*
Y27270D01*
X64478Y25559D01*
X67777D01*
X68841Y26623D01*
Y29925D01*
X68295Y30471D01*
Y32756D01*
G01X869275Y750472D02*
X870546Y749201D01*
Y713363D01*
X870378Y712239D01*
X839357Y637349D01*
X792238Y590229D01*
X764751Y578845D01*
X730322Y571996D01*
X717478D01*
X676101Y554854D01*
X654119Y532873D01*
X551028Y490172D01*
X58682Y77046D01*
X57222Y73528D01*
X52555Y66543D01*
X51975Y65143D01*
Y63566D01*
X50304Y61895D01*
G01X50339Y416945D02*
X49758D01*
X47619Y419084D01*
G01X44967Y416860D02*
X45942D01*
X47618Y415184D01*
G01X50339Y413795D02*
Y412430D01*
X48317Y410408D01*
Y409407D01*
X49282Y408442D01*
X53938D01*
X56993Y405387D01*
Y401314D01*
X57342Y400965D01*
Y399799D01*
G01X44967Y413710D02*
Y412364D01*
X47047Y410284D01*
Y408880D01*
X48755Y407172D01*
X53411D01*
X55723Y404860D01*
Y401314D01*
X55374Y400965D01*
Y399799D01*
G01X50339Y420095D02*
Y422491D01*
X48383Y424447D01*
Y427829D01*
X49360Y428806D01*
G01X44967Y420010D02*
Y422357D01*
X47113Y424503D01*
Y427653D01*
X45960Y428806D01*
G01X57966Y1660959D02*
X57153D01*
X56804Y1661308D01*
X56478D01*
X55470Y1660300D01*
Y1658918D01*
X52486Y1655934D01*
X41987D01*
X40922Y1654869D01*
G01X57966Y1662927D02*
X57001D01*
X56652Y1662578D01*
X55951D01*
X54200Y1660827D01*
Y1659445D01*
X51959Y1657204D01*
X41987D01*
X40922Y1658269D01*
G01X57966Y1668833D02*
X57085D01*
X56736Y1669182D01*
X55332D01*
X54220Y1670294D01*
X53203D01*
X50015Y1673482D01*
X46343D01*
X45437Y1674388D01*
X42744D01*
X41679Y1673323D01*
G01X57966Y1670801D02*
X57241D01*
X56892Y1670452D01*
X55859D01*
X54747Y1671564D01*
X53730D01*
X50542Y1674752D01*
X46871D01*
X45965Y1675658D01*
X42744D01*
X41679Y1676723D01*
G01X61057Y62334D02*
X62222Y61169D01*
Y60523D01*
X62801Y59126D01*
X63893Y58034D01*
X73277Y51763D01*
X75184Y49856D01*
X75928Y48062D01*
Y47322D01*
X75382Y46776D01*
Y44370D01*
G01X64657Y62334D02*
X63492Y61169D01*
Y60776D01*
X63878Y59846D01*
X64703Y59021D01*
X74087Y52750D01*
X76261Y50576D01*
X77198Y48315D01*
Y47322D01*
X77744Y46776D01*
Y44370D01*
G01X873175Y750472D02*
X871816Y749113D01*
Y713268D01*
X871611Y711897D01*
X840434Y636629D01*
X792958Y589151D01*
X765122Y577623D01*
X730448Y570726D01*
X717731D01*
X676821Y553777D01*
X655018Y531974D01*
X655017D01*
X654839Y531796D01*
X551695Y489073D01*
X59737Y76272D01*
X58348Y72926D01*
X53681Y65941D01*
X53245Y64890D01*
Y63266D01*
X54616Y61895D01*
G01X61057Y64434D02*
X62222Y65599D01*
Y68275D01*
X61157Y69340D01*
G01X64657Y64434D02*
X63492Y65599D01*
Y68275D01*
X64557Y69340D01*
G01X65533Y410890D02*
Y409502D01*
X63573Y407542D01*
Y404663D01*
X60930Y402020D01*
Y401314D01*
X61280Y400964D01*
Y399799D01*
G01X60189Y410770D02*
Y409430D01*
X62303Y407316D01*
Y405190D01*
X59660Y402547D01*
Y401314D01*
X59311Y400965D01*
Y399799D01*
G01X65533Y414040D02*
X69411D01*
X69523Y413928D01*
G01X65533Y414040D02*
X64752D01*
X62812Y412100D01*
G01X56163Y413928D02*
X60189Y413920D01*
G01D02*
X60793D01*
X62813Y415940D01*
Y416000D01*
G01X65533Y417190D02*
Y418976D01*
X63450Y421059D01*
Y422959D01*
X64237Y423746D01*
X65533D01*
G01X60189Y417070D02*
Y418959D01*
X62180Y420950D01*
Y423090D01*
X61524Y423746D01*
X60182D01*
G01X64821Y430806D02*
X63493Y429478D01*
Y425786D01*
X65533Y423746D01*
G01X60921Y430806D02*
X62223Y429504D01*
Y425787D01*
X60182Y423746D01*
G01X60715Y522792D02*
X61363D01*
X61712Y523141D01*
X70530D01*
X72058Y521613D01*
G01X60715Y524760D02*
X61377D01*
X61726Y524411D01*
X70956D01*
X72058Y525513D01*
G01X60715Y532634D02*
X61295D01*
X61644Y532285D01*
X63331D01*
X66586Y535540D01*
Y539615D01*
X68869Y541898D01*
X70743D01*
X72058Y543213D01*
G01X60715Y530666D02*
X61367D01*
X61716Y531015D01*
X63858D01*
X67856Y535013D01*
Y539088D01*
X69396Y540628D01*
X70743D01*
X72058Y539313D01*
G01X77744Y32756D02*
Y30351D01*
X77198Y29805D01*
Y27544D01*
X78265Y26477D01*
G01X75382Y32756D02*
Y30351D01*
X75928Y29805D01*
Y27540D01*
X74865Y26477D01*
G01X72057Y68334D02*
X73222Y67169D01*
Y65800D01*
X74126Y63616D01*
X82078Y51716D01*
X83014Y48632D01*
Y47322D01*
X82468Y46776D01*
Y44370D01*
G01X75657Y68334D02*
X74492Y67169D01*
Y66053D01*
X75252Y64217D01*
X83239Y52265D01*
X84284Y48821D01*
Y47322D01*
X84831Y46775D01*
Y44370D01*
G01X72057Y70434D02*
X73222Y71599D01*
Y74274D01*
X72153Y75343D01*
G01X75657Y70434D02*
X74492Y71599D01*
Y74282D01*
X75553Y75343D01*
G01X75208Y521613D02*
X76523Y522928D01*
X79633D01*
X80948Y521613D01*
G01X75208Y525513D02*
X76523Y524198D01*
X79633D01*
X80948Y525513D01*
G01X80318Y543313D02*
X78903Y541898D01*
X76523D01*
X75208Y543213D01*
G01X80318Y539413D02*
X79103Y540628D01*
X76523D01*
X75208Y539313D01*
G01X85836Y1655143D02*
X84771Y1656208D01*
X80130D01*
X75030Y1661308D01*
X74000D01*
X73651Y1660959D01*
X72926D01*
G01X85836Y1658543D02*
X84771Y1657478D01*
X80657D01*
X75557Y1662578D01*
X74156D01*
X73807Y1662927D01*
X72926D01*
G01X87891Y1671121D02*
X86826Y1672186D01*
X83339D01*
X81791Y1670638D01*
X78077D01*
X76621Y1669182D01*
X74000D01*
X73651Y1668833D01*
X72926D01*
G01X87891Y1674521D02*
X86826Y1673456D01*
X82812D01*
X81264Y1671908D01*
X77550D01*
X76094Y1670452D01*
X74156D01*
X73807Y1670801D01*
X72926D01*
G01X85370Y19541D02*
X84284Y20627D01*
Y29805D01*
X84831Y30352D01*
Y32756D01*
G01X91917D02*
Y30351D01*
X91371Y29805D01*
Y27544D01*
X92438Y26477D01*
G01X82468Y32756D02*
Y30351D01*
X83014Y29805D01*
Y20585D01*
X81970Y19541D01*
G01X89555Y32756D02*
Y30351D01*
X90101Y29805D01*
Y27540D01*
X89038Y26477D01*
G01X96143Y19541D02*
X97188Y20586D01*
Y29805D01*
X96642Y30351D01*
Y32756D01*
G01X83057Y62334D02*
X84222Y61169D01*
Y60220D01*
X84492Y59566D01*
X87844Y54549D01*
X89140Y51807D01*
X90101Y48642D01*
Y47322D01*
X89555Y46776D01*
Y44370D01*
G01X86657Y62334D02*
X85492Y61169D01*
Y60472D01*
X85618Y60167D01*
X88952Y55177D01*
X90329Y52266D01*
X91371Y48831D01*
Y47322D01*
X91917Y46776D01*
Y44370D01*
G01X94057Y68334D02*
X95222Y67169D01*
Y65861D01*
X97188Y55975D01*
Y47322D01*
X96642Y46776D01*
Y44370D01*
G01X97657Y68334D02*
X96492Y67169D01*
Y65987D01*
X98458Y56101D01*
Y47322D01*
X99004Y46776D01*
Y44370D01*
G01X94057Y70434D02*
X95222Y71599D01*
Y74275D01*
X94157Y75340D01*
G01X83057Y64434D02*
X84222Y65599D01*
Y68275D01*
X83157Y69340D01*
G01X97657Y70434D02*
X96492Y71599D01*
Y74275D01*
X97557Y75340D01*
G01X86657Y64434D02*
X85492Y65599D01*
Y68275D01*
X86557Y69340D01*
G01X99543Y19541D02*
X98458Y20626D01*
Y29805D01*
X99005Y30352D01*
X99004Y30353D01*
Y32756D01*
G01X106090D02*
Y30351D01*
X105544Y29805D01*
Y27544D01*
X106611Y26477D01*
G01X103728Y32756D02*
Y30351D01*
X104274Y29805D01*
Y27540D01*
X103211Y26477D01*
G01X110316Y19541D02*
X111361Y20586D01*
Y29805D01*
X110815Y30351D01*
Y32756D01*
G01X116057Y68334D02*
X117222Y67169D01*
Y65946D01*
X114739Y59954D01*
X111361Y48821D01*
Y47322D01*
X110815Y46776D01*
Y44370D01*
G01X105057Y62334D02*
X106222Y61169D01*
Y58990D01*
X104274Y49200D01*
Y47322D01*
X103728Y46776D01*
Y44370D01*
G01X108657Y62334D02*
X107492Y61169D01*
Y58864D01*
X105544Y49074D01*
Y47322D01*
X106090Y46776D01*
Y44370D01*
G01X105057Y64434D02*
X106222Y65599D01*
Y68275D01*
X105157Y69340D01*
G01X108657Y64434D02*
X107492Y65599D01*
Y68275D01*
X108557Y69340D01*
G01X110770Y1662719D02*
Y1661938D01*
X112473Y1660235D01*
G01X110775Y1657752D02*
Y1658533D01*
X109073Y1660235D01*
G01X107620Y1662719D02*
X106220D01*
X104369Y1660868D01*
X103860D01*
X103859Y1660867D01*
X100507D01*
X99443Y1661931D01*
G01X107625Y1657752D02*
X106217D01*
X104372Y1659597D01*
X100509D01*
X99443Y1658531D01*
G01X109269Y1683513D02*
Y1684063D01*
X107569Y1685763D01*
G01X109269Y1688013D02*
Y1687463D01*
X110969Y1685763D01*
G01X111369Y1683513D02*
X113843D01*
X115434Y1685104D01*
X116633D01*
X125560Y1676177D01*
X128723D01*
X128876Y1676024D01*
X129932D01*
G01X107169Y1683513D02*
X104695D01*
X103217Y1684991D01*
X103216D01*
X103079Y1685128D01*
X101508D01*
X100443Y1684063D01*
G01X111369Y1688013D02*
X113897D01*
X115536Y1686374D01*
X117160D01*
X126087Y1677447D01*
X128931D01*
X129083Y1677599D01*
X129932D01*
G01X107169Y1688013D02*
X104695D01*
X103080Y1686398D01*
X101508D01*
X100443Y1687463D01*
G01X113716Y19541D02*
X112631Y20626D01*
Y29805D01*
X113178Y30352D01*
X113177Y30353D01*
Y32756D01*
G01X120264D02*
Y30351D01*
X119718Y29805D01*
Y27544D01*
X120785Y26477D01*
G01X117902Y32756D02*
Y30351D01*
X118448Y29805D01*
Y27540D01*
X117385Y26477D01*
G01X124490Y19541D02*
X125538Y20589D01*
Y29801D01*
X124988Y30351D01*
Y32756D01*
G01X138057Y68334D02*
X139222Y67169D01*
Y66307D01*
X139050Y65741D01*
X136660Y62162D01*
X132867Y57535D01*
X126582Y51242D01*
X125534Y48708D01*
Y47322D01*
X124988Y46776D01*
Y44370D01*
G01X127057Y62334D02*
X128222Y61169D01*
Y60531D01*
X128031Y60072D01*
X119922Y51963D01*
X119415Y51204D01*
X118448Y48870D01*
Y47322D01*
X117902Y46776D01*
Y44370D01*
G01X119657Y68334D02*
X118492Y67169D01*
Y65693D01*
X115937Y59525D01*
X112631Y48632D01*
Y47322D01*
X113177Y46776D01*
Y44370D01*
G01X130657Y62334D02*
X129492Y61169D01*
Y60277D01*
X129108Y59351D01*
X120909Y51153D01*
X120541Y50602D01*
X119718Y48617D01*
Y47322D01*
X120264Y46776D01*
Y44370D01*
G01X116057Y70434D02*
X117222Y71599D01*
Y74275D01*
X116157Y75340D01*
G01X119657Y70434D02*
X118492Y71599D01*
Y74275D01*
X119557Y75340D01*
G01X113920Y1662719D02*
X115551D01*
X117427Y1660843D01*
X118426D01*
X125581Y1667998D01*
X128789D01*
X128941Y1668150D01*
X129932D01*
G01X113925Y1657752D02*
X115336D01*
X117157Y1659573D01*
X118953D01*
X126108Y1666728D01*
X128789D01*
X128942Y1666575D01*
X129932D01*
G01X127890Y19541D02*
X126808Y20623D01*
Y29809D01*
X127350Y30351D01*
Y32756D01*
G01X141657Y68334D02*
X140492Y67169D01*
Y66118D01*
X140211Y65192D01*
X137682Y61405D01*
X133810Y56682D01*
X127659Y50523D01*
X126804Y48455D01*
Y47322D01*
X127350Y46776D01*
Y44370D01*
G01X138057Y70434D02*
X139222Y71599D01*
Y74275D01*
X138157Y75340D01*
G01X127057Y64434D02*
X128222Y65599D01*
Y68274D01*
X127153Y69343D01*
G01X141657Y70434D02*
X140492Y71599D01*
Y74275D01*
X141557Y75340D01*
G01X130657Y64434D02*
X129492Y65599D01*
Y68282D01*
X130553Y69343D01*
G01X139774Y1668150D02*
X141019D01*
X141171Y1667998D01*
X144909D01*
X148324Y1664583D01*
X149377D01*
X151004Y1666210D01*
X153711D01*
G01X139774Y1666575D02*
X140822D01*
X140975Y1666728D01*
X144382D01*
X147797Y1663313D01*
X149377D01*
X151035Y1661655D01*
X153711D01*
G01X152560Y1674239D02*
X151244D01*
X149307Y1676176D01*
X140917D01*
X140765Y1676024D01*
X139774D01*
G01X152560Y1679384D02*
X151268D01*
X149330Y1677446D01*
X140917D01*
X140764Y1677599D01*
X139774D01*
G01X156130Y32756D02*
Y30351D01*
X155584Y29805D01*
Y27544D01*
X156651Y26477D01*
G01X153768Y32756D02*
Y30351D01*
X154314Y29805D01*
Y27540D01*
X153251Y26477D01*
G01X149057Y62334D02*
X150222Y61169D01*
Y59313D01*
X150488Y57973D01*
X154314Y48738D01*
Y47322D01*
X153768Y46776D01*
Y44370D01*
G01X152657Y62334D02*
X151492Y61169D01*
Y59439D01*
X151710Y58344D01*
X155584Y48991D01*
Y47322D01*
X156130Y46776D01*
Y44370D01*
G01X149057Y64434D02*
X150222Y65599D01*
Y68274D01*
X149153Y69343D01*
G01X152657Y64434D02*
X151492Y65599D01*
Y68282D01*
X152553Y69343D01*
G01X155811Y1666210D02*
Y1665633D01*
X154111Y1663933D01*
G01X155811Y1661655D02*
Y1662233D01*
X157511Y1663933D01*
G01X155710Y1674239D02*
Y1675111D01*
X154010Y1676811D01*
G01X155710Y1679384D02*
Y1678511D01*
X157410Y1676811D01*
G01X170303Y32756D02*
Y30351D01*
X169757Y29805D01*
Y27544D01*
X170824Y26477D01*
G01X163756Y19541D02*
X162670Y20627D01*
Y29805D01*
X163216Y30351D01*
Y32756D01*
G01X167941D02*
Y30351D01*
X168487Y29805D01*
Y27540D01*
X167424Y26477D01*
G01X160356Y19541D02*
X161400Y20585D01*
Y29805D01*
X160854Y30351D01*
Y32756D01*
G01X172261Y62334D02*
X173426Y61169D01*
Y60475D01*
X172920Y58809D01*
X170124Y53578D01*
X168487Y49625D01*
Y47322D01*
X167941Y46776D01*
Y44370D01*
G01X161261Y68334D02*
X162426Y67169D01*
Y62571D01*
X161400Y52151D01*
Y47322D01*
X160854Y46776D01*
Y44370D01*
G01X175861Y62334D02*
X174696Y61169D01*
Y60286D01*
X174100Y58320D01*
X171274Y53034D01*
X169757Y49372D01*
Y47322D01*
X170303Y46776D01*
Y44370D01*
G01X164861Y68334D02*
X163696Y67169D01*
Y62508D01*
X162670Y52088D01*
Y47322D01*
X163216Y46776D01*
Y44370D01*
G01X161261Y70434D02*
X162426Y71599D01*
Y74275D01*
X161361Y75340D01*
G01X164861Y70434D02*
X163696Y71599D01*
Y74275D01*
X164761Y75340D01*
G01X169351Y1462595D02*
X170416Y1463660D01*
Y1466430D01*
X169251Y1467595D01*
G01X168113Y1483690D02*
X166948Y1482525D01*
X164178D01*
X163113Y1483590D01*
G01X168113Y1480090D02*
X166948Y1481255D01*
X164178D01*
X163113Y1480190D01*
G01Y1501990D02*
X164178Y1503055D01*
X166948D01*
X168113Y1501890D01*
G01X163113Y1505390D02*
X164178Y1504325D01*
X166948D01*
X168113Y1505490D01*
G01X168483Y1523431D02*
X169445Y1524393D01*
X170471D01*
X171433Y1523431D01*
G01X168483Y1526631D02*
X169451Y1525663D01*
X170465D01*
X171433Y1526631D01*
G01X162531Y1523331D02*
X163596Y1524396D01*
X165418D01*
X166383Y1523431D01*
G01X162531Y1526731D02*
X163596Y1525666D01*
X165418D01*
X166383Y1526631D01*
G01X157911Y1666210D02*
X160587D01*
X162245Y1664552D01*
X164461D01*
X165491Y1665582D01*
G01X157911Y1661655D02*
X160618D01*
X162245Y1663282D01*
X164391D01*
X165491Y1662182D01*
G01X158860Y1674239D02*
X160152D01*
X162090Y1676177D01*
X164236D01*
X165336Y1675077D01*
G01X158860Y1679384D02*
X160176D01*
X162099Y1677461D01*
Y1677447D01*
X164306D01*
X165336Y1678477D01*
G01X177929Y19541D02*
X176844Y20626D01*
Y29805D01*
X177391Y30352D01*
X177390Y30353D01*
Y32756D01*
G01X174529Y19541D02*
X175574Y20586D01*
Y29805D01*
X175028Y30351D01*
Y32756D01*
G01X183261Y68334D02*
X184426Y67169D01*
Y66078D01*
X176238Y51627D01*
X175574Y49106D01*
Y47322D01*
X175028Y46776D01*
Y44370D01*
G01X186861Y68334D02*
X185696Y67169D01*
Y65743D01*
X177425Y51144D01*
X176844Y48941D01*
Y47322D01*
X177390Y46776D01*
Y44370D01*
G01X183261Y70434D02*
X184426Y71599D01*
Y74274D01*
X183357Y75343D01*
G01X172261Y64434D02*
X173426Y65599D01*
Y68275D01*
X172361Y69340D01*
G01X186861Y70434D02*
X185696Y71599D01*
Y74282D01*
X186757Y75343D01*
G01X175861Y64434D02*
X174696Y65599D01*
Y68275D01*
X175761Y69340D01*
G01X179451Y1452895D02*
X178386Y1453960D01*
Y1456730D01*
X179551Y1457895D01*
G01X176051Y1452895D02*
X177116Y1453960D01*
Y1456730D01*
X175951Y1457895D01*
G01X172751Y1462595D02*
X171686Y1463660D01*
Y1466430D01*
X172851Y1467595D01*
G01X171433Y1523431D02*
X172350Y1524348D01*
X174418D01*
X175635Y1525565D01*
X177969D01*
G01X171433Y1526631D02*
X172446Y1525618D01*
X173891D01*
X175108Y1526835D01*
X178044D01*
G01X200264Y32756D02*
Y30351D01*
X199718Y29805D01*
Y27544D01*
X200785Y26477D01*
G01X197902Y32756D02*
Y30351D01*
X198448Y29805D01*
Y27540D01*
X197385Y26477D01*
G01X194261Y62334D02*
X195426Y61169D01*
Y58139D01*
X195613Y57193D01*
X197843Y51809D01*
X198448Y48771D01*
Y47322D01*
X197902Y46776D01*
Y44370D01*
G01X197861Y62334D02*
X196696Y61169D01*
Y58264D01*
X196835Y57564D01*
X199065Y52180D01*
X199718Y48897D01*
Y47322D01*
X200264Y46776D01*
Y44370D01*
G01X194261Y64434D02*
X195426Y65599D01*
Y68275D01*
X194361Y69340D01*
G01X197861Y64434D02*
X196696Y65599D01*
Y68275D01*
X197761Y69340D01*
G01X192851Y1472295D02*
X191786Y1473360D01*
Y1476130D01*
X192951Y1477295D01*
G01X199551Y1462595D02*
X198486Y1463660D01*
Y1466430D01*
X199651Y1467595D01*
G01X189451Y1472295D02*
X190516Y1473360D01*
Y1476130D01*
X189351Y1477295D01*
G01X196151Y1462595D02*
X197216Y1463660D01*
Y1466430D01*
X196051Y1467595D01*
G01X188066Y1607286D02*
X189231Y1606121D01*
Y1593445D01*
X188166Y1592380D01*
G01X200126Y1607286D02*
X201291Y1606121D01*
Y1593445D01*
X200226Y1592380D01*
G01X191666Y1607286D02*
X190501Y1606121D01*
Y1593445D01*
X191566Y1592380D01*
G01X188066Y1609386D02*
X189231Y1610551D01*
Y1623227D01*
X188166Y1624292D01*
G01X200126Y1609386D02*
X201291Y1610551D01*
Y1623227D01*
X200226Y1624292D01*
G01X191666Y1609386D02*
X190501Y1610551D01*
Y1623227D01*
X191566Y1624292D01*
G01X207890Y19541D02*
X206804Y20627D01*
Y29805D01*
X207351Y30352D01*
X207350Y30353D01*
Y32756D01*
G01X214437D02*
Y30351D01*
X213891Y29805D01*
Y27544D01*
X214958Y26477D01*
G01X204490Y19541D02*
X205534Y20585D01*
Y29805D01*
X204988Y30351D01*
Y32756D01*
G01X212075D02*
Y30351D01*
X212621Y29805D01*
Y27540D01*
X211558Y26477D01*
G01X216395Y62334D02*
X217560Y61169D01*
Y60422D01*
X212766Y48885D01*
X212621Y48161D01*
Y47322D01*
X212075Y46776D01*
Y44370D01*
G01X205395Y68334D02*
X206560Y67169D01*
Y64198D01*
X205534Y53778D01*
Y47322D01*
X204988Y46776D01*
Y44370D01*
G01X219995Y62334D02*
X218830Y61169D01*
Y60168D01*
X213987Y48513D01*
X213891Y48035D01*
Y47322D01*
X214437Y46776D01*
Y44370D01*
G01X208995Y68334D02*
X207830Y67169D01*
Y64135D01*
X206804Y53715D01*
Y47322D01*
X207350Y46776D01*
Y44370D01*
G01X205395Y70434D02*
X206560Y71599D01*
Y74275D01*
X205495Y75340D01*
G01X208995Y70434D02*
X207830Y71599D01*
Y74275D01*
X208895Y75340D01*
G01X206251Y1452895D02*
X205186Y1453960D01*
Y1456730D01*
X206351Y1457895D01*
G01X202851Y1452895D02*
X203916Y1453960D01*
Y1456730D01*
X202751Y1457895D01*
G01X212186Y1607286D02*
X213351Y1606121D01*
Y1593445D01*
X212286Y1592380D01*
G01X203726Y1607286D02*
X202561Y1606121D01*
Y1593445D01*
X203626Y1592380D01*
G01X215786Y1607286D02*
X214621Y1606121D01*
Y1593445D01*
X215686Y1592380D01*
G01X212186Y1609386D02*
X213351Y1610551D01*
Y1623227D01*
X212286Y1624292D01*
G01X203726Y1609386D02*
X202561Y1610551D01*
Y1623227D01*
X203626Y1624292D01*
G01X215786Y1609386D02*
X214621Y1610551D01*
Y1623227D01*
X215686Y1624292D01*
G01X222063Y19541D02*
X220978Y20626D01*
Y29805D01*
X221525Y30352D01*
X221524Y30353D01*
Y32756D01*
G01X218663Y19541D02*
X219708Y20586D01*
Y29805D01*
X219161Y30352D01*
Y32756D01*
G01X228610D02*
Y30351D01*
X228064Y29805D01*
Y27544D01*
X229131Y26477D01*
G01X226248Y32756D02*
Y30351D01*
X226794Y29805D01*
Y27540D01*
X225731Y26477D01*
G01X227395Y68334D02*
X228560Y67169D01*
Y66511D01*
X227047Y62861D01*
X221273Y52060D01*
X219707Y48279D01*
Y47322D01*
X219161Y46776D01*
Y44370D01*
G01X230995Y68334D02*
X229830Y67169D01*
Y66258D01*
X228197Y62317D01*
X222423Y51516D01*
X220977Y48026D01*
Y47322D01*
X221524Y46775D01*
Y44370D01*
G01X228610D02*
Y46774D01*
X228611Y46775D01*
X228064Y47322D01*
Y49586D01*
X229127Y50649D01*
G01X226248Y44370D02*
Y46776D01*
X226794Y47322D01*
Y49582D01*
X225727Y50649D01*
G01X227395Y70434D02*
X228560Y71599D01*
Y74275D01*
X227495Y75340D01*
G01X216395Y64434D02*
X217560Y65599D01*
Y68274D01*
X216491Y69343D01*
G01X230995Y70434D02*
X229830Y71599D01*
Y74275D01*
X230895Y75340D01*
G01X219995Y64434D02*
X218830Y65599D01*
Y68282D01*
X219891Y69343D01*
G01X299939Y895563D02*
X293070Y888694D01*
Y852671D01*
X286509Y846110D01*
Y842871D01*
X239959Y796319D01*
X238363D01*
X237360Y795316D01*
G01X299039Y896461D02*
X299040D01*
X291800Y889221D01*
Y853198D01*
X285239Y846637D01*
Y843398D01*
X284158Y842317D01*
X283224D01*
X282141Y841234D01*
Y840300D01*
X239432Y797589D01*
X238433D01*
X237360Y798662D01*
G01X299039Y916879D02*
X296522D01*
X275800Y896157D01*
Y864376D01*
X245685Y834262D01*
X241213D01*
X240114Y833163D01*
X238396D01*
X237360Y832127D01*
G01X299039Y918149D02*
X295995D01*
X274530Y896684D01*
Y864903D01*
X245158Y835532D01*
X240686D01*
X239587Y834433D01*
X238400D01*
X237360Y835473D01*
G01X299161Y936526D02*
X291569D01*
X258530Y903487D01*
Y884275D01*
X244231Y869976D01*
X238398D01*
X237360Y868938D01*
G01X299161Y937796D02*
X291042D01*
X257260Y904014D01*
Y884802D01*
X243704Y871246D01*
X238398D01*
X237360Y872284D01*
G01X299033Y955526D02*
X281933D01*
X245474Y919067D01*
Y915531D01*
X240919Y910976D01*
Y908022D01*
X239666Y906769D01*
X238379D01*
X237360Y905750D01*
G01X299033Y956796D02*
X281406D01*
X244204Y919594D01*
Y916058D01*
X239649Y911503D01*
Y908549D01*
X239139Y908039D01*
X238417D01*
X237360Y909096D01*
G01X299039Y974479D02*
X263526D01*
X247150Y958103D01*
Y954057D01*
X241485Y948392D01*
Y945242D01*
X239762Y943519D01*
X238318D01*
X237360Y942561D01*
G01X299039Y975749D02*
X262999D01*
X245880Y958630D01*
Y954584D01*
X240215Y948919D01*
Y945769D01*
X239235Y944789D01*
X238478D01*
X237360Y945907D01*
G01X299848Y1068947D02*
X294353D01*
X291795Y1066389D01*
X263987D01*
X239517Y1090859D01*
X238799D01*
X237745Y1089805D01*
G01X299848Y1070217D02*
X293826D01*
X291268Y1067659D01*
X264514D01*
X240044Y1092129D01*
X238805D01*
X237783Y1093151D01*
G01X299039Y1087867D02*
X276745D01*
X242386Y1122226D01*
Y1124901D01*
X239594Y1127693D01*
X238376D01*
X237299Y1126616D01*
G01X299039Y1089137D02*
X277272D01*
X243656Y1122753D01*
Y1125428D01*
X240121Y1128963D01*
X238374D01*
X237375Y1129962D01*
G01X299039Y1106706D02*
X288203D01*
X258691Y1136218D01*
Y1147757D01*
X241943Y1164505D01*
X238377D01*
X237299Y1163427D01*
G01X299039Y1107976D02*
X288730D01*
X259961Y1136745D01*
Y1148284D01*
X242470Y1165775D01*
X238373D01*
X237375Y1166773D01*
G01X299039Y1125945D02*
X293585D01*
X276146Y1143384D01*
Y1165958D01*
X240786Y1201318D01*
X238379D01*
X237299Y1200238D01*
G01X299039Y1127215D02*
X294112D01*
X277416Y1143911D01*
Y1166485D01*
X241313Y1202588D01*
X238371D01*
X237375Y1203584D01*
G01X298899Y1146984D02*
X293554Y1152329D01*
Y1178397D01*
X292894Y1179057D01*
Y1180587D01*
X293554Y1181247D01*
Y1182777D01*
X241344Y1234987D01*
Y1236324D01*
X239542Y1238126D01*
X238376D01*
X237299Y1237049D01*
G01X299799Y1147883D02*
X294824Y1152856D01*
Y1183304D01*
X242614Y1235514D01*
Y1236851D01*
X240069Y1239396D01*
X238374D01*
X237375Y1240395D01*
G01X229651Y1452895D02*
X230716Y1453960D01*
Y1456730D01*
X229551Y1457895D01*
G01X219651Y1472295D02*
X218586Y1473360D01*
Y1476130D01*
X219751Y1477295D01*
G01X226351Y1462595D02*
X225286Y1463660D01*
Y1466430D01*
X226451Y1467595D01*
G01X216251Y1472295D02*
X217316Y1473360D01*
Y1476130D01*
X216151Y1477295D01*
G01X222951Y1462595D02*
X224016Y1463660D01*
Y1466430D01*
X222851Y1467595D01*
G01X224246Y1607286D02*
X225411Y1606121D01*
Y1593445D01*
X224346Y1592380D01*
G01X227846Y1607286D02*
X226681Y1606121D01*
Y1593445D01*
X227746Y1592380D01*
G01X224246Y1609386D02*
X225411Y1610551D01*
Y1623227D01*
X224346Y1624292D01*
G01X227846Y1609386D02*
X226681Y1610551D01*
Y1623227D01*
X227746Y1624292D01*
G01X301106Y892414D02*
Y892415D01*
X296000Y887309D01*
Y845743D01*
X294160Y843903D01*
X292384D01*
X290779Y845508D01*
X290061D01*
X289439Y844886D01*
Y844168D01*
X291044Y842563D01*
Y840787D01*
X286748Y836491D01*
X284404D01*
X283707Y835794D01*
Y833450D01*
X282273Y832016D01*
X279929D01*
X279232Y831319D01*
Y828975D01*
X277798Y827541D01*
X275454D01*
X274757Y826844D01*
Y824500D01*
X273323Y823066D01*
X270979D01*
X270282Y822369D01*
Y820025D01*
X268848Y818591D01*
X266504D01*
X265807Y817894D01*
Y815550D01*
X264373Y814116D01*
X262029D01*
X261332Y813419D01*
Y811075D01*
X259898Y809641D01*
X257554D01*
X256857Y808944D01*
Y806600D01*
X255423Y805166D01*
X253079D01*
X252382Y804469D01*
Y802125D01*
X250948Y800691D01*
X248604D01*
X247907Y799994D01*
Y797650D01*
X246473Y796216D01*
X244129D01*
X243432Y795519D01*
Y793175D01*
X241592Y791335D01*
X237112D01*
X236074Y790297D01*
X233969D01*
G01X300208Y893314D02*
X294730Y887836D01*
Y850824D01*
X294070Y850164D01*
Y848634D01*
X294730Y847974D01*
Y846270D01*
X293633Y845173D01*
X292911D01*
X291306Y846778D01*
X289534D01*
X288169Y845413D01*
Y843641D01*
X289774Y842036D01*
Y841314D01*
X286221Y837761D01*
X283877D01*
X282437Y836321D01*
Y833977D01*
X281746Y833286D01*
X279402D01*
X277962Y831846D01*
Y829502D01*
X277271Y828811D01*
X274927D01*
X273487Y827371D01*
Y825027D01*
X272796Y824336D01*
X270452D01*
X269012Y822896D01*
Y820552D01*
X268321Y819861D01*
X265977D01*
X264537Y818421D01*
Y816077D01*
X263846Y815386D01*
X261502D01*
X260062Y813946D01*
Y811602D01*
X259371Y810911D01*
X257027D01*
X255587Y809471D01*
Y807127D01*
X254896Y806436D01*
X252552D01*
X251112Y804996D01*
Y802652D01*
X250421Y801961D01*
X248077D01*
X246637Y800521D01*
Y798177D01*
X245946Y797486D01*
X243602D01*
X242162Y796046D01*
Y793702D01*
X241065Y792605D01*
X237112D01*
X236074Y793643D01*
X233969D01*
G01X299914Y915039D02*
X297085D01*
X277460Y895414D01*
Y863688D01*
X272731Y858959D01*
Y857183D01*
X273583Y856331D01*
Y855613D01*
X272961Y854991D01*
X272243D01*
X271391Y855843D01*
X269615D01*
X268256Y854484D01*
Y852708D01*
X269108Y851856D01*
Y851138D01*
X268486Y850516D01*
X267768D01*
X266916Y851368D01*
X265140D01*
X263781Y850009D01*
Y848233D01*
X264633Y847381D01*
Y846663D01*
X264011Y846041D01*
X263293D01*
X262441Y846893D01*
X260665D01*
X259306Y845534D01*
Y843758D01*
X260158Y842906D01*
Y842188D01*
X259536Y841566D01*
X258818D01*
X257966Y842418D01*
X256190D01*
X254831Y841059D01*
Y839283D01*
X255683Y838431D01*
Y837713D01*
X255061Y837091D01*
X254343D01*
X253491Y837943D01*
X251715D01*
X250356Y836584D01*
Y834808D01*
X250819Y834345D01*
Y833627D01*
X250197Y833005D01*
X249479D01*
X249016Y833468D01*
X247240D01*
X246367Y832595D01*
X241979D01*
X238800Y829416D01*
X237112D01*
X236074Y830454D01*
X233969D01*
G01X299914Y913769D02*
X297612D01*
X278730Y894887D01*
Y863161D01*
X274001Y858432D01*
Y857710D01*
X274853Y856858D01*
Y855086D01*
X273488Y853721D01*
X271716D01*
X270864Y854573D01*
X270142D01*
X269526Y853957D01*
Y853235D01*
X270378Y852383D01*
Y850611D01*
X269013Y849246D01*
X267241D01*
X266389Y850098D01*
X265667D01*
X265051Y849482D01*
Y848760D01*
X265903Y847908D01*
Y846136D01*
X264538Y844771D01*
X262766D01*
X261914Y845623D01*
X261192D01*
X260576Y845007D01*
Y844285D01*
X261428Y843433D01*
Y841661D01*
X260063Y840296D01*
X258291D01*
X257439Y841148D01*
X256717D01*
X256101Y840532D01*
Y839810D01*
X256953Y838958D01*
Y837186D01*
X255588Y835821D01*
X253816D01*
X252964Y836673D01*
X252242D01*
X251626Y836057D01*
Y835335D01*
X252089Y834872D01*
Y833100D01*
X250724Y831735D01*
X248952D01*
X248489Y832198D01*
X247767D01*
X246894Y831325D01*
X242506D01*
X239327Y828146D01*
X237112D01*
X236074Y827108D01*
X233969D01*
G01X299799Y933476D02*
X292719D01*
X261460Y902217D01*
Y882994D01*
X259474Y881008D01*
Y880286D01*
X261397Y878363D01*
Y876591D01*
X260032Y875226D01*
X258260D01*
X256337Y877149D01*
X255615D01*
X254999Y876533D01*
Y875811D01*
X257577Y873233D01*
Y871461D01*
X256212Y870096D01*
X254440D01*
X251862Y872674D01*
X251140D01*
X250524Y872058D01*
Y871336D01*
X252447Y869413D01*
Y867641D01*
X251082Y866276D01*
X249310D01*
X247387Y868199D01*
X246665D01*
X243423Y864957D01*
X237112D01*
X236074Y863919D01*
X233969D01*
G01X299799Y934746D02*
X292192D01*
X260190Y902744D01*
Y883521D01*
X258204Y881535D01*
Y879759D01*
X260127Y877836D01*
Y877118D01*
X259505Y876496D01*
X258787D01*
X256864Y878419D01*
X255088D01*
X253729Y877060D01*
Y875284D01*
X256307Y872706D01*
Y871988D01*
X255685Y871366D01*
X254967D01*
X252389Y873944D01*
X250613D01*
X249254Y872585D01*
Y870809D01*
X251177Y868886D01*
Y868168D01*
X250555Y867546D01*
X249837D01*
X247914Y869469D01*
X246138D01*
X242896Y866227D01*
X237112D01*
X236074Y867265D01*
X233969D01*
G01X299039Y953807D02*
X286253D01*
X281233Y948787D01*
X280511D01*
X279913Y949385D01*
X278141D01*
X276776Y948020D01*
Y946248D01*
X277374Y945650D01*
Y944928D01*
X276758Y944312D01*
X276036D01*
X275438Y944910D01*
X273666D01*
X272301Y943545D01*
Y941773D01*
X272899Y941175D01*
Y940453D01*
X272283Y939837D01*
X271561D01*
X270963Y940435D01*
X269191D01*
X267826Y939070D01*
Y937298D01*
X268424Y936700D01*
Y935978D01*
X267808Y935362D01*
X267086D01*
X266488Y935960D01*
X264716D01*
X263351Y934595D01*
Y932823D01*
X263949Y932225D01*
Y931503D01*
X263333Y930887D01*
X262611D01*
X262013Y931485D01*
X260241D01*
X258876Y930120D01*
Y928348D01*
X259474Y927750D01*
Y927028D01*
X258858Y926412D01*
X258136D01*
X257538Y927010D01*
X255766D01*
X254401Y925645D01*
Y923873D01*
X254999Y923275D01*
Y922553D01*
X254383Y921937D01*
X253661D01*
X253063Y922535D01*
X251291D01*
X249926Y921170D01*
Y919398D01*
X250524Y918800D01*
Y918078D01*
X242623Y910177D01*
Y907077D01*
X238584Y903038D01*
X237112D01*
X236074Y904076D01*
X233969D01*
G01X299039Y952537D02*
X286780D01*
X281760Y947517D01*
X279984D01*
X279386Y948115D01*
X278668D01*
X278046Y947493D01*
Y946775D01*
X278644Y946177D01*
Y944401D01*
X277285Y943042D01*
X275509D01*
X274911Y943640D01*
X274193D01*
X273571Y943018D01*
Y942300D01*
X274169Y941702D01*
Y939926D01*
X272810Y938567D01*
X271034D01*
X270436Y939165D01*
X269718D01*
X269096Y938543D01*
Y937825D01*
X269694Y937227D01*
Y935451D01*
X268335Y934092D01*
X266559D01*
X265961Y934690D01*
X265243D01*
X264621Y934068D01*
Y933350D01*
X265219Y932752D01*
Y930976D01*
X263860Y929617D01*
X262084D01*
X261486Y930215D01*
X260768D01*
X260146Y929593D01*
Y928875D01*
X260744Y928277D01*
Y926501D01*
X259385Y925142D01*
X257609D01*
X257011Y925740D01*
X256293D01*
X255671Y925118D01*
Y924400D01*
X256269Y923802D01*
Y922026D01*
X254910Y920667D01*
X253134D01*
X252536Y921265D01*
X251818D01*
X251196Y920643D01*
Y919925D01*
X251794Y919327D01*
Y917551D01*
X243893Y909650D01*
Y906550D01*
X239111Y901768D01*
X237112D01*
X236074Y900730D01*
X233969D01*
G01X300904Y972441D02*
X263837D01*
X262268Y970872D01*
Y969096D01*
X264011Y967352D01*
X264012Y966635D01*
X263390Y966014D01*
X262671Y966013D01*
X260927Y967757D01*
X259153D01*
X257793Y966397D01*
Y964621D01*
X259536Y962877D01*
X259537Y962160D01*
X258915Y961539D01*
X258196Y961538D01*
X256452Y963282D01*
X254678D01*
X253318Y961922D01*
Y960146D01*
X255061Y958402D01*
X255062Y957685D01*
X254440Y957064D01*
X253721Y957063D01*
X251977Y958807D01*
X250203D01*
X248810Y957414D01*
Y953368D01*
X243145Y947703D01*
Y944499D01*
X238435Y939789D01*
X237172D01*
X236074Y940887D01*
X233969D01*
G01X300904Y971171D02*
X264364D01*
X263538Y970345D01*
Y969623D01*
X265282Y967879D01*
X265283Y966109D01*
X263917Y964743D01*
X262145Y964742D01*
X260400Y966487D01*
X259680D01*
X259063Y965870D01*
Y965148D01*
X260807Y963404D01*
X260808Y961634D01*
X259442Y960268D01*
X257670Y960267D01*
X255925Y962012D01*
X255205D01*
X254588Y961395D01*
Y960673D01*
X256332Y958929D01*
X256333Y957159D01*
X254967Y955793D01*
X253195Y955792D01*
X251450Y957537D01*
X250730D01*
X250080Y956887D01*
Y952841D01*
X244415Y947176D01*
Y943972D01*
X238962Y938519D01*
X237052D01*
X236074Y937541D01*
X233969D01*
G01X300707Y1067257D02*
X295019D01*
X289806Y1062044D01*
X288801D01*
X288291Y1062554D01*
Y1063476D01*
X287038Y1064729D01*
X285113D01*
X283860Y1063476D01*
Y1062554D01*
X283350Y1062044D01*
X282479D01*
X281969Y1062554D01*
Y1063476D01*
X280716Y1064729D01*
X278791D01*
X277538Y1063476D01*
Y1062554D01*
X277028Y1062044D01*
X276157D01*
X275647Y1062554D01*
Y1063476D01*
X274394Y1064729D01*
X272469D01*
X271216Y1063476D01*
Y1062554D01*
X270706Y1062044D01*
X269835D01*
X269325Y1062554D01*
Y1063476D01*
X268072Y1064729D01*
X266147D01*
X264894Y1063476D01*
Y1062554D01*
X264384Y1062044D01*
X263480D01*
X261722Y1063802D01*
Y1065922D01*
X260170Y1067474D01*
X258050D01*
X257247Y1068277D01*
Y1070397D01*
X255695Y1071949D01*
X253575D01*
X252772Y1072752D01*
Y1074872D01*
X251220Y1076424D01*
X249100D01*
X248297Y1077227D01*
Y1079347D01*
X246745Y1080899D01*
X244625D01*
X243822Y1081702D01*
Y1083822D01*
X242270Y1085374D01*
X240150D01*
X238431Y1087093D01*
X237112D01*
X236074Y1088131D01*
X233969D01*
G01X300707Y1065987D02*
X295546D01*
X290333Y1060774D01*
X288274D01*
X287021Y1062027D01*
Y1062949D01*
X286511Y1063459D01*
X285640D01*
X285130Y1062949D01*
Y1062027D01*
X283877Y1060774D01*
X281952D01*
X280699Y1062027D01*
Y1062949D01*
X280189Y1063459D01*
X279318D01*
X278808Y1062949D01*
Y1062027D01*
X277555Y1060774D01*
X275630D01*
X274377Y1062027D01*
Y1062949D01*
X273867Y1063459D01*
X272996D01*
X272486Y1062949D01*
Y1062027D01*
X271233Y1060774D01*
X269308D01*
X268055Y1062027D01*
Y1062949D01*
X267545Y1063459D01*
X266674D01*
X266164Y1062949D01*
Y1062027D01*
X264911Y1060774D01*
X262953D01*
X260452Y1063275D01*
Y1065395D01*
X259643Y1066204D01*
X257523D01*
X255977Y1067750D01*
Y1069870D01*
X255168Y1070679D01*
X253048D01*
X251502Y1072225D01*
Y1074345D01*
X250693Y1075154D01*
X248573D01*
X247027Y1076700D01*
Y1078820D01*
X246218Y1079629D01*
X244098D01*
X242552Y1081175D01*
Y1083295D01*
X241743Y1084104D01*
X239623D01*
X237904Y1085823D01*
X237112D01*
X236074Y1084785D01*
X233969D01*
G01X299565Y1085134D02*
X298792D01*
X297737Y1086189D01*
X294906D01*
X293851Y1085134D01*
X292470D01*
X291415Y1086189D01*
X288584D01*
X287529Y1085134D01*
X286148D01*
X285093Y1086189D01*
X282262D01*
X281207Y1085134D01*
X279826D01*
X278771Y1086189D01*
X275940D01*
X274885Y1085134D01*
X273847D01*
X272757Y1086224D01*
Y1086946D01*
X273151Y1087340D01*
Y1089112D01*
X271786Y1090477D01*
X270014D01*
X269620Y1090083D01*
X268898D01*
X268282Y1090699D01*
Y1091421D01*
X268676Y1091815D01*
Y1093587D01*
X267311Y1094952D01*
X265539D01*
X265145Y1094558D01*
X264423D01*
X263807Y1095174D01*
Y1095896D01*
X264201Y1096290D01*
Y1098062D01*
X262836Y1099427D01*
X261064D01*
X260670Y1099033D01*
X259948D01*
X259332Y1099649D01*
Y1100371D01*
X259726Y1100765D01*
Y1102537D01*
X258361Y1103902D01*
X256589D01*
X256195Y1103508D01*
X255473D01*
X254857Y1104124D01*
Y1104846D01*
X255251Y1105240D01*
Y1107012D01*
X253886Y1108377D01*
X252114D01*
X251720Y1107983D01*
X250998D01*
X250382Y1108599D01*
Y1109321D01*
X250776Y1109715D01*
Y1111487D01*
X249411Y1112852D01*
X247639D01*
X247245Y1112458D01*
X246523D01*
X245907Y1113074D01*
Y1113796D01*
X246301Y1114190D01*
Y1115962D01*
X244936Y1117327D01*
X243164D01*
X242770Y1116933D01*
X242048D01*
X240704Y1118277D01*
Y1121878D01*
X238678Y1123904D01*
X237112D01*
X236074Y1124942D01*
X233969D01*
G01X299565Y1083864D02*
X298265D01*
X297210Y1084919D01*
X295433D01*
X294378Y1083864D01*
X291943D01*
X290888Y1084919D01*
X289111D01*
X288056Y1083864D01*
X285621D01*
X284566Y1084919D01*
X282789D01*
X281734Y1083864D01*
X279299D01*
X278244Y1084919D01*
X276467D01*
X275412Y1083864D01*
X273320D01*
X271487Y1085697D01*
Y1087473D01*
X271881Y1087867D01*
Y1088585D01*
X271259Y1089207D01*
X270541D01*
X270147Y1088813D01*
X268371D01*
X267012Y1090172D01*
Y1091948D01*
X267406Y1092342D01*
Y1093060D01*
X266784Y1093682D01*
X266066D01*
X265672Y1093288D01*
X263896D01*
X262537Y1094647D01*
Y1096423D01*
X262931Y1096817D01*
Y1097535D01*
X262309Y1098157D01*
X261591D01*
X261197Y1097763D01*
X259421D01*
X258062Y1099122D01*
Y1100898D01*
X258456Y1101292D01*
Y1102010D01*
X257834Y1102632D01*
X257116D01*
X256722Y1102238D01*
X254946D01*
X253587Y1103597D01*
Y1105373D01*
X253981Y1105767D01*
Y1106485D01*
X253359Y1107107D01*
X252641D01*
X252247Y1106713D01*
X250471D01*
X249112Y1108072D01*
Y1109848D01*
X249506Y1110242D01*
Y1110960D01*
X248884Y1111582D01*
X248166D01*
X247772Y1111188D01*
X245996D01*
X244637Y1112547D01*
Y1114323D01*
X245031Y1114717D01*
Y1115435D01*
X244409Y1116057D01*
X243691D01*
X243297Y1115663D01*
X241521D01*
X239434Y1117750D01*
Y1121351D01*
X238151Y1122634D01*
X237112D01*
X236074Y1121596D01*
X233969D01*
G01X299039Y1104876D02*
X285502D01*
X284311Y1106067D01*
Y1108233D01*
X282782Y1109762D01*
X280616D01*
X279836Y1110542D01*
Y1112708D01*
X278307Y1114237D01*
X276141D01*
X275361Y1115017D01*
Y1117183D01*
X273832Y1118712D01*
X271666D01*
X270886Y1119492D01*
Y1121658D01*
X269357Y1123187D01*
X267191D01*
X266411Y1123967D01*
Y1126133D01*
X264882Y1127662D01*
X262716D01*
X261936Y1128442D01*
Y1130608D01*
X260407Y1132137D01*
X258241D01*
X257004Y1133374D01*
Y1134972D01*
X255525Y1136451D01*
Y1137606D01*
X257004Y1139085D01*
Y1147070D01*
X255133Y1148941D01*
X252981D01*
X252188Y1149734D01*
Y1151886D01*
X247727Y1156347D01*
X245951D01*
X242675Y1153071D01*
X241956Y1153072D01*
X241334Y1153693D01*
X241335Y1154410D01*
X244612Y1157687D01*
Y1159462D01*
X243359Y1160715D01*
X237112D01*
X236074Y1161753D01*
X233969D01*
G01X299039Y1103606D02*
X284975D01*
X283041Y1105540D01*
Y1107706D01*
X282255Y1108492D01*
X280089D01*
X278566Y1110015D01*
Y1112181D01*
X277780Y1112967D01*
X275614D01*
X274091Y1114490D01*
Y1116656D01*
X273305Y1117442D01*
X271139D01*
X269616Y1118965D01*
Y1121131D01*
X268830Y1121917D01*
X266664D01*
X265141Y1123440D01*
Y1125606D01*
X264355Y1126392D01*
X262189D01*
X260666Y1127915D01*
Y1130081D01*
X259880Y1130867D01*
X257714D01*
X255734Y1132847D01*
Y1134445D01*
X254255Y1135924D01*
Y1138133D01*
X255734Y1139612D01*
Y1146543D01*
X254606Y1147671D01*
X252454D01*
X250918Y1149207D01*
Y1151359D01*
X247200Y1155077D01*
X246478D01*
X243201Y1151800D01*
X241429Y1151801D01*
X240063Y1153167D01*
X240064Y1154937D01*
X243342Y1158215D01*
Y1158935D01*
X242832Y1159445D01*
X237112D01*
X236074Y1158407D01*
X233969D01*
G01X299039Y1124276D02*
X292897D01*
X274451Y1142722D01*
Y1161219D01*
X273290Y1162380D01*
Y1163102D01*
X274085Y1163897D01*
Y1165669D01*
X272720Y1167034D01*
X270948D01*
X270153Y1166239D01*
X269431D01*
X268815Y1166855D01*
Y1167577D01*
X269610Y1168372D01*
Y1170144D01*
X268245Y1171509D01*
X266473D01*
X265678Y1170714D01*
X264956D01*
X264340Y1171330D01*
Y1172052D01*
X265135Y1172847D01*
Y1174619D01*
X263770Y1175984D01*
X261998D01*
X261203Y1175189D01*
X260481D01*
X259865Y1175805D01*
Y1176527D01*
X260660Y1177322D01*
Y1179094D01*
X259295Y1180459D01*
X257523D01*
X256728Y1179664D01*
X256006D01*
X255390Y1180280D01*
Y1181002D01*
X256185Y1181797D01*
Y1183569D01*
X254820Y1184934D01*
X253048D01*
X252253Y1184139D01*
X251531D01*
X250915Y1184755D01*
Y1185477D01*
X251710Y1186272D01*
Y1188044D01*
X250345Y1189409D01*
X248573D01*
X247778Y1188614D01*
X247056D01*
X246440Y1189230D01*
Y1189952D01*
X247235Y1190747D01*
Y1192519D01*
X245870Y1193884D01*
X244098D01*
X243303Y1193089D01*
X242581D01*
X238144Y1197526D01*
X236812D01*
X235774Y1198564D01*
X233969D01*
G01X299039Y1123006D02*
X292370D01*
X273181Y1142195D01*
Y1160692D01*
X272020Y1161853D01*
Y1163629D01*
X272815Y1164424D01*
Y1165142D01*
X272193Y1165764D01*
X271475D01*
X270680Y1164969D01*
X268904D01*
X267545Y1166328D01*
Y1168104D01*
X268340Y1168899D01*
Y1169617D01*
X267718Y1170239D01*
X267000D01*
X266205Y1169444D01*
X264429D01*
X263070Y1170803D01*
Y1172579D01*
X263865Y1173374D01*
Y1174092D01*
X263243Y1174714D01*
X262525D01*
X261730Y1173919D01*
X259954D01*
X258595Y1175278D01*
Y1177054D01*
X259390Y1177849D01*
Y1178567D01*
X258768Y1179189D01*
X258050D01*
X257255Y1178394D01*
X255479D01*
X254120Y1179753D01*
Y1181529D01*
X254915Y1182324D01*
Y1183042D01*
X254293Y1183664D01*
X253575D01*
X252780Y1182869D01*
X251004D01*
X249645Y1184228D01*
Y1186004D01*
X250440Y1186799D01*
Y1187517D01*
X249818Y1188139D01*
X249100D01*
X248305Y1187344D01*
X246529D01*
X245170Y1188703D01*
Y1190479D01*
X245965Y1191274D01*
Y1191992D01*
X245343Y1192614D01*
X244625D01*
X243830Y1191819D01*
X242054D01*
X237617Y1196256D01*
X236812D01*
X235774Y1195218D01*
X233969D01*
G01X299039Y1143640D02*
X298573D01*
X291884Y1150329D01*
Y1176536D01*
X288958Y1179462D01*
Y1180184D01*
X290492Y1181718D01*
Y1183490D01*
X289127Y1184855D01*
X287355D01*
X285821Y1183321D01*
X285099D01*
X284483Y1183937D01*
Y1184659D01*
X286017Y1186193D01*
Y1187965D01*
X284652Y1189330D01*
X282880D01*
X281346Y1187796D01*
X280624D01*
X280008Y1188412D01*
Y1189134D01*
X281542Y1190668D01*
Y1192440D01*
X280177Y1193805D01*
X278405D01*
X276871Y1192271D01*
X276149D01*
X275533Y1192887D01*
Y1193609D01*
X277067Y1195143D01*
Y1196915D01*
X275702Y1198280D01*
X273930D01*
X272396Y1196746D01*
X271674D01*
X270447Y1197973D01*
Y1203451D01*
X239561Y1234337D01*
X237112D01*
X236074Y1235375D01*
X233969D01*
G01X299039Y1142370D02*
X298046D01*
X290614Y1149802D01*
Y1176009D01*
X287688Y1178935D01*
Y1180711D01*
X289222Y1182245D01*
Y1182963D01*
X288600Y1183585D01*
X287882D01*
X286348Y1182051D01*
X284572D01*
X283213Y1183410D01*
Y1185186D01*
X284747Y1186720D01*
Y1187438D01*
X284125Y1188060D01*
X283407D01*
X281873Y1186526D01*
X280097D01*
X278738Y1187885D01*
Y1189661D01*
X280272Y1191195D01*
Y1191913D01*
X279650Y1192535D01*
X278932D01*
X277398Y1191001D01*
X275622D01*
X274263Y1192360D01*
Y1194136D01*
X275797Y1195670D01*
Y1196388D01*
X275175Y1197010D01*
X274457D01*
X272923Y1195476D01*
X271147D01*
X269177Y1197446D01*
Y1202924D01*
X242132Y1229969D01*
X241198D01*
X240115Y1231052D01*
Y1231986D01*
X239034Y1233067D01*
X237112D01*
X236074Y1232029D01*
X233969D01*
G01X233051Y1452895D02*
X231986Y1453960D01*
Y1456730D01*
X233151Y1457895D01*
G01X246451Y1472295D02*
X245386Y1473360D01*
Y1476130D01*
X246551Y1477295D01*
G01X243051Y1472295D02*
X244116Y1473360D01*
Y1476130D01*
X242951Y1477295D01*
G01X236306Y1607286D02*
X237471Y1606121D01*
Y1593445D01*
X236406Y1592380D01*
G01X239906Y1607286D02*
X238741Y1606121D01*
Y1593445D01*
X239806Y1592380D01*
G01X236306Y1609386D02*
X237471Y1610551D01*
Y1623227D01*
X236406Y1624292D01*
G01X239906Y1609386D02*
X238741Y1610551D01*
Y1623227D01*
X239806Y1624292D01*
G01X259951Y1457895D02*
X258786Y1456730D01*
Y1453960D01*
X259851Y1452895D01*
G01X256351Y1457895D02*
X257516Y1456730D01*
Y1453960D01*
X256451Y1452895D01*
G01X253151Y1462595D02*
X252086Y1463660D01*
Y1466430D01*
X253251Y1467595D01*
G01X249751Y1462595D02*
X250816Y1463660D01*
Y1466430D01*
X249651Y1467595D01*
G01X248366Y1607286D02*
X249531Y1606121D01*
Y1593445D01*
X248466Y1592380D01*
G01X260426Y1607286D02*
X261591Y1606121D01*
Y1593445D01*
X260526Y1592380D01*
G01X251966Y1607286D02*
X250801Y1606121D01*
Y1593445D01*
X251866Y1592380D01*
G01X248366Y1609386D02*
X249531Y1610551D01*
Y1623227D01*
X248466Y1624292D01*
G01X260426Y1609386D02*
X261591Y1610551D01*
Y1623227D01*
X260526Y1624292D01*
G01X251966Y1609386D02*
X250801Y1610551D01*
Y1623227D01*
X251866Y1624292D01*
G01X269851Y1452895D02*
X270916Y1453960D01*
Y1456730D01*
X269751Y1457895D01*
G01X273251Y1452895D02*
X272186Y1453960D01*
Y1456730D01*
X273351Y1457895D01*
G01X272486Y1607286D02*
X273651Y1606121D01*
Y1593445D01*
X272586Y1592380D01*
G01X264026Y1607286D02*
X262861Y1606121D01*
Y1593445D01*
X263926Y1592380D01*
G01X276086Y1607286D02*
X274921Y1606121D01*
Y1593445D01*
X275986Y1592380D01*
G01X272486Y1609386D02*
X273651Y1610551D01*
Y1623227D01*
X272586Y1624292D01*
G01X264026Y1609386D02*
X262861Y1610551D01*
Y1623227D01*
X263926Y1624292D01*
G01X276086Y1609386D02*
X274921Y1610551D01*
Y1623227D01*
X275986Y1624292D01*
G01X284228Y25935D02*
X283163Y27000D01*
Y29974D01*
X283709Y30520D01*
Y32756D01*
G01X280828Y25935D02*
X281893Y27000D01*
Y29960D01*
X281346Y30507D01*
Y32756D01*
G01X284226Y50649D02*
X283163Y49586D01*
Y47085D01*
X283709Y46539D01*
Y44370D01*
G01X280826Y50649D02*
X281893Y49582D01*
Y47287D01*
X281346Y46740D01*
Y44370D01*
G01X280621Y1484082D02*
X279556Y1483017D01*
X276786D01*
X275621Y1484182D01*
G01X280621Y1480682D02*
X279556Y1481747D01*
X276786D01*
X275621Y1480582D01*
G01X280621Y1497482D02*
X279556Y1496417D01*
X276786D01*
X275621Y1497582D01*
G01X280621Y1494082D02*
X279556Y1495147D01*
X276786D01*
X275621Y1493982D01*
G01X284546Y1607286D02*
X285711Y1606121D01*
Y1593445D01*
X284646Y1592380D01*
G01X288146Y1607286D02*
X286981Y1606121D01*
Y1593445D01*
X288046Y1592380D01*
G01X284546Y1609386D02*
X285711Y1610551D01*
Y1623227D01*
X284646Y1624292D01*
G01X288146Y1609386D02*
X286981Y1610551D01*
Y1623227D01*
X288046Y1624292D01*
G01X304013Y1457895D02*
X305178Y1456730D01*
Y1453960D01*
X304113Y1452895D01*
G01X300913Y1467595D02*
X299748Y1466430D01*
Y1463660D01*
X300813Y1462595D01*
G01X297313Y1467595D02*
X298478Y1466430D01*
Y1463660D01*
X297413Y1462595D01*
G01X296175Y1483690D02*
X295010Y1482525D01*
X292240D01*
X291175Y1483590D01*
G01X296175Y1480090D02*
X295010Y1481255D01*
X292240D01*
X291175Y1480190D01*
G01X296175Y1501890D02*
X295010Y1503055D01*
X292240D01*
X291175Y1501990D01*
G01X296175Y1505490D02*
X295010Y1504325D01*
X292240D01*
X291175Y1505390D01*
G01X296545Y1523431D02*
X297507Y1524393D01*
X298533D01*
X299495Y1523431D01*
G01D02*
X300412Y1524348D01*
X302480D01*
X303697Y1525565D01*
X306031D01*
G01X296545Y1526631D02*
X297513Y1525663D01*
X298527D01*
X299495Y1526631D01*
G01D02*
X300508Y1525618D01*
X301953D01*
X303170Y1526835D01*
X306106D01*
G01X290593Y1523331D02*
X291658Y1524396D01*
X293480D01*
X294445Y1523431D01*
G01X290593Y1526731D02*
X291658Y1525666D01*
X293480D01*
X294445Y1526631D01*
G01X296606Y1607286D02*
X297771Y1606121D01*
Y1593445D01*
X296706Y1592380D01*
G01X300206Y1607286D02*
X299041Y1606121D01*
Y1593445D01*
X300106Y1592380D01*
G01X296606Y1609386D02*
X297771Y1610551D01*
Y1623227D01*
X296706Y1624292D01*
G01X300206Y1609386D02*
X299041Y1610551D01*
Y1623227D01*
X300106Y1624292D01*
G01X321645Y896616D02*
X319807Y895569D01*
G01X319795Y893427D02*
X317957Y892380D01*
G01X321645Y915749D02*
X319807Y914702D01*
G01X319795Y912560D02*
X317957Y911513D01*
G01X321645Y934883D02*
X319807Y933836D01*
G01X319795Y931694D02*
X317957Y930647D01*
G01X321645Y954017D02*
X319807Y952970D01*
G01X319795Y950828D02*
X317957Y949781D01*
G01X319795Y969962D02*
X317957Y968915D01*
G01X321645Y973151D02*
X319807Y972104D01*
G01X320976Y1068466D02*
X319138Y1069513D01*
G01X320976Y1087600D02*
X319138Y1088647D01*
G01X320976Y1106734D02*
X319138Y1107781D01*
G01X320976Y1125868D02*
X319138Y1126915D01*
G01X320976Y1145001D02*
X319138Y1146048D01*
G01X307613Y1457895D02*
X306448Y1456730D01*
Y1453960D01*
X307513Y1452895D01*
G01X321013Y1477295D02*
X319848Y1476130D01*
Y1473360D01*
X320913Y1472295D01*
G01X317413Y1477295D02*
X318578Y1476130D01*
Y1473360D01*
X317513Y1472295D01*
G01X308666Y1607286D02*
X309831Y1606121D01*
Y1593445D01*
X308766Y1592380D01*
G01X312266Y1607286D02*
X311101Y1606121D01*
Y1593445D01*
X312166Y1592380D01*
G01X308666Y1609386D02*
X309831Y1610551D01*
Y1623227D01*
X308766Y1624292D01*
G01X312266Y1609386D02*
X311101Y1610551D01*
Y1623227D01*
X312166Y1624292D01*
G01X325346Y896616D02*
X323508Y895569D01*
G01X332748Y896616D02*
X330910Y895569D01*
G01X334598Y893427D02*
X332760Y892380D01*
G01X327196Y899805D02*
X325358Y898758D01*
G01X325346Y915749D02*
X323508Y914702D01*
G01X327196Y918938D02*
X325358Y917891D01*
G01X332748Y915749D02*
X330910Y914702D01*
G01X334598Y912560D02*
X332760Y911513D01*
G01X325346Y934883D02*
X323508Y933836D01*
G01X327196Y938072D02*
X325358Y937025D01*
G01X332748Y934883D02*
X330910Y933836D01*
G01X334598Y931694D02*
X332760Y930647D01*
G01X325346Y954017D02*
X323508Y952970D01*
G01X332748Y954017D02*
X330910Y952970D01*
G01X334598Y950828D02*
X332760Y949781D01*
G01X327196Y957206D02*
X325358Y956159D01*
G01X334598Y969962D02*
X332760Y968915D01*
G01X325346Y973151D02*
X323508Y972104D01*
G01X327196Y976340D02*
X325358Y975293D01*
G01X332748Y973151D02*
X330910Y972104D01*
G01X328378Y1068466D02*
X326539Y1069513D01*
G01X326527Y1071655D02*
X324689Y1072702D01*
G01X322826Y1065277D02*
X320988Y1066324D01*
G01X335779Y1068466D02*
X333941Y1069513D01*
G01X333929Y1065277D02*
X332091Y1066324D01*
G01X328378Y1087600D02*
X326539Y1088647D01*
G01X322826Y1084411D02*
X320988Y1085458D01*
G01X335779Y1087600D02*
X333941Y1088647D01*
G01X333929Y1084411D02*
X332091Y1085458D01*
G01X322826Y1103545D02*
X320988Y1104592D01*
G01X326527Y1090789D02*
X324689Y1091836D01*
G01X333929Y1103545D02*
X332091Y1104592D01*
G01X328378Y1106734D02*
X326539Y1107781D01*
G01X326527Y1109923D02*
X324689Y1110970D01*
G01X335779Y1106734D02*
X333941Y1107781D01*
G01X328378Y1125868D02*
X326539Y1126915D01*
G01X322826Y1122679D02*
X320988Y1123726D01*
G01X326527Y1129057D02*
X324689Y1130103D01*
G01X335779Y1125868D02*
X333941Y1126915D01*
G01X333929Y1122679D02*
X332091Y1123726D01*
G01X328378Y1145001D02*
X326539Y1146048D01*
G01X322826Y1141812D02*
X320988Y1142859D01*
G01X326527Y1148190D02*
X324689Y1149237D01*
G01X335779Y1145001D02*
X333941Y1146048D01*
G01X333929Y1141812D02*
X332091Y1142859D01*
G01X334413Y1457895D02*
X333248Y1456730D01*
Y1453960D01*
X334313Y1452895D01*
G01X330813Y1457895D02*
X331978Y1456730D01*
Y1453960D01*
X330913Y1452895D01*
G01X327713Y1467595D02*
X326548Y1466430D01*
Y1463660D01*
X327613Y1462595D01*
G01X324113Y1467595D02*
X325278Y1466430D01*
Y1463660D01*
X324213Y1462595D01*
G01X320726Y1607286D02*
X321891Y1606121D01*
Y1593445D01*
X320826Y1592380D01*
G01X332786Y1607286D02*
X333951Y1606121D01*
Y1593445D01*
X332886Y1592380D01*
G01X324326Y1607286D02*
X323161Y1606121D01*
Y1593445D01*
X324226Y1592380D01*
G01X320726Y1609386D02*
X321891Y1610551D01*
Y1623227D01*
X320826Y1624292D01*
G01X332786Y1609386D02*
X333951Y1610551D01*
Y1623227D01*
X332886Y1624292D01*
G01X324326Y1609386D02*
X323161Y1610551D01*
Y1623227D01*
X324226Y1624292D01*
G01X347551Y896616D02*
X345713Y895569D01*
G01X351252Y896616D02*
X349414Y895569D01*
G01X345700Y893427D02*
X343862Y892380D01*
G01X340149Y896616D02*
X338311Y895569D01*
G01X338299Y899805D02*
X336461Y898758D01*
G01X347551Y915749D02*
X345713Y914702D01*
G01X351252Y915749D02*
X349414Y914702D01*
G01X345700Y912560D02*
X343862Y911513D01*
G01X340149Y915749D02*
X338311Y914702D01*
G01X338299Y918938D02*
X336461Y917891D01*
G01X347551Y934883D02*
X345713Y933836D01*
G01X351252Y934883D02*
X349414Y933836D01*
G01X345700Y931694D02*
X343862Y930647D01*
G01X340149Y934883D02*
X338311Y933836D01*
G01X338299Y938072D02*
X336461Y937025D01*
G01X347551Y954017D02*
X345713Y952970D01*
G01X351252Y954017D02*
X349414Y952970D01*
G01X345700Y950828D02*
X343862Y949781D01*
G01X340149Y954017D02*
X338311Y952970D01*
G01X345700Y969962D02*
X343862Y968915D01*
G01X338299Y957206D02*
X336461Y956159D01*
G01X347551Y973151D02*
X345713Y972104D01*
G01X351252Y973151D02*
X349414Y972104D01*
G01X340149Y973151D02*
X338311Y972104D01*
G01X338299Y976340D02*
X336461Y975293D01*
G01X346881Y1068466D02*
X345043Y1069513D01*
G01X348732Y1065277D02*
X346894Y1066324D01*
G01X339480Y1068466D02*
X337642Y1069513D01*
G01X341330Y1071655D02*
X339492Y1072702D01*
G01X346881Y1087600D02*
X345043Y1088647D01*
G01X348732Y1084411D02*
X346894Y1085458D01*
G01X339480Y1087600D02*
X337642Y1088647D01*
G01X348732Y1103545D02*
X346894Y1104592D01*
G01X341330Y1090789D02*
X339492Y1091836D01*
G01X346881Y1106734D02*
X345043Y1107781D01*
G01X339480Y1106734D02*
X337642Y1107781D01*
G01X341330Y1109923D02*
X339492Y1110970D01*
G01X346881Y1125868D02*
X345043Y1126915D01*
G01X348732Y1122679D02*
X346894Y1123726D01*
G01X339480Y1125868D02*
X337642Y1126915D01*
G01X341330Y1129057D02*
X339492Y1130103D01*
G01X346881Y1145001D02*
X345043Y1146048D01*
G01X348732Y1141812D02*
X346894Y1142859D01*
G01X339480Y1145001D02*
X337642Y1146048D01*
G01X341330Y1148190D02*
X339492Y1149237D01*
G01X347813Y1477295D02*
X346648Y1476130D01*
Y1473360D01*
X347713Y1472295D01*
G01X344213Y1477295D02*
X345378Y1476130D01*
Y1473360D01*
X344313Y1472295D01*
G01X344846Y1607286D02*
X346011Y1606121D01*
Y1593445D01*
X344946Y1592380D01*
G01X336386Y1607286D02*
X335221Y1606121D01*
Y1593445D01*
X336286Y1592380D01*
G01X348446Y1607286D02*
X347281Y1606121D01*
Y1593445D01*
X348346Y1592380D01*
G01X344846Y1609386D02*
X346011Y1610551D01*
Y1623227D01*
X344946Y1624292D01*
G01X336386Y1609386D02*
X335221Y1610551D01*
Y1623227D01*
X336286Y1624292D01*
G01X348446Y1609386D02*
X347281Y1610551D01*
Y1623227D01*
X348346Y1624292D01*
G01X358653Y896616D02*
X356815Y895569D01*
G01X366055Y896616D02*
X364217Y895569D01*
G01X360504Y893427D02*
X358665Y892380D01*
G01X353102Y899805D02*
X351264Y898758D01*
G01X364204Y899805D02*
X362366Y898758D01*
G01X353102Y918938D02*
X351264Y917891D01*
G01X358653Y915749D02*
X356815Y914702D01*
G01X366055Y915749D02*
X364217Y914702D01*
G01X360504Y912560D02*
X358665Y911513D01*
G01X364204Y918938D02*
X362366Y917891D01*
G01X353102Y938072D02*
X351264Y937025D01*
G01X358653Y934883D02*
X356815Y933836D01*
G01X366055Y934883D02*
X364217Y933836D01*
G01X360504Y931694D02*
X358665Y930647D01*
G01X364204Y938072D02*
X362366Y937025D01*
G01X358653Y954017D02*
X356815Y952970D01*
G01X366055Y954017D02*
X364217Y952970D01*
G01X360504Y950828D02*
X358665Y949781D01*
G01X353102Y957206D02*
X351264Y956159D01*
G01X360504Y969962D02*
X358665Y968915D01*
G01X364204Y957206D02*
X362366Y956159D01*
G01X353102Y976340D02*
X351264Y975293D01*
G01X358653Y973151D02*
X356815Y972104D01*
G01X366055Y973151D02*
X364217Y972104D01*
G01X364204Y976340D02*
X362366Y975293D01*
G01X354283Y1068466D02*
X352445Y1069513D01*
G01X352433Y1071655D02*
X350595Y1072702D01*
G01X365385Y1068466D02*
X363547Y1069513D01*
G01X361685Y1068466D02*
X359847Y1069513D01*
G01X359834Y1065277D02*
X357996Y1066324D01*
G01X354283Y1087600D02*
X352445Y1088647D01*
G01X361685Y1087600D02*
X359847Y1088647D01*
G01X365385Y1087600D02*
X363547Y1088647D01*
G01X359834Y1084411D02*
X357996Y1085458D01*
G01X352433Y1090789D02*
X350595Y1091836D01*
G01X359834Y1103545D02*
X357996Y1104592D01*
G01X354283Y1106734D02*
X352445Y1107781D01*
G01X352433Y1109923D02*
X350595Y1110970D01*
G01X361685Y1106734D02*
X359847Y1107781D01*
G01X365385Y1106734D02*
X363547Y1107781D01*
G01X354283Y1125868D02*
X352445Y1126915D01*
G01X352433Y1129057D02*
X350595Y1130103D01*
G01X361685Y1125868D02*
X359847Y1126915D01*
G01X365385Y1125868D02*
X363547Y1126915D01*
G01X359834Y1122679D02*
X357996Y1123726D01*
G01X354283Y1145001D02*
X352445Y1146048D01*
G01X352433Y1148190D02*
X350595Y1149237D01*
G01X361685Y1145001D02*
X359847Y1146048D01*
G01X365385Y1145001D02*
X363547Y1146048D01*
G01X359834Y1141812D02*
X357996Y1142859D01*
G01X361213Y1457895D02*
X360048Y1456730D01*
Y1453960D01*
X361113Y1452895D01*
G01X357613Y1457895D02*
X358778Y1456730D01*
Y1453960D01*
X357713Y1452895D01*
G01X354513Y1467595D02*
X353348Y1466430D01*
Y1463660D01*
X354413Y1462595D01*
G01X350913Y1467595D02*
X352078Y1466430D01*
Y1463660D01*
X351013Y1462595D01*
G01X356906Y1607286D02*
X358071Y1606121D01*
Y1593445D01*
X357006Y1592380D01*
G01X360506Y1607286D02*
X359341Y1606121D01*
Y1593445D01*
X360406Y1592380D01*
G01X356906Y1609386D02*
X358071Y1610551D01*
Y1623227D01*
X357006Y1624292D01*
G01X360506Y1609386D02*
X359341Y1610551D01*
Y1623227D01*
X360406Y1624292D01*
G01X439474Y884261D02*
X439968Y883767D01*
X440241Y883118D01*
X440374Y882285D01*
X439468Y871236D01*
X438754Y869128D01*
X412506Y834806D01*
X389179Y808129D01*
X386318Y806944D01*
X384468D01*
X382769Y807648D01*
X381395Y808892D01*
X375721Y819506D01*
X374635Y820592D01*
X373064D01*
X371999Y819527D01*
G01X438576Y883362D02*
X438893Y883045D01*
X439011Y882765D01*
X439095Y882236D01*
X438214Y871496D01*
X437617Y869734D01*
X411522Y835611D01*
X400646Y823173D01*
X399600Y823103D01*
X398613Y821973D01*
X398683Y820929D01*
X397696Y819800D01*
X396650Y819730D01*
X395663Y818600D01*
X395733Y817556D01*
X394746Y816427D01*
X393701Y816357D01*
X392714Y815227D01*
X392784Y814182D01*
X388418Y809190D01*
X386065Y808214D01*
X384721D01*
X383459Y808737D01*
X382412Y809686D01*
X379060Y815956D01*
X379368Y816971D01*
X378651Y818313D01*
X377635Y818621D01*
X376753Y820271D01*
X375162Y821862D01*
X373064D01*
X371999Y822927D01*
G01X418500Y872172D02*
Y871322D01*
X417718Y869611D01*
X417717D01*
X375253Y832862D01*
X373065D01*
X372000Y831797D01*
G01X417230Y872172D02*
Y871599D01*
X416677Y870391D01*
X390087Y847380D01*
X389043Y847455D01*
X387908Y846474D01*
X387833Y845429D01*
X386699Y844448D01*
X385655Y844523D01*
X384520Y843542D01*
X384445Y842497D01*
X383311Y841516D01*
X382268Y841591D01*
X381132Y840610D01*
X381057Y839565D01*
X374779Y834132D01*
X373065D01*
X372000Y835197D01*
G01X406129Y871272D02*
Y870962D01*
X405801Y870269D01*
X386962Y854808D01*
X385920Y854910D01*
X384760Y853959D01*
X384657Y852916D01*
X383498Y851965D01*
X382457Y852067D01*
X381297Y851116D01*
X381194Y850073D01*
X380035Y849122D01*
X378993Y849224D01*
X377833Y848273D01*
X377730Y847230D01*
X375939Y845760D01*
X375938Y845759D01*
X374982Y845362D01*
X373065D01*
X372000Y846427D01*
G01X407399Y871272D02*
Y870676D01*
X406827Y869468D01*
X376599Y844658D01*
Y844657D01*
X375235Y844092D01*
X373065D01*
X372000Y843027D01*
G01X373456Y896616D02*
X371618Y895569D01*
G01X377157Y896616D02*
X375319Y895569D01*
G01X371606Y893427D02*
X369768Y892380D01*
G01X379007Y899805D02*
X377169Y898758D01*
G01X373456Y915749D02*
X371618Y914702D01*
G01X377157Y915749D02*
X375319Y914702D01*
G01X371606Y912560D02*
X369768Y911513D01*
G01X379007Y918938D02*
X377169Y917891D01*
G01X373456Y934883D02*
X371618Y933836D01*
G01X377157Y934883D02*
X375319Y933836D01*
G01X371606Y931694D02*
X369768Y930647D01*
G01X379007Y938072D02*
X377169Y937025D01*
G01X373456Y954017D02*
X371618Y952970D01*
G01X377157Y954017D02*
X375319Y952970D01*
G01X371606Y950828D02*
X369768Y949781D01*
G01X371606Y969962D02*
X369768Y968915D01*
G01X379007Y957206D02*
X377169Y956159D01*
G01X373456Y973151D02*
X371618Y972104D01*
G01X377157Y973151D02*
X375319Y972104D01*
G01X379007Y976340D02*
X377169Y975293D01*
G01X380189Y1068466D02*
X378351Y1069513D01*
G01X372787Y1068466D02*
X370949Y1069513D01*
G01X378338Y1071655D02*
X376500Y1072702D01*
G01X374637Y1065277D02*
X372799Y1066324D01*
G01X367236Y1071655D02*
X365398Y1072702D01*
G01X372787Y1087600D02*
X370949Y1088647D01*
G01X380189Y1087600D02*
X378351Y1088647D01*
G01X374637Y1084411D02*
X372799Y1085458D01*
G01X374637Y1103545D02*
X372799Y1104592D01*
G01X378338Y1090789D02*
X376500Y1091836D01*
G01X367236Y1090789D02*
X365398Y1091836D01*
G01X372787Y1106734D02*
X370949Y1107781D01*
G01X380189Y1106734D02*
X378351Y1107781D01*
G01X378338Y1109923D02*
X376500Y1110970D01*
G01X367236Y1109923D02*
X365398Y1110970D01*
G01X372787Y1125868D02*
X370949Y1126915D01*
G01X380189Y1125868D02*
X378351Y1126915D01*
G01X374637Y1122679D02*
X372799Y1123726D01*
G01X378338Y1129057D02*
X376500Y1130103D01*
G01X367236Y1129057D02*
X365398Y1130103D01*
G01X372787Y1145001D02*
X370949Y1146048D01*
G01X380189Y1145001D02*
X378351Y1146048D01*
G01X374637Y1141812D02*
X372799Y1142859D01*
G01X378338Y1148190D02*
X376500Y1149237D01*
G01X367236Y1148190D02*
X365398Y1149237D01*
G01X374613Y1477295D02*
X373448Y1476130D01*
Y1473360D01*
X374513Y1472295D01*
G01X371013Y1477295D02*
X372178Y1476130D01*
Y1473360D01*
X371113Y1472295D01*
G01X377713Y1467595D02*
X378878Y1466430D01*
Y1463660D01*
X377813Y1462595D01*
G01X368966Y1607286D02*
X370131Y1606121D01*
Y1593445D01*
X369066Y1592380D01*
G01X372566Y1607286D02*
X371401Y1606121D01*
Y1593445D01*
X372466Y1592380D01*
G01X368966Y1609386D02*
X370131Y1610551D01*
Y1623227D01*
X369066Y1624292D01*
G01X372566Y1609386D02*
X371401Y1610551D01*
Y1623227D01*
X372466Y1624292D01*
G01X388273Y-24855D02*
X390841Y-25571D01*
G01X388273Y-22887D02*
X390841Y-22171D01*
G01X428333Y872825D02*
Y870387D01*
X425908Y863564D01*
X400969Y832889D01*
X399927Y832781D01*
X398980Y831616D01*
X399088Y830575D01*
X398142Y829412D01*
X397100Y829304D01*
X396153Y828139D01*
X396261Y827098D01*
X395315Y825935D01*
X394273Y825828D01*
X393327Y824663D01*
X393434Y823622D01*
X387336Y816121D01*
X386794Y815862D01*
X386066D01*
X385001Y816927D01*
G01X429603Y872825D02*
Y870168D01*
X427032Y862932D01*
X388142Y815097D01*
X387082Y814592D01*
X386066D01*
X385001Y813527D01*
G01X390110Y893427D02*
X388272Y892380D01*
G01X386409Y893427D02*
X384571Y892380D01*
G01X390110Y899805D02*
X388272Y898758D01*
G01X390110Y906182D02*
X388272Y905135D01*
G01X386409Y899805D02*
X384571Y898758D01*
G01X386409Y906182D02*
X384571Y905135D01*
G01X390110Y912560D02*
X388272Y911513D01*
G01X386409Y912560D02*
X384571Y911513D01*
G01X390110Y925316D02*
X388272Y924269D01*
G01X390110Y918938D02*
X388272Y917891D01*
G01X386409Y925316D02*
X384571Y924269D01*
G01X386409Y918938D02*
X384571Y917891D01*
G01X390110Y931694D02*
X388272Y930647D01*
G01X386409Y931694D02*
X384571Y930647D01*
G01X386409Y950828D02*
X384571Y949781D01*
G01X386409Y944450D02*
X384571Y943403D01*
G01X390110Y950828D02*
X388272Y949781D01*
G01X390110Y944450D02*
X388272Y943403D01*
G01X386409Y957206D02*
X384571Y956159D01*
G01X390110Y957206D02*
X388272Y956159D01*
G01X386409Y963584D02*
X384571Y962537D01*
G01X386409Y969962D02*
X384571Y968915D01*
G01X390110Y963584D02*
X388272Y962537D01*
G01X390110Y969962D02*
X388272Y968915D01*
G01X386409Y976340D02*
X384571Y975293D01*
G01X390110Y976340D02*
X388272Y975293D01*
G01X387590Y1068466D02*
X385752Y1069513D01*
G01X387590Y1074844D02*
X385752Y1075891D01*
G01X387590Y1062088D02*
X385752Y1063135D01*
G01X391291Y1068466D02*
X389453Y1069513D01*
G01X391291Y1074844D02*
X389453Y1075891D01*
G01X391291Y1062088D02*
X389453Y1063135D01*
G01X387590Y1087600D02*
X385752Y1088647D01*
G01X387590Y1081222D02*
X385752Y1082269D01*
G01X391291Y1087600D02*
X389453Y1088647D01*
G01X391291Y1081222D02*
X389453Y1082269D01*
G01X387590Y1093978D02*
X385752Y1095025D01*
G01X391291Y1093978D02*
X389453Y1095025D01*
G01X391291Y1113112D02*
X389453Y1114159D01*
G01X391291Y1119490D02*
X389453Y1120537D01*
G01X391291Y1106734D02*
X389453Y1107781D01*
G01X387590Y1113112D02*
X385752Y1114159D01*
G01X387590Y1119490D02*
X385752Y1120537D01*
G01X387590Y1106734D02*
X385752Y1107781D01*
G01X391291Y1125868D02*
X389453Y1126915D01*
G01X391291Y1132246D02*
X389453Y1133293D01*
G01X387590Y1125868D02*
X385752Y1126915D01*
G01X387590Y1132246D02*
X385752Y1133293D01*
G01X391291Y1138623D02*
X389453Y1139670D01*
G01X391291Y1145001D02*
X389453Y1146048D01*
G01X387590Y1138623D02*
X385752Y1139670D01*
G01X387590Y1145001D02*
X385752Y1146048D01*
G01X387590Y1157757D02*
X385752Y1158804D01*
G01X383889Y1157757D02*
X382051Y1158804D01*
G01X394992Y1157757D02*
X393154Y1158804D01*
G01X391291Y1151379D02*
X389453Y1152426D01*
G01X387590Y1151379D02*
X385752Y1152426D01*
G01X474500Y1264925D02*
X475865Y1263560D01*
Y1260847D01*
X385104Y1170086D01*
Y1165350D01*
X383889Y1164135D01*
G01X478500Y1264925D02*
X477135Y1263560D01*
Y1260320D01*
X386374Y1169559D01*
Y1165351D01*
X387590Y1164135D01*
G01X388013Y1457895D02*
X386848Y1456730D01*
Y1453960D01*
X387913Y1452895D01*
G01X384413Y1457895D02*
X385578Y1456730D01*
Y1453960D01*
X384513Y1452895D01*
G01X381313Y1467595D02*
X380148Y1466430D01*
Y1463660D01*
X381213Y1462595D01*
G01X406243Y112951D02*
X405212Y113982D01*
X401593D01*
X400426Y112815D01*
G01X426767Y119086D02*
X425808D01*
X425459Y119435D01*
X416405D01*
X410986Y114016D01*
X407308D01*
X406243Y112951D01*
G01Y116351D02*
X405144Y115252D01*
X401389D01*
X400426Y116215D01*
G01X426767Y121054D02*
X425798D01*
X425449Y120705D01*
X415878D01*
X410459Y115286D01*
X407308D01*
X406243Y116351D01*
G01X405606Y125815D02*
X407057Y127266D01*
X408378D01*
X409443Y126201D01*
G01X426767Y128928D02*
X425804D01*
X425455Y129277D01*
X421706D01*
X419973Y131010D01*
X415201D01*
X411457Y127266D01*
X410508D01*
X409443Y126201D01*
G01X405606Y129715D02*
X406785Y128536D01*
X408378D01*
X409443Y129601D01*
G01X426767Y130897D02*
X425851D01*
X425501Y130547D01*
X422233D01*
X420500Y132280D01*
X414674D01*
X410930Y128536D01*
X410508D01*
X409443Y129601D01*
G01X404913Y880671D02*
X403075Y879624D01*
G01X408614Y880671D02*
X406776Y879624D01*
G01X401212Y893427D02*
X399374Y892380D01*
G01X397511Y893427D02*
X395673Y892380D01*
G01X408614Y893427D02*
X406776Y892380D01*
G01X408614Y887049D02*
X406776Y886002D01*
G01X401212Y899805D02*
X399374Y898758D01*
G01X401212Y906182D02*
X399374Y905135D01*
G01X397511Y899805D02*
X395673Y898758D01*
G01X397511Y906182D02*
X395673Y905135D01*
G01X408614Y899805D02*
X406776Y898758D01*
G01X408614Y906182D02*
X406776Y905135D01*
G01X401212Y925316D02*
X399374Y924269D01*
G01X401212Y918938D02*
X399374Y917891D01*
G01X401212Y912560D02*
X399374Y911513D01*
G01X397511Y925316D02*
X395673Y924269D01*
G01X397511Y918938D02*
X395673Y917891D01*
G01X397511Y912560D02*
X395673Y911513D01*
G01X408614Y918938D02*
X406776Y917891D01*
G01X408614Y912560D02*
X406776Y911513D01*
G01X408614Y925316D02*
X406776Y924269D01*
G01X401212Y931694D02*
X399374Y930647D01*
G01X397511Y931694D02*
X395673Y930647D01*
G01X397511Y950828D02*
X395673Y949781D01*
G01X397511Y944450D02*
X395673Y943403D01*
G01X408614Y950828D02*
X406776Y949781D01*
G01X408614Y944450D02*
X406776Y943403D01*
G01X401212Y950828D02*
X399374Y949781D01*
G01X401212Y944450D02*
X399374Y943403D01*
G01X397511Y957206D02*
X395673Y956159D01*
G01X408614Y957206D02*
X406776Y956159D01*
G01X401212Y957206D02*
X399374Y956159D01*
G01X397511Y963584D02*
X395673Y962537D01*
G01X397511Y969962D02*
X395673Y968915D01*
G01X408614Y963584D02*
X406776Y962537D01*
G01X408614Y969962D02*
X406776Y968915D01*
G01X401212Y963584D02*
X399374Y962537D01*
G01X401212Y969962D02*
X399374Y968915D01*
G01X397511Y976340D02*
X395673Y975293D01*
G01X408614Y976340D02*
X406776Y975293D01*
G01X401212Y976340D02*
X399374Y975293D01*
G01X398693Y1068466D02*
X396855Y1069513D01*
G01X398693Y1074844D02*
X396855Y1075891D01*
G01X398693Y1062088D02*
X396855Y1063135D01*
G01X409795Y1068466D02*
X407957Y1069513D01*
G01X409795Y1062088D02*
X407957Y1063135D01*
G01X402393Y1068466D02*
X400555Y1069513D01*
G01X402393Y1074844D02*
X400555Y1075891D01*
G01X402393Y1062088D02*
X400555Y1063135D01*
G01X409795Y1074844D02*
X407957Y1075891D01*
G01X398693Y1087600D02*
X396855Y1088647D01*
G01X398693Y1081222D02*
X396855Y1082269D01*
G01X409795Y1087600D02*
X407957Y1088647D01*
G01X409795Y1081222D02*
X407957Y1082269D01*
G01X402393Y1087600D02*
X400555Y1088647D01*
G01X402393Y1081222D02*
X400555Y1082269D01*
G01X398693Y1093978D02*
X396855Y1095025D01*
G01X409795Y1093978D02*
X407957Y1095025D01*
G01X402393Y1093978D02*
X400555Y1095025D01*
G01X402393Y1113112D02*
X400555Y1114159D01*
G01X402393Y1119490D02*
X400555Y1120537D01*
G01X402393Y1106734D02*
X400555Y1107781D01*
G01X398693Y1113112D02*
X396855Y1114159D01*
G01X398693Y1119490D02*
X396855Y1120537D01*
G01X398693Y1106734D02*
X396855Y1107781D01*
G01X409795Y1113112D02*
X407957Y1114159D01*
G01X402393Y1125868D02*
X400555Y1126915D01*
G01X398693Y1125868D02*
X396855Y1126915D01*
G01X409795Y1119490D02*
X407957Y1120537D01*
G01X409795Y1125868D02*
X407957Y1126915D01*
G01X402393Y1132246D02*
X400555Y1133293D01*
G01X398693Y1132246D02*
X396855Y1133293D01*
G01X409795Y1132246D02*
X407957Y1133293D01*
G01X402393Y1138623D02*
X400555Y1139670D01*
G01X402393Y1145001D02*
X400555Y1146048D01*
G01X398693Y1138623D02*
X396855Y1139670D01*
G01X398693Y1145001D02*
X396855Y1146048D01*
G01X409795Y1138623D02*
X407957Y1139670D01*
G01X409795Y1145001D02*
X407957Y1146048D01*
G01X398693Y1157757D02*
X396855Y1158804D01*
G01X409795Y1157757D02*
X407957Y1158804D01*
G01X406094Y1157757D02*
X404256Y1158804D01*
G01X402393Y1151379D02*
X400555Y1152426D01*
G01X398693Y1151379D02*
X396855Y1152426D01*
G01X409795Y1151379D02*
X407957Y1152426D01*
G01X401413Y1457895D02*
X400248Y1456730D01*
Y1453960D01*
X401313Y1452895D01*
G01X397813Y1457895D02*
X398978Y1456730D01*
Y1453960D01*
X397913Y1452895D01*
G01X403683Y1480582D02*
X404848Y1481747D01*
X407618D01*
X408683Y1480682D01*
G01X403683Y1484182D02*
X404848Y1483017D01*
X407618D01*
X408683Y1484082D01*
G01X403683Y1497582D02*
X404848Y1496417D01*
X407618D01*
X408683Y1497482D01*
G01X403683Y1493982D02*
X404848Y1495147D01*
X407618D01*
X408683Y1494082D01*
G01X408943Y1609772D02*
X408193D01*
X407844Y1610121D01*
X404902D01*
X403837Y1609056D01*
G01X408943Y1611741D02*
X408144D01*
X407794Y1611391D01*
X404902D01*
X403837Y1612456D01*
G01X426767Y124991D02*
X425838D01*
X425489Y125340D01*
X418647D01*
X417486Y124179D01*
G01X426767Y126960D02*
X425829D01*
X425479Y126610D01*
X418455D01*
X417486Y127579D01*
G01X423417Y893427D02*
X421579Y892380D01*
G01X412315Y893427D02*
X410477Y892380D01*
G01X419716Y893427D02*
X417878Y892380D01*
G01X412315Y887049D02*
X410477Y886002D01*
G01X423417Y899805D02*
X421579Y898758D01*
G01X423417Y906182D02*
X421579Y905135D01*
G01X412315Y899805D02*
X410477Y898758D01*
G01X412315Y906182D02*
X410477Y905135D01*
G01X419716Y899805D02*
X417878Y898758D01*
G01X419716Y906182D02*
X417878Y905135D01*
G01X423417Y918938D02*
X421579Y917891D01*
G01X423417Y912560D02*
X421579Y911513D01*
G01X423417Y925316D02*
X421579Y924269D01*
G01X412315Y918938D02*
X410477Y917891D01*
G01X412315Y912560D02*
X410477Y911513D01*
G01X412315Y925316D02*
X410477Y924269D01*
G01X419716Y918938D02*
X417878Y917891D01*
G01X419716Y912560D02*
X417878Y911513D01*
G01X419716Y925316D02*
X417878Y924269D01*
G01X419716Y938072D02*
X417878Y937025D01*
G01X423417Y938072D02*
X421579Y937025D01*
G01X419716Y944450D02*
X417878Y943403D01*
G01X419716Y950828D02*
X417878Y949781D01*
G01X423417Y944450D02*
X421579Y943403D01*
G01X412315Y950828D02*
X410477Y949781D01*
G01X412315Y944450D02*
X410477Y943403D01*
G01X423417Y950828D02*
X421579Y949781D01*
G01X419716Y957206D02*
X417878Y956159D01*
G01X423417Y957206D02*
X421579Y956159D01*
G01X412315Y957206D02*
X410477Y956159D01*
G01X419716Y963584D02*
X417878Y962537D01*
G01X419716Y969962D02*
X417878Y968915D01*
G01X423417Y963584D02*
X421579Y962537D01*
G01X423417Y969962D02*
X421579Y968915D01*
G01X412315Y963584D02*
X410477Y962537D01*
G01X412315Y969962D02*
X410477Y968915D01*
G01X419716Y976340D02*
X417878Y975293D01*
G01X423417Y976340D02*
X421579Y975293D01*
G01X412315Y976340D02*
X410477Y975293D01*
G01X420897Y1074844D02*
X419059Y1075891D01*
G01X420897Y1062088D02*
X419059Y1063135D01*
G01X420897Y1068466D02*
X419059Y1069513D01*
G01X424598Y1062088D02*
X422760Y1063135D01*
G01X413496Y1068466D02*
X411658Y1069513D01*
G01X413496Y1074844D02*
X411658Y1075891D01*
G01X413496Y1062088D02*
X411658Y1063135D01*
G01X424598Y1068466D02*
X422760Y1069513D01*
G01X424598Y1074844D02*
X422760Y1075891D01*
G01X420897Y1081222D02*
X419059Y1082269D01*
G01X420897Y1087600D02*
X419059Y1088647D01*
G01X424598Y1081222D02*
X422760Y1082269D01*
G01X413496Y1087600D02*
X411658Y1088647D01*
G01X413496Y1081222D02*
X411658Y1082269D01*
G01X424598Y1087600D02*
X422760Y1088647D01*
G01X420897Y1093978D02*
X419059Y1095025D01*
G01X420897Y1100356D02*
X419059Y1101403D01*
G01X424598Y1093978D02*
X422760Y1095025D01*
G01X424598Y1100356D02*
X422760Y1101403D01*
G01X413496Y1093978D02*
X411658Y1095025D01*
G01X424598Y1113112D02*
X422760Y1114159D01*
G01X413496Y1119490D02*
X411658Y1120537D01*
G01X413496Y1113112D02*
X411658Y1114159D01*
G01X420897Y1119490D02*
X419059Y1120537D01*
G01X420897Y1113112D02*
X419059Y1114159D01*
G01X424598Y1119490D02*
X422760Y1120537D01*
G01X424598Y1125868D02*
X422760Y1126915D01*
G01X413496Y1125868D02*
X411658Y1126915D01*
G01X420897Y1125868D02*
X419059Y1126915D01*
G01X424598Y1132246D02*
X422760Y1133293D01*
G01X413496Y1132246D02*
X411658Y1133293D01*
G01X420897Y1132246D02*
X419059Y1133293D01*
G01X424598Y1138623D02*
X422760Y1139670D01*
G01X424598Y1145001D02*
X422760Y1146048D01*
G01X413496Y1138623D02*
X411658Y1139670D01*
G01X413496Y1145001D02*
X411658Y1146048D01*
G01X420897Y1138623D02*
X419059Y1139670D01*
G01X420897Y1145001D02*
X419059Y1146048D01*
G01X420897Y1157757D02*
X419059Y1158804D01*
G01X417196Y1157757D02*
X415358Y1158804D01*
G01X413496Y1151379D02*
X411658Y1152426D01*
G01X424598Y1151379D02*
X422760Y1152426D01*
G01X420897Y1151379D02*
X419059Y1152426D01*
G01X420897Y1164135D02*
X419682Y1165350D01*
Y1182338D01*
X486122Y1248778D01*
Y1263409D01*
X487500Y1264787D01*
G01X417196Y1164135D02*
X418412Y1165351D01*
Y1182865D01*
X484852Y1249305D01*
Y1263435D01*
X483500Y1264787D01*
G01X417309Y1603375D02*
Y1602708D01*
X416959Y1602358D01*
Y1601203D01*
X416122Y1600366D01*
Y1598827D01*
X413396Y1596101D01*
Y1594597D01*
G01X423214Y1603375D02*
Y1602615D01*
X422865Y1602266D01*
Y1601407D01*
X424404Y1599868D01*
Y1596498D01*
X425469Y1595433D01*
G01X421246Y1603375D02*
Y1602655D01*
X421595Y1602306D01*
Y1600880D01*
X423134Y1599341D01*
Y1596498D01*
X422069Y1595433D01*
G01X415340Y1603375D02*
Y1602759D01*
X415689Y1602410D01*
Y1601730D01*
X414852Y1600893D01*
Y1599354D01*
X412500Y1597002D01*
X410991D01*
G01X417365Y1627695D02*
X418430Y1626630D01*
Y1625173D01*
X419626Y1623977D01*
Y1623225D01*
X419277Y1622876D01*
Y1622075D01*
G01X420765Y1627695D02*
X419700Y1626630D01*
Y1625700D01*
X420896Y1624504D01*
Y1623205D01*
X421246Y1622855D01*
Y1622075D01*
G01X432669Y896616D02*
X430831Y895569D01*
G01X428968Y896616D02*
X427130Y895569D01*
G01X432669Y902994D02*
X430831Y901947D01*
G01X432669Y909371D02*
X430831Y908325D01*
G01X428968Y902994D02*
X427130Y901947D01*
G01X428968Y909371D02*
X427130Y908325D01*
G01X432669Y915749D02*
X430831Y914702D01*
G01X432669Y922127D02*
X430831Y921080D01*
G01X428968Y915749D02*
X427130Y914702D01*
G01X428968Y922127D02*
X427130Y921080D01*
G01X432669Y928505D02*
X430831Y927458D01*
G01X428968Y928505D02*
X427130Y927458D01*
G01X428968Y941261D02*
X427130Y940214D01*
G01X432669Y941261D02*
X430831Y940214D01*
G01X428968Y947639D02*
X427130Y946592D01*
G01X428968Y954017D02*
X427130Y952970D01*
G01X432669Y947639D02*
X430831Y946592D01*
G01X432669Y954017D02*
X430831Y952970D01*
G01X428968Y960395D02*
X427130Y959348D01*
G01X428968Y966773D02*
X427130Y965726D01*
G01X432669Y960395D02*
X430831Y959348D01*
G01X432669Y966773D02*
X430831Y965726D01*
G01X428968Y979529D02*
X427130Y978482D01*
G01X428968Y973151D02*
X427130Y972104D01*
G01X432669Y979529D02*
X430831Y978482D01*
G01X432669Y973151D02*
X430831Y972104D01*
G01X430149Y1058899D02*
X428311Y1059946D01*
G01X433850Y1058899D02*
X432012Y1059946D01*
G01X430149Y1071655D02*
X428311Y1072702D01*
G01X430149Y1065277D02*
X428311Y1066324D01*
G01X433850Y1071655D02*
X432012Y1072702D01*
G01X433850Y1065277D02*
X432012Y1066324D01*
G01X430149Y1078033D02*
X428311Y1079080D01*
G01X433850Y1078033D02*
X432012Y1079080D01*
G01X430149Y1084411D02*
X428311Y1085458D01*
G01X433850Y1084411D02*
X432012Y1085458D01*
G01X430149Y1097167D02*
X428311Y1098214D01*
G01X430149Y1090789D02*
X428311Y1091836D01*
G01X433850Y1097167D02*
X432012Y1098214D01*
G01X433850Y1090789D02*
X432012Y1091836D01*
G01X433850Y1116301D02*
X432012Y1117348D01*
G01X433850Y1109923D02*
X432012Y1110970D01*
G01X430149Y1116301D02*
X428311Y1117348D01*
G01X430149Y1109923D02*
X428311Y1110970D01*
G01X433850Y1122679D02*
X432012Y1123726D01*
G01X430149Y1122679D02*
X428311Y1123726D01*
G01X433850Y1129057D02*
X432012Y1130103D01*
G01X430149Y1129057D02*
X428311Y1130103D01*
G01X433850Y1141812D02*
X432012Y1142859D01*
G01X433850Y1135434D02*
X432012Y1136481D01*
G01X430149Y1141812D02*
X428311Y1142859D01*
G01X430149Y1135434D02*
X428311Y1136481D01*
G01X428299Y1164135D02*
X429515Y1165351D01*
Y1187828D01*
X493865Y1252178D01*
Y1263422D01*
X492500Y1264787D01*
G01X432000Y1164135D02*
X430785Y1165350D01*
Y1187301D01*
X495135Y1251651D01*
Y1263422D01*
X496500Y1264787D01*
G01X436924Y1462595D02*
X435859Y1463660D01*
Y1466430D01*
X437024Y1467595D01*
G01X433524Y1462595D02*
X434589Y1463660D01*
Y1466430D01*
X433424Y1467595D01*
G01X427286Y1483590D02*
X428351Y1482525D01*
X431121D01*
X432286Y1483690D01*
G01X427286Y1480190D02*
X428351Y1481255D01*
X431121D01*
X432286Y1480090D01*
G01X427286Y1501990D02*
X428351Y1503055D01*
X431121D01*
X432286Y1501890D01*
G01X427286Y1505390D02*
X428351Y1504325D01*
X431121D01*
X432286Y1505490D01*
G01X432656Y1523431D02*
X433618Y1524393D01*
X434644D01*
X435606Y1523431D01*
G01D02*
X436523Y1524348D01*
X438591D01*
X439808Y1525565D01*
X442142D01*
G01X432656Y1526631D02*
X433624Y1525663D01*
X434638D01*
X435606Y1526631D01*
G01D02*
X436619Y1525618D01*
X438064D01*
X439281Y1526835D01*
X442217D01*
G01X426704Y1523331D02*
X427769Y1524396D01*
X429591D01*
X430556Y1523431D01*
G01X426704Y1526731D02*
X427769Y1525666D01*
X429591D01*
X430556Y1526631D01*
G01X427643Y1611741D02*
X428503D01*
X428853Y1611391D01*
X431704D01*
X433042Y1612729D01*
X435711D01*
X436776Y1613794D01*
G01X427643Y1609772D02*
X428460D01*
X428809Y1610121D01*
X432231D01*
X433569Y1611459D01*
X435711D01*
X436776Y1610394D01*
G01X450980Y106684D02*
Y105779D01*
X450631Y105430D01*
Y100896D01*
X454401Y97126D01*
Y89812D01*
X455502Y88711D01*
G01X449011Y106684D02*
Y105790D01*
X449361Y105440D01*
Y100369D01*
X453131Y96599D01*
Y89740D01*
X452102Y88711D01*
G01X447043Y106684D02*
Y105757D01*
X446694Y105408D01*
Y98055D01*
X447313Y97436D01*
Y95785D01*
X448414Y94684D01*
G01X445074Y106684D02*
Y105762D01*
X445424Y105412D01*
Y97528D01*
X446043Y96909D01*
Y95713D01*
X445014Y94684D01*
G01X447472Y896616D02*
X449310Y895569D01*
G01X451173Y896616D02*
X453011Y895569D01*
G01X447472Y909371D02*
X449310Y908325D01*
G01X447472Y902994D02*
X449310Y901947D01*
G01X451173Y909371D02*
X453011Y908325D01*
G01X451173Y902994D02*
X453011Y901947D01*
G01X447472Y922127D02*
X449310Y921080D01*
G01X447472Y915749D02*
X449310Y914702D01*
G01X451173Y922127D02*
X453011Y921080D01*
G01X451173Y915749D02*
X453011Y914702D01*
G01X451173Y941261D02*
X453011Y940214D01*
G01X447472Y941261D02*
X449310Y940214D01*
G01X447472Y928505D02*
X449310Y927458D01*
G01X451173Y928505D02*
X453011Y927458D01*
G01X451173Y954017D02*
X453011Y952970D01*
G01X451173Y947639D02*
X453011Y946592D01*
G01X447472Y954017D02*
X449310Y952970D01*
G01X447472Y947639D02*
X449310Y946592D01*
G01X451173Y960395D02*
X453011Y959348D01*
G01X451173Y966773D02*
X453011Y965726D01*
G01X447472Y960395D02*
X449310Y959348D01*
G01X447472Y966773D02*
X449310Y965726D01*
G01X451173Y979529D02*
X453011Y978482D01*
G01X451173Y973151D02*
X453011Y972104D01*
G01X447472Y979529D02*
X449310Y978482D01*
G01X447472Y973151D02*
X449310Y972104D01*
G01X452354Y1058899D02*
X454192Y1059946D01*
G01X448653Y1058899D02*
X450491Y1059946D01*
G01X452354Y1065277D02*
X454192Y1066324D01*
G01X452354Y1071655D02*
X454192Y1072702D01*
G01X448653Y1065277D02*
X450491Y1066324D01*
G01X448653Y1071655D02*
X450491Y1072702D01*
G01X452354Y1078033D02*
X454192Y1079080D01*
G01X448653Y1078033D02*
X450491Y1079080D01*
G01X452354Y1084411D02*
X454192Y1085458D01*
G01X448653Y1084411D02*
X450491Y1085458D01*
G01X452354Y1090789D02*
X454192Y1091836D01*
G01X452354Y1097167D02*
X454192Y1098214D01*
G01X448653Y1090789D02*
X450491Y1091836D01*
G01X448653Y1097167D02*
X450491Y1098214D01*
G01X448653Y1109923D02*
X450491Y1110970D01*
G01X448653Y1116301D02*
X450491Y1117348D01*
G01X452354Y1109923D02*
X454192Y1110970D01*
G01X452354Y1116301D02*
X454192Y1117348D01*
G01X448653Y1122679D02*
X450491Y1123726D01*
G01X452354Y1122679D02*
X454192Y1123726D01*
G01X448653Y1129057D02*
X450491Y1130103D01*
G01X452354Y1129057D02*
X454192Y1130103D01*
G01X448653Y1135434D02*
X450491Y1136481D01*
G01X448653Y1141812D02*
X450491Y1142859D01*
G01X452354Y1135434D02*
X454192Y1136481D01*
G01X452354Y1141812D02*
X454192Y1142859D01*
G01X443624Y1452895D02*
X442559Y1453960D01*
Y1456730D01*
X443724Y1457895D01*
G01X440224Y1452895D02*
X441289Y1453960D01*
Y1456730D01*
X440124Y1457895D01*
G01X453624Y1472295D02*
X454689Y1473360D01*
Y1476130D01*
X453524Y1477295D01*
G01X452239Y1607286D02*
X453404Y1606121D01*
Y1593445D01*
X452339Y1592380D01*
G01X452239Y1609386D02*
X453404Y1610551D01*
Y1623227D01*
X452339Y1624292D01*
G01X456885Y106684D02*
Y105859D01*
X456536Y105510D01*
Y102910D01*
X461355Y98091D01*
Y96202D01*
X462456Y95101D01*
G01X454917Y106684D02*
Y105841D01*
X455266Y105492D01*
Y102383D01*
X460085Y97564D01*
Y96130D01*
X459056Y95101D01*
G01X456724Y893427D02*
X458562Y892380D01*
G01X467826Y893427D02*
X469664Y892380D01*
G01X460425Y893427D02*
X462263Y892380D01*
G01X456724Y906182D02*
X458562Y905135D01*
G01X456724Y899805D02*
X458562Y898758D01*
G01X467826Y906182D02*
X469664Y905135D01*
G01X467826Y899805D02*
X469664Y898758D01*
G01X460425Y906182D02*
X462263Y905135D01*
G01X460425Y899805D02*
X462263Y898758D01*
G01X456724Y925316D02*
X458562Y924269D01*
G01X456724Y912560D02*
X458562Y911513D01*
G01X456724Y918938D02*
X458562Y917891D01*
G01X467826Y925316D02*
X469664Y924269D01*
G01X467826Y912560D02*
X469664Y911513D01*
G01X467826Y918938D02*
X469664Y917891D01*
G01X460425Y925316D02*
X462263Y924269D01*
G01X460425Y912560D02*
X462263Y911513D01*
G01X460425Y918938D02*
X462263Y917891D01*
G01X460425Y938072D02*
X462263Y937025D01*
G01X456724Y938072D02*
X458562Y937025D01*
G01X460425Y944450D02*
X462263Y943403D01*
G01X460425Y950828D02*
X462263Y949781D01*
G01X456724Y944450D02*
X458562Y943403D01*
G01X456724Y950828D02*
X458562Y949781D01*
G01X467826Y944450D02*
X469664Y943403D01*
G01X467826Y950828D02*
X469664Y949781D01*
G01X460425Y957206D02*
X462263Y956159D01*
G01X456724Y957206D02*
X458562Y956159D01*
G01X467826Y957206D02*
X469664Y956159D01*
G01X460425Y963584D02*
X462263Y962537D01*
G01X460425Y969962D02*
X462263Y968915D01*
G01X456724Y963584D02*
X458562Y962537D01*
G01X456724Y969962D02*
X458562Y968915D01*
G01X467826Y963584D02*
X469664Y962537D01*
G01X467826Y969962D02*
X469664Y968915D01*
G01X460425Y976340D02*
X462263Y975293D01*
G01X456724Y976340D02*
X458562Y975293D01*
G01X467826Y976340D02*
X469664Y975293D01*
G01X461606Y1062088D02*
X463444Y1063135D01*
G01X461606Y1074844D02*
X463444Y1075891D01*
G01X461606Y1068466D02*
X463444Y1069513D01*
G01X457905Y1062088D02*
X459743Y1063135D01*
G01X457905Y1074844D02*
X459743Y1075891D01*
G01X457905Y1068466D02*
X459743Y1069513D01*
G01X469007Y1062088D02*
X470845Y1063135D01*
G01X469007Y1074844D02*
X470845Y1075891D01*
G01X469007Y1068466D02*
X470845Y1069513D01*
G01X461606Y1081222D02*
X463444Y1082269D01*
G01X461606Y1087600D02*
X463444Y1088647D01*
G01X457905Y1081222D02*
X459743Y1082269D01*
G01X457905Y1087600D02*
X459743Y1088647D01*
G01X469007Y1081222D02*
X470845Y1082269D01*
G01X469007Y1087600D02*
X470845Y1088647D01*
G01X461606Y1100356D02*
X463444Y1101403D01*
G01X461606Y1093978D02*
X463444Y1095025D01*
G01X457905Y1100356D02*
X459743Y1101403D01*
G01X457905Y1093978D02*
X459743Y1095025D01*
G01X469007Y1093978D02*
X470845Y1095025D01*
G01X457905Y1113112D02*
X459743Y1114159D01*
G01X457905Y1119490D02*
X459743Y1120537D01*
G01X469007Y1113112D02*
X470845Y1114159D01*
G01X469007Y1119490D02*
X470845Y1120537D01*
G01X461606Y1113112D02*
X463444Y1114159D01*
G01X461606Y1119490D02*
X463444Y1120537D01*
G01X457905Y1125868D02*
X459743Y1126915D01*
G01X469007Y1125868D02*
X470845Y1126915D01*
G01X461606Y1125868D02*
X463444Y1126915D01*
G01X457905Y1132246D02*
X459743Y1133293D01*
G01X469007Y1132246D02*
X470845Y1133293D01*
G01X461606Y1132246D02*
X463444Y1133293D01*
G01X457905Y1145001D02*
X459743Y1146048D01*
G01X457905Y1138623D02*
X459743Y1139670D01*
G01X469007Y1145001D02*
X470845Y1146048D01*
G01X469007Y1138623D02*
X470845Y1139670D01*
G01X461606Y1145001D02*
X463444Y1146048D01*
G01X461606Y1138623D02*
X463444Y1139670D01*
G01X470424Y1452895D02*
X469359Y1453960D01*
Y1456730D01*
X470524Y1457895D01*
G01X467024Y1452895D02*
X468089Y1453960D01*
Y1456730D01*
X466924Y1457895D01*
G01X457024Y1472295D02*
X455959Y1473360D01*
Y1476130D01*
X457124Y1477295D01*
G01X463724Y1462595D02*
X462659Y1463660D01*
Y1466430D01*
X463824Y1467595D01*
G01X460324Y1462595D02*
X461389Y1463660D01*
Y1466430D01*
X460224Y1467595D01*
G01X464299Y1607286D02*
X465464Y1606121D01*
Y1593445D01*
X464399Y1592380D01*
G01X455839Y1607286D02*
X454674Y1606121D01*
Y1593445D01*
X455739Y1592380D01*
G01X467899Y1607286D02*
X466734Y1606121D01*
Y1593445D01*
X467799Y1592380D01*
G01X464299Y1609386D02*
X465464Y1610551D01*
Y1623227D01*
X464399Y1624292D01*
G01X455839Y1609386D02*
X454674Y1610551D01*
Y1623227D01*
X455739Y1624292D01*
G01X467899Y1609386D02*
X466734Y1610551D01*
Y1623227D01*
X467799Y1624292D01*
G01X480930Y139492D02*
X479357D01*
X477429Y141420D01*
X475737D01*
X474740Y140423D01*
Y139475D01*
X475470Y138745D01*
Y137245D01*
X474740Y136515D01*
Y135319D01*
X475470Y134589D01*
Y133089D01*
X474740Y132359D01*
Y130859D01*
X475579Y130020D01*
X476295D01*
G01X480930Y144392D02*
X479112D01*
X477410Y142690D01*
X475210D01*
X473470Y140950D01*
Y130595D01*
X472895Y130020D01*
G01X482255Y133222D02*
X483320Y132157D01*
X485385D01*
X487170Y133942D01*
X488930D01*
G01X482255Y129822D02*
X483320Y130887D01*
X485430D01*
X487375Y128942D01*
X488930D01*
G01X484080Y139492D02*
Y140242D01*
X485780Y141942D01*
G01X484080Y144392D02*
Y143642D01*
X482380Y141942D01*
G01X478929Y893427D02*
X480767Y892380D01*
G01X482629Y893427D02*
X484467Y892380D01*
G01X471527Y893427D02*
X473365Y892380D01*
G01X478929Y899805D02*
X480767Y898758D01*
G01X478929Y906182D02*
X480767Y905135D01*
G01X482629Y899805D02*
X484467Y898758D01*
G01X471527Y906182D02*
X473365Y905135D01*
G01X471527Y899805D02*
X473365Y898758D01*
G01X482629Y906182D02*
X484467Y905135D01*
G01X478929Y912560D02*
X480767Y911513D01*
G01X478929Y918938D02*
X480767Y917891D01*
G01X478929Y925316D02*
X480767Y924269D01*
G01X482629Y912560D02*
X484467Y911513D01*
G01X482629Y918938D02*
X484467Y917891D01*
G01X482629Y925316D02*
X484467Y924269D01*
G01X471527Y925316D02*
X473365Y924269D01*
G01X471527Y912560D02*
X473365Y911513D01*
G01X471527Y918938D02*
X473365Y917891D01*
G01X478929Y931694D02*
X480767Y930647D01*
G01X482629Y931694D02*
X484467Y930647D01*
G01X482629Y944450D02*
X484467Y943403D01*
G01X482629Y950828D02*
X484467Y949781D01*
G01X471527Y944450D02*
X473365Y943403D01*
G01X471527Y950828D02*
X473365Y949781D01*
G01X478929Y944450D02*
X480767Y943403D01*
G01X478929Y950828D02*
X480767Y949781D01*
G01X482629Y957206D02*
X484467Y956159D01*
G01X471527Y957206D02*
X473365Y956159D01*
G01X478929Y957206D02*
X480767Y956159D01*
G01X482629Y963584D02*
X484467Y962537D01*
G01X482629Y969962D02*
X484467Y968915D01*
G01X471527Y963584D02*
X473365Y962537D01*
G01X471527Y969962D02*
X473365Y968915D01*
G01X478929Y963584D02*
X480767Y962537D01*
G01X478929Y969962D02*
X480767Y968915D01*
G01X482629Y976340D02*
X484467Y975293D01*
G01X471527Y976340D02*
X473365Y975293D01*
G01X478929Y976340D02*
X480767Y975293D01*
G01X483811Y1062088D02*
X485649Y1063135D01*
G01X483811Y1074844D02*
X485649Y1075891D01*
G01X483811Y1068466D02*
X485649Y1069513D01*
G01X472708Y1062088D02*
X474546Y1063135D01*
G01X472708Y1074844D02*
X474546Y1075891D01*
G01X472708Y1068466D02*
X474546Y1069513D01*
G01X480110Y1062088D02*
X481948Y1063135D01*
G01X480110Y1074844D02*
X481948Y1075891D01*
G01X480110Y1068466D02*
X481948Y1069513D01*
G01X483811Y1081222D02*
X485649Y1082269D01*
G01X483811Y1087600D02*
X485649Y1088647D01*
G01X472708Y1081222D02*
X474546Y1082269D01*
G01X472708Y1087600D02*
X474546Y1088647D01*
G01X480110Y1081222D02*
X481948Y1082269D01*
G01X480110Y1087600D02*
X481948Y1088647D01*
G01X483811Y1093978D02*
X485649Y1095025D01*
G01X472708Y1093978D02*
X474546Y1095025D01*
G01X480110Y1093978D02*
X481948Y1095025D01*
G01X480110Y1119490D02*
X481948Y1120537D01*
G01X480110Y1113112D02*
X481948Y1114159D01*
G01X480110Y1106734D02*
X481948Y1107781D01*
G01X483811Y1119490D02*
X485649Y1120537D01*
G01X483811Y1113112D02*
X485649Y1114159D01*
G01X472708Y1113112D02*
X474546Y1114159D01*
G01X472708Y1119490D02*
X474546Y1120537D01*
G01X483811Y1106734D02*
X485649Y1107781D01*
G01X480110Y1125868D02*
X481948Y1126915D01*
G01X483811Y1125868D02*
X485649Y1126915D01*
G01X472708Y1125868D02*
X474546Y1126915D01*
G01X480110Y1132246D02*
X481948Y1133293D01*
G01X472708Y1132246D02*
X474546Y1133293D01*
G01X483811Y1132246D02*
X485649Y1133293D01*
G01X480110Y1145001D02*
X481948Y1146048D01*
G01X480110Y1138623D02*
X481948Y1139670D01*
G01X483811Y1145001D02*
X485649Y1146048D01*
G01X483811Y1138623D02*
X485649Y1139670D01*
G01X472708Y1145001D02*
X474546Y1146048D01*
G01X472708Y1138623D02*
X474546Y1139670D01*
G01X483500Y1267937D02*
X484865Y1269302D01*
Y1340924D01*
G01X475865Y1361180D02*
Y1269440D01*
X474500Y1268075D01*
G01X478500D02*
X477135Y1269440D01*
Y1371685D01*
G01X475865Y1361180D02*
Y1375073D01*
X538511Y1437719D01*
Y1438780D01*
X539594Y1439863D01*
X540655D01*
X541736Y1440944D01*
Y1442005D01*
X542819Y1443088D01*
X543880D01*
X544961Y1444169D01*
Y1445229D01*
X546044Y1446312D01*
X547104D01*
X548675Y1447883D01*
Y1454253D01*
X547891Y1455037D01*
X547183D01*
X546253Y1454107D01*
G01X477135Y1371685D02*
Y1374546D01*
X549945Y1447356D01*
Y1454780D01*
X548418Y1456307D01*
X547453D01*
X546253Y1457507D01*
G01X483824Y1472295D02*
X482759Y1473360D01*
Y1476130D01*
X483924Y1477295D01*
G01X480424Y1472295D02*
X481489Y1473360D01*
Y1476130D01*
X480324Y1477295D01*
G01X476359Y1607286D02*
X477524Y1606121D01*
Y1593445D01*
X476459Y1592380D01*
G01X479959Y1607286D02*
X478794Y1606121D01*
Y1593445D01*
X479859Y1592380D01*
G01X476359Y1609386D02*
X477524Y1610551D01*
Y1623227D01*
X476459Y1624292D01*
G01X479959Y1609386D02*
X478794Y1610551D01*
Y1623227D01*
X479859Y1624292D01*
G01X490380Y131442D02*
X492080Y133142D01*
Y133942D01*
G01X493780Y131442D02*
X492080Y129742D01*
Y128942D01*
G01X507261Y134147D02*
X504748D01*
X504570Y133969D01*
X503808D01*
X503064Y133661D01*
X501400Y131997D01*
X498730D01*
X496785Y133942D01*
X495230D01*
G01X506670Y132573D02*
X505921D01*
X505920Y132572D01*
X504749D01*
X504622Y132699D01*
X504061D01*
X503784Y132583D01*
X501927Y130727D01*
X498775D01*
X496498Y128450D01*
X495722D01*
X495230Y128942D01*
G01X487230Y139492D02*
X488822D01*
X490720Y141390D01*
X493344D01*
X497284Y137450D01*
X504596D01*
X504749Y137297D01*
X507261D01*
G01X487230Y144392D02*
X488867D01*
X490599Y142660D01*
X493871D01*
X497811Y138720D01*
X504596D01*
X504748Y138872D01*
X507261D01*
G01X490031Y893427D02*
X491869Y892380D01*
G01X493732Y893427D02*
X495570Y892380D01*
G01X490031Y906182D02*
X491869Y905135D01*
G01X490031Y899805D02*
X491869Y898758D01*
G01X493732Y906182D02*
X495570Y905135D01*
G01X493732Y899805D02*
X495570Y898758D01*
G01X490031Y912560D02*
X491869Y911513D01*
G01X493732Y912560D02*
X495570Y911513D01*
G01X490031Y918938D02*
X491869Y917891D01*
G01X490031Y925316D02*
X491869Y924269D01*
G01X493732Y918938D02*
X495570Y917891D01*
G01X493732Y925316D02*
X495570Y924269D01*
G01X490031Y931694D02*
X491869Y930647D01*
G01X493732Y931694D02*
X495570Y930647D01*
G01X493732Y944450D02*
X495570Y943403D01*
G01X493732Y950828D02*
X495570Y949781D01*
G01X490031Y944450D02*
X491869Y943403D01*
G01X490031Y950828D02*
X491869Y949781D01*
G01X493732Y957206D02*
X495570Y956159D01*
G01X490031Y957206D02*
X491869Y956159D01*
G01X493732Y963584D02*
X495570Y962537D01*
G01X493732Y969962D02*
X495570Y968915D01*
G01X490031Y963584D02*
X491869Y962537D01*
G01X490031Y969962D02*
X491869Y968915D01*
G01X493732Y976340D02*
X495570Y975293D01*
G01X490031Y976340D02*
X491869Y975293D01*
G01X494913Y1062088D02*
X496751Y1063135D01*
G01X494913Y1074844D02*
X496751Y1075891D01*
G01X494913Y1068466D02*
X496751Y1069513D01*
G01X491212Y1062088D02*
X493050Y1063135D01*
G01X491212Y1074844D02*
X493050Y1075891D01*
G01X491212Y1068466D02*
X493050Y1069513D01*
G01X494913Y1081222D02*
X496751Y1082269D01*
G01X494913Y1087600D02*
X496751Y1088647D01*
G01X491212Y1081222D02*
X493050Y1082269D01*
G01X491212Y1087600D02*
X493050Y1088647D01*
G01X494913Y1093978D02*
X496751Y1095025D01*
G01X491212Y1093978D02*
X493050Y1095025D01*
G01X491212Y1106734D02*
X493050Y1107781D01*
G01X491212Y1119490D02*
X493050Y1120537D01*
G01X491212Y1113112D02*
X493050Y1114159D01*
G01X494913Y1106734D02*
X496751Y1107781D01*
G01X494913Y1119490D02*
X496751Y1120537D01*
G01X494913Y1113112D02*
X496751Y1114159D01*
G01X491212Y1132246D02*
X493050Y1133293D01*
G01X491212Y1125868D02*
X493050Y1126915D01*
G01X494913Y1132246D02*
X496751Y1133293D01*
G01X494913Y1125868D02*
X496751Y1126915D01*
G01X491212Y1145001D02*
X493050Y1146048D01*
G01X491212Y1138623D02*
X493050Y1139670D01*
G01X494913Y1145001D02*
X496751Y1146048D01*
G01X494913Y1138623D02*
X496751Y1139670D01*
G01X492500Y1267937D02*
X493865Y1269302D01*
Y1279971D01*
X628988Y1415094D01*
G01X496500Y1267937D02*
X495135Y1269302D01*
Y1279443D01*
X497519Y1281827D01*
X498580D01*
X499663Y1282910D01*
Y1283971D01*
X500744Y1285052D01*
X501805D01*
X502888Y1286135D01*
Y1287196D01*
X503969Y1288277D01*
X505030D01*
X506113Y1289360D01*
Y1290421D01*
X637447Y1421755D01*
G01X487500Y1267937D02*
X486135Y1269302D01*
Y1351429D01*
G01X484865Y1340924D02*
Y1377964D01*
X554296Y1447395D01*
Y1455469D01*
X556067Y1457240D01*
X557811D01*
X558876Y1458305D01*
G01X486135Y1351429D02*
Y1363757D01*
X486885Y1364507D01*
Y1366037D01*
X486135Y1366787D01*
Y1368317D01*
X486885Y1369067D01*
Y1370597D01*
X486135Y1371347D01*
Y1372877D01*
X486885Y1373627D01*
Y1375157D01*
X486135Y1375907D01*
Y1377437D01*
X555566Y1446868D01*
Y1454942D01*
X556594Y1455970D01*
X557811D01*
X558876Y1454905D01*
G01X497224Y1452895D02*
X496159Y1453960D01*
Y1456730D01*
X497324Y1457895D01*
G01X493824Y1452895D02*
X494889Y1453960D01*
Y1456730D01*
X493724Y1457895D01*
G01X490524Y1462595D02*
X489459Y1463660D01*
Y1466430D01*
X490624Y1467595D01*
G01X487124Y1462595D02*
X488189Y1463660D01*
Y1466430D01*
X487024Y1467595D01*
G01X488419Y1607286D02*
X489584Y1606121D01*
Y1593445D01*
X488519Y1592380D01*
G01X492019Y1607286D02*
X490854Y1606121D01*
Y1593445D01*
X491919Y1592380D01*
G01X488419Y1609386D02*
X489584Y1610551D01*
Y1623227D01*
X488519Y1624292D01*
G01X492019Y1609386D02*
X490854Y1610551D01*
Y1623227D01*
X491919Y1624292D01*
G01X513177Y53543D02*
Y51280D01*
X513723Y50734D01*
Y47678D01*
X512658Y46613D01*
G01X514240Y97146D02*
X515355Y98261D01*
Y100636D01*
X513770Y102221D01*
Y105220D01*
G01Y107320D02*
X514300D01*
X516020Y109040D01*
Y109270D01*
G01X515385Y115300D02*
Y113954D01*
X513770Y112339D01*
Y109420D01*
G01X504834Y874293D02*
X506050Y873077D01*
Y871188D01*
X507450Y869788D01*
X510566Y868497D01*
X510937Y868126D01*
Y866692D01*
X509572Y865327D01*
G01X508535Y874293D02*
X507320Y873078D01*
Y871715D01*
X508170Y870865D01*
X511286Y869574D01*
X512207Y868653D01*
Y866692D01*
X513572Y865327D01*
G01X506685Y896616D02*
X508523Y895569D01*
G01X502984Y896616D02*
X504822Y895569D01*
G01X508535Y893427D02*
X510373Y892380D01*
G01X501133Y899805D02*
X502971Y898758D01*
G01X514086Y896616D02*
X515924Y895569D01*
G01X506685Y915749D02*
X508523Y914702D01*
G01X502984Y915749D02*
X504822Y914702D01*
G01X508535Y912560D02*
X510373Y911513D01*
G01X501133Y918938D02*
X502971Y917891D01*
G01X514086Y915749D02*
X515924Y914702D01*
G01X506685Y934883D02*
X508523Y933836D01*
G01X502984Y934883D02*
X504822Y933836D01*
G01X508535Y931694D02*
X510373Y930647D01*
G01X501133Y938072D02*
X502971Y937025D01*
G01X514086Y934883D02*
X515924Y933836D01*
G01X506685Y954017D02*
X508523Y952970D01*
G01X502984Y954017D02*
X504822Y952970D01*
G01X508535Y950828D02*
X510373Y949781D01*
G01X514086Y954017D02*
X515924Y952970D01*
G01X508535Y969962D02*
X510373Y968915D01*
G01X501133Y957206D02*
X502971Y956159D01*
G01X506685Y973151D02*
X508523Y972104D01*
G01X502984Y973151D02*
X504822Y972104D01*
G01X501133Y976340D02*
X502971Y975293D01*
G01X514086Y973151D02*
X515924Y972104D01*
G01X502315Y1068466D02*
X504153Y1069513D01*
G01X509716Y1068466D02*
X511554Y1069513D01*
G01X504165Y1071655D02*
X506003Y1072702D01*
G01X507866Y1065277D02*
X509704Y1066324D01*
G01X509716Y1087600D02*
X511554Y1088647D01*
G01X502315Y1087600D02*
X504153Y1088647D01*
G01X507866Y1084411D02*
X509704Y1085458D01*
G01X507866Y1103545D02*
X509704Y1104592D01*
G01X504165Y1090789D02*
X506003Y1091836D01*
G01X509716Y1106734D02*
X511554Y1107781D01*
G01X502315Y1106734D02*
X504153Y1107781D01*
G01X504165Y1109923D02*
X506003Y1110970D01*
G01X509716Y1125868D02*
X511554Y1126915D01*
G01X502315Y1125868D02*
X504153Y1126915D01*
G01X507866Y1122679D02*
X509704Y1123726D01*
G01X504165Y1129057D02*
X506003Y1130103D01*
G01X509716Y1145001D02*
X511554Y1146048D01*
G01X502315Y1145001D02*
X504153Y1146048D01*
G01X507866Y1141812D02*
X509704Y1142859D01*
G01X504165Y1148190D02*
X506003Y1149237D01*
G01X510624Y1472295D02*
X509559Y1473360D01*
Y1476130D01*
X510724Y1477295D01*
G01X507224Y1472295D02*
X508289Y1473360D01*
Y1476130D01*
X507124Y1477295D01*
G01X513924Y1462595D02*
X514989Y1463660D01*
Y1466430D01*
X513824Y1467595D01*
G01X500479Y1607286D02*
X501644Y1606121D01*
Y1593445D01*
X500579Y1592380D01*
G01X512539Y1607286D02*
X513704Y1606121D01*
Y1593445D01*
X512639Y1592380D01*
G01X504079Y1607286D02*
X502914Y1606121D01*
Y1593445D01*
X503979Y1592380D01*
G01X500479Y1609386D02*
X501644Y1610551D01*
Y1623227D01*
X500579Y1624292D01*
G01X512539Y1609386D02*
X513704Y1610551D01*
Y1623227D01*
X512639Y1624292D01*
G01X504079Y1609386D02*
X502914Y1610551D01*
Y1623227D01*
X503979Y1624292D01*
G01X520264Y53543D02*
Y51426D01*
X520810Y50880D01*
Y41373D01*
X519765Y40328D01*
G01X522626Y53543D02*
Y51162D01*
X522080Y50616D01*
Y41413D01*
X523165Y40328D01*
G01X515539Y53543D02*
Y51256D01*
X514993Y50710D01*
Y47678D01*
X516058Y46613D01*
G01X520264Y65157D02*
Y67287D01*
X520810Y67833D01*
Y70369D01*
X519743Y71436D01*
G01X522626Y65157D02*
Y67375D01*
X522080Y67921D01*
Y70373D01*
X523143Y71436D01*
G01X518270Y107320D02*
X517770D01*
X516020Y105570D01*
Y105370D01*
G01X526460Y100895D02*
X527643Y99712D01*
X529172D01*
X532274Y96610D01*
X533514D01*
X534264Y97360D01*
X535784D01*
X536534Y96610D01*
X538054D01*
X538804Y97360D01*
X540324D01*
X541074Y96610D01*
X543893D01*
X545640Y98357D01*
Y102233D01*
X543893Y103980D01*
X542373D01*
X541623Y103230D01*
X540103D01*
X539353Y103980D01*
X536039D01*
X534541Y105478D01*
Y106669D01*
X532920Y108290D01*
Y111080D01*
G01X526460Y97495D02*
X527407Y98442D01*
X528645D01*
X531747Y95340D01*
X544420D01*
X546910Y97830D01*
Y102760D01*
X544420Y105250D01*
X536566D01*
X535811Y106005D01*
Y106651D01*
X537420Y108260D01*
Y111080D01*
G01X517640Y97146D02*
X516625Y98161D01*
Y100716D01*
X518270Y102361D01*
Y105220D01*
G01X519116Y124200D02*
Y119820D01*
X516655Y117359D01*
Y114045D01*
X518270Y112430D01*
Y109420D01*
G01X517694Y130014D02*
Y127501D01*
X517846Y127349D01*
Y120347D01*
X515385Y117886D01*
Y115300D01*
G01X532920Y115280D02*
Y118079D01*
X534615Y119774D01*
Y120310D01*
X533995Y120930D01*
X527280D01*
G01X520843Y130014D02*
Y127501D01*
X520995Y127349D01*
Y124405D01*
X524470Y120930D01*
X527280D01*
G01X522418Y130014D02*
Y127502D01*
X522265Y127349D01*
Y124932D01*
X524997Y122200D01*
X533520D01*
G01X519268Y130014D02*
Y127501D01*
X519116Y127349D01*
Y124200D01*
G01X521488Y896616D02*
X523326Y895569D01*
G01X519637Y893427D02*
X521475Y892380D01*
G01X528889Y896616D02*
X530727Y895569D01*
G01X527039Y899805D02*
X528877Y898758D01*
G01X515937Y899805D02*
X517775Y898758D01*
G01X528889Y915749D02*
X530727Y914702D01*
G01X527039Y918938D02*
X528877Y917891D01*
G01X521488Y915749D02*
X523326Y914702D01*
G01X519637Y912560D02*
X521475Y911513D01*
G01X515937Y918938D02*
X517775Y917891D01*
G01X528889Y934883D02*
X530727Y933836D01*
G01X527039Y938072D02*
X528877Y937025D01*
G01X521488Y934883D02*
X523326Y933836D01*
G01X519637Y931694D02*
X521475Y930647D01*
G01X515937Y938072D02*
X517775Y937025D01*
G01X528889Y954017D02*
X530727Y952970D01*
G01X521488Y954017D02*
X523326Y952970D01*
G01X519637Y950828D02*
X521475Y949781D01*
G01X527039Y957206D02*
X528877Y956159D01*
G01X519637Y969962D02*
X521475Y968915D01*
G01X515937Y957206D02*
X517775Y956159D01*
G01X528889Y973151D02*
X530727Y972104D01*
G01X527039Y976340D02*
X528877Y975293D01*
G01X521488Y973151D02*
X523326Y972104D01*
G01X515937Y976340D02*
X517775Y975293D01*
G01X528220Y1068466D02*
X530058Y1069513D01*
G01X517118Y1068466D02*
X518956Y1069513D01*
G01X520818Y1068466D02*
X522657Y1069513D01*
G01X515267Y1071655D02*
X517105Y1072702D01*
G01X522669Y1065277D02*
X524507Y1066324D01*
G01X528220Y1087600D02*
X530058Y1088647D01*
G01X520818Y1087600D02*
X522657Y1088647D01*
G01X517118Y1087600D02*
X518956Y1088647D01*
G01X522669Y1084411D02*
X524507Y1085458D01*
G01X522669Y1103545D02*
X524507Y1104592D01*
G01X515267Y1090789D02*
X517105Y1091836D01*
G01X528220Y1106734D02*
X530058Y1107781D01*
G01X520818Y1106734D02*
X522657Y1107781D01*
G01X517118Y1106734D02*
X518956Y1107781D01*
G01X515267Y1109923D02*
X517105Y1110970D01*
G01X528220Y1125868D02*
X530058Y1126915D01*
G01X520818Y1125868D02*
X522657Y1126915D01*
G01X517118Y1125868D02*
X518956Y1126915D01*
G01X522669Y1122679D02*
X524507Y1123726D01*
G01X515267Y1129057D02*
X517105Y1130103D01*
G01X528220Y1145001D02*
X530058Y1146048D01*
G01X520818Y1145001D02*
X522657Y1146048D01*
G01X517118Y1145001D02*
X518956Y1146048D01*
G01X522669Y1141812D02*
X524507Y1142859D01*
G01X515267Y1148190D02*
X517105Y1149237D01*
G01X524024Y1452895D02*
X522959Y1453960D01*
Y1456730D01*
X524124Y1457895D01*
G01X520624Y1452895D02*
X521689Y1453960D01*
Y1456730D01*
X520524Y1457895D01*
G01X517324Y1462595D02*
X516259Y1463660D01*
Y1466430D01*
X517424Y1467595D01*
G01X524599Y1607286D02*
X525764Y1606121D01*
Y1593445D01*
X524699Y1592380D01*
G01X516139Y1607286D02*
X514974Y1606121D01*
Y1593445D01*
X516039Y1592380D01*
G01X528199Y1607286D02*
X527034Y1606121D01*
Y1593445D01*
X528099Y1592380D01*
G01X524599Y1609386D02*
X525764Y1610551D01*
Y1623227D01*
X524699Y1624292D01*
G01X516139Y1609386D02*
X514974Y1610551D01*
Y1623227D01*
X516039Y1624292D01*
G01X528199Y1609386D02*
X527034Y1610551D01*
Y1623227D01*
X528099Y1624292D01*
G01X534437Y53543D02*
Y51426D01*
X534983Y50880D01*
Y48132D01*
X533918Y47067D01*
G01X536799Y53543D02*
Y51162D01*
X536253Y50616D01*
Y48132D01*
X537318Y47067D01*
G01X534437Y65157D02*
Y67371D01*
X534983Y67917D01*
Y85981D01*
X538210Y89208D01*
Y90618D01*
G01X536799Y65157D02*
Y67391D01*
X536253Y67937D01*
Y76504D01*
X536983Y77234D01*
Y78734D01*
X536253Y79464D01*
Y80964D01*
X536983Y81694D01*
Y83194D01*
X536253Y83924D01*
Y85454D01*
X539012Y88213D01*
X540615D01*
G01X541524Y65157D02*
Y67287D01*
X542070Y67833D01*
Y70369D01*
X541003Y71436D01*
G01X543886Y65157D02*
Y67375D01*
X543340Y67921D01*
Y70373D01*
X544403Y71436D01*
G01X537420Y115280D02*
Y118060D01*
X535885Y119595D01*
Y120837D01*
X534522Y122200D01*
X533520D01*
G01X535170Y111230D02*
Y111480D01*
X533470Y113180D01*
X532920D01*
G01X535170Y115130D02*
Y114880D01*
X536870Y113180D01*
X537420D01*
G01X537575Y138872D02*
X540088D01*
X540212Y138996D01*
X544298D01*
X545048Y138246D01*
X546568D01*
X547318Y138996D01*
X548838D01*
X549912Y137922D01*
Y136861D01*
X550988Y135785D01*
X552049D01*
X553225Y134609D01*
Y133189D01*
X552475Y132439D01*
Y130919D01*
X553225Y130169D01*
Y129326D01*
X551280Y127381D01*
Y126090D01*
G01X537575Y140447D02*
X540087D01*
X540268Y140266D01*
X549365D01*
X554495Y135136D01*
Y129335D01*
X556280Y127550D01*
Y126090D01*
G01X568360Y125935D02*
Y127903D01*
X570405Y129948D01*
Y132395D01*
X565446Y137354D01*
X564385D01*
X563309Y138430D01*
Y139491D01*
X562235Y140565D01*
X561174D01*
X560098Y141641D01*
Y142702D01*
X559024Y143776D01*
X554490D01*
X553740Y143026D01*
X552220D01*
X551470Y143776D01*
X540268D01*
X540088Y143596D01*
X537575D01*
G01X573360Y125935D02*
Y128092D01*
X571675Y129777D01*
Y132922D01*
X559551Y145046D01*
X540212D01*
X540087Y145171D01*
X537575D01*
G01X538141Y874293D02*
X539357Y873077D01*
Y867234D01*
X540956Y865635D01*
Y852865D01*
X536779Y842776D01*
Y827212D01*
X586592Y777399D01*
X588886Y771861D01*
Y769200D01*
G01X536320Y871396D02*
Y865685D01*
X538767Y863238D01*
Y852857D01*
X533703Y840629D01*
Y827192D01*
X581760Y779135D01*
Y759700D01*
G01X535050Y871396D02*
Y865158D01*
X537497Y862711D01*
Y853110D01*
X532433Y840882D01*
Y826665D01*
X570857Y788241D01*
Y787180D01*
X571933Y786104D01*
X572994D01*
X574068Y785030D01*
Y783969D01*
X575144Y782893D01*
X576205D01*
X577279Y781819D01*
Y780758D01*
X578355Y779682D01*
X579416D01*
X580490Y778608D01*
Y769100D01*
G01X600647Y772929D02*
X543600Y829976D01*
Y841838D01*
X550459Y858397D01*
Y873078D01*
X549244Y874293D01*
G01X541842D02*
X540627Y873078D01*
Y867761D01*
X542226Y866162D01*
Y852612D01*
X538049Y842523D01*
Y827739D01*
X587669Y778119D01*
X590156Y772115D01*
Y759400D01*
G01X547988Y870766D02*
Y857904D01*
X541508Y842262D01*
Y828985D01*
X594619Y775874D01*
X598124Y767411D01*
Y759500D01*
G01X546718Y870766D02*
Y867215D01*
X545968Y866465D01*
Y864945D01*
X546718Y864195D01*
Y862675D01*
X545968Y861925D01*
Y860405D01*
X546718Y859655D01*
Y858157D01*
X540238Y842515D01*
Y828458D01*
X593542Y775154D01*
X596854Y767158D01*
Y765500D01*
G01X532590Y896616D02*
X534428Y895569D01*
G01X534441Y893427D02*
X536279Y892380D01*
G01X539992Y896616D02*
X541830Y895569D01*
G01X541842Y899805D02*
X543680Y898758D01*
G01X532590Y915749D02*
X534428Y914702D01*
G01X534441Y912560D02*
X536279Y911513D01*
G01X539992Y915749D02*
X541830Y914702D01*
G01X541842Y918938D02*
X543680Y917891D01*
G01X532590Y934883D02*
X534428Y933836D01*
G01X534441Y931694D02*
X536279Y930647D01*
G01X539992Y934883D02*
X541830Y933836D01*
G01X541842Y938072D02*
X543680Y937025D01*
G01X532590Y954017D02*
X534428Y952970D01*
G01X534441Y950828D02*
X536279Y949781D01*
G01X539992Y954017D02*
X541830Y952970D01*
G01X534441Y969962D02*
X536279Y968915D01*
G01X541842Y957206D02*
X543680Y956159D01*
G01X532590Y973151D02*
X534428Y972104D01*
G01X539992Y973151D02*
X541830Y972104D01*
G01X541842Y976340D02*
X543680Y975293D01*
G01X535622Y1068466D02*
X537460Y1069513D01*
G01X530070Y1071655D02*
X531908Y1072702D01*
G01X533771Y1065277D02*
X535609Y1066324D01*
G01X543023Y1068466D02*
X544861Y1069513D01*
G01X541173Y1071655D02*
X543011Y1072702D01*
G01X535622Y1087600D02*
X537460Y1088647D01*
G01X533771Y1084411D02*
X535609Y1085458D01*
G01X543023Y1087600D02*
X544861Y1088647D01*
G01X533771Y1103545D02*
X535609Y1104592D01*
G01X530070Y1090789D02*
X531908Y1091836D01*
G01X541173Y1090789D02*
X543011Y1091836D01*
G01X535622Y1106734D02*
X537460Y1107781D01*
G01X530070Y1109923D02*
X531908Y1110970D01*
G01X543023Y1106734D02*
X544861Y1107781D01*
G01X541173Y1109923D02*
X543011Y1110970D01*
G01X535622Y1125868D02*
X537460Y1126915D01*
G01X533771Y1122679D02*
X535609Y1123726D01*
G01X530070Y1129057D02*
X531908Y1130103D01*
G01X543023Y1125868D02*
X544861Y1126915D01*
G01X541173Y1129057D02*
X543011Y1130103D01*
G01X535622Y1145001D02*
X537460Y1146048D01*
G01X533771Y1141812D02*
X535609Y1142859D01*
G01X530070Y1148190D02*
X531908Y1149237D01*
G01X543023Y1145001D02*
X544861Y1146048D01*
G01X541173Y1148190D02*
X543011Y1149237D01*
G01X537424Y1452895D02*
X536359Y1453960D01*
Y1456730D01*
X537524Y1457895D01*
G01X534024Y1452895D02*
X535089Y1453960D01*
Y1456730D01*
X533924Y1457895D01*
G01X544794Y1480682D02*
X543729Y1481747D01*
X540959D01*
X539794Y1480582D01*
G01X544794Y1484082D02*
X543729Y1483017D01*
X540959D01*
X539794Y1484182D01*
G01X544794Y1497482D02*
X543729Y1496417D01*
X540959D01*
X539794Y1497582D01*
G01X544794Y1494082D02*
X543729Y1495147D01*
X540959D01*
X539794Y1493982D01*
G01X536659Y1607286D02*
X537824Y1606121D01*
Y1593445D01*
X536759Y1592380D01*
G01X540259Y1607286D02*
X539094Y1606121D01*
Y1593445D01*
X540159Y1592380D01*
G01X536659Y1609386D02*
X537824Y1610551D01*
Y1623227D01*
X536759Y1624292D01*
G01X540259Y1609386D02*
X539094Y1610551D01*
Y1623227D01*
X540159Y1624292D01*
G01X548610Y65157D02*
Y67371D01*
X549156Y67917D01*
Y77038D01*
X549136Y77058D01*
Y78057D01*
X547821Y79372D01*
G01X550972Y65157D02*
Y67391D01*
X550426Y67937D01*
Y78077D01*
X551721Y79372D01*
G01X555697Y65157D02*
Y67563D01*
X556243Y68109D01*
Y70369D01*
X555176Y71436D01*
G01X558059Y65157D02*
Y67563D01*
X557513Y68109D01*
Y70373D01*
X558576Y71436D01*
G01X551280Y119790D02*
Y118560D01*
X553150Y116690D01*
Y113248D01*
X552105Y112203D01*
G01X556280Y119790D02*
Y118559D01*
X554420Y116699D01*
Y113288D01*
X555505Y112203D01*
G01X551280Y122940D02*
X552080D01*
X553780Y124640D01*
G01X556280Y122940D02*
X555480D01*
X553780Y121240D01*
G01X606091Y760386D02*
Y765524D01*
X603434Y771939D01*
X544870Y830503D01*
Y841585D01*
X551729Y858144D01*
Y873078D01*
X552944Y874293D01*
G01X557720Y871658D02*
Y865791D01*
X573973Y849539D01*
X577661Y840635D01*
Y836209D01*
X576368Y833087D01*
Y829246D01*
X575618Y828496D01*
Y826976D01*
X576368Y826226D01*
Y824706D01*
X575618Y823956D01*
Y822436D01*
X576368Y821686D01*
Y803125D01*
X606319Y773174D01*
X607057Y771392D01*
G01X558990Y871583D02*
Y866318D01*
X575051Y850259D01*
X578931Y840888D01*
Y835956D01*
X577638Y832834D01*
Y803652D01*
X607396Y773894D01*
X613470Y759231D01*
Y759230D01*
G01X554795Y896616D02*
X556633Y895569D01*
G01X547393Y896616D02*
X549231Y895569D01*
G01X545543Y893427D02*
X547381Y892380D01*
G01X558496Y896616D02*
X560334Y895569D01*
G01X552944Y899805D02*
X554783Y898758D01*
G01X558496Y915749D02*
X560334Y914702D01*
G01X554795Y915749D02*
X556633Y914702D01*
G01X552944Y918938D02*
X554783Y917891D01*
G01X547393Y915749D02*
X549231Y914702D01*
G01X545543Y912560D02*
X547381Y911513D01*
G01X558496Y934883D02*
X560334Y933836D01*
G01X554795Y934883D02*
X556633Y933836D01*
G01X552944Y938072D02*
X554783Y937025D01*
G01X547393Y934883D02*
X549231Y933836D01*
G01X545543Y931694D02*
X547381Y930647D01*
G01X558496Y954017D02*
X560334Y952970D01*
G01X554795Y954017D02*
X556633Y952970D01*
G01X547393Y954017D02*
X549231Y952970D01*
G01X545543Y950828D02*
X547381Y949781D01*
G01X552944Y957206D02*
X554783Y956159D01*
G01X545543Y969962D02*
X547381Y968915D01*
G01X558496Y973151D02*
X560334Y972104D01*
G01X554795Y973151D02*
X556633Y972104D01*
G01X552944Y976340D02*
X554783Y975293D01*
G01X547393Y973151D02*
X549231Y972104D01*
G01X554126Y1068466D02*
X555964Y1069513D01*
G01X555976Y1071655D02*
X557814Y1072702D01*
G01X546724Y1068466D02*
X548562Y1069513D01*
G01X548574Y1065277D02*
X550412Y1066324D01*
G01X554126Y1087600D02*
X555964Y1088647D01*
G01X546724Y1087600D02*
X548562Y1088647D01*
G01X548574Y1084411D02*
X550412Y1085458D01*
G01X555976Y1090789D02*
X557814Y1091836D01*
G01X548574Y1103545D02*
X550412Y1104592D01*
G01X554126Y1106734D02*
X555964Y1107781D01*
G01X555976Y1109923D02*
X557814Y1110970D01*
G01X546724Y1106734D02*
X548562Y1107781D01*
G01X554126Y1125868D02*
X555964Y1126915D01*
G01X555976Y1129057D02*
X557814Y1130103D01*
G01X546724Y1125868D02*
X548562Y1126915D01*
G01X548574Y1122679D02*
X550412Y1123726D01*
G01X554126Y1145001D02*
X555964Y1146048D01*
G01X555976Y1148190D02*
X557814Y1149237D01*
G01X546724Y1145001D02*
X548562Y1146048D01*
G01X548574Y1141812D02*
X550412Y1142859D01*
G01X555348Y1483590D02*
X556413Y1482525D01*
X559183D01*
X560348Y1483690D01*
G01X555348Y1480190D02*
X556413Y1481255D01*
X559183D01*
X560348Y1480090D01*
G01X555348Y1501990D02*
X556413Y1503055D01*
X559183D01*
X560348Y1501890D01*
G01X555348Y1505390D02*
X556413Y1504325D01*
X559183D01*
X560348Y1505490D01*
G01X554766Y1523331D02*
X555831Y1524396D01*
X557653D01*
X558618Y1523431D01*
G01X554766Y1526731D02*
X555831Y1525666D01*
X557653D01*
X558618Y1526631D01*
G01X548719Y1607286D02*
X549884Y1606121D01*
Y1593445D01*
X548819Y1592380D01*
G01X552319Y1607286D02*
X551154Y1606121D01*
Y1593445D01*
X552219Y1592380D01*
G01X548719Y1609386D02*
X549884Y1610551D01*
Y1623227D01*
X548819Y1624292D01*
G01X552319Y1609386D02*
X551154Y1610551D01*
Y1623227D01*
X552219Y1624292D01*
G01X568360Y119635D02*
Y117733D01*
X570199Y115894D01*
Y114071D01*
X569449Y113321D01*
Y111801D01*
X570199Y111051D01*
Y109251D01*
X569449Y108501D01*
Y106981D01*
X570199Y106231D01*
Y105227D01*
X569239Y104267D01*
X567525D01*
X566957Y104835D01*
X565427D01*
X564859Y104267D01*
X560187D01*
X559069Y105385D01*
G01X573360Y119635D02*
Y117796D01*
X571469Y115905D01*
Y104700D01*
X569766Y102997D01*
X560069D01*
X559069Y101985D01*
G01X568360Y122785D02*
X569385D01*
X570860Y121310D01*
G01X573360Y122785D02*
X572785D01*
X570860Y124710D01*
G01X581427Y890205D02*
X588095Y883536D01*
Y847320D01*
X620625Y814790D01*
Y810796D01*
X621742Y809679D01*
X622676D01*
X623759Y808596D01*
Y807662D01*
X624840Y806581D01*
X625774D01*
X626857Y805498D01*
Y804564D01*
X640486Y790935D01*
X642928D01*
X643963Y791970D01*
G01X580528Y889306D02*
X586825Y883009D01*
Y846793D01*
X619355Y814263D01*
Y810269D01*
X639959Y789665D01*
X642922D01*
X643963Y788624D01*
G01X560346Y893427D02*
X562184Y892380D01*
G01X579963Y894388D02*
X589815Y884532D01*
Y847948D01*
X627083Y810680D01*
X630305D01*
X630865Y810120D01*
Y809341D01*
X628907Y807383D01*
Y805547D01*
X630206Y804248D01*
X632042D01*
X633999Y806205D01*
X634780D01*
X635340Y805645D01*
Y804866D01*
X633437Y802963D01*
Y801127D01*
X634736Y799828D01*
X636572D01*
X638474Y801730D01*
X639255D01*
X639815Y801170D01*
Y800391D01*
X638141Y798717D01*
Y796943D01*
X640402Y794682D01*
X644118D01*
X645157Y793643D01*
X647354D01*
G01X580862Y895286D02*
X591085Y885058D01*
Y848475D01*
X624512Y815048D01*
X625446D01*
X626529Y813965D01*
Y813031D01*
X627610Y811950D01*
X630832D01*
X632135Y810647D01*
Y808814D01*
X630177Y806856D01*
Y806074D01*
X630733Y805518D01*
X631515D01*
X633472Y807475D01*
X635307D01*
X636610Y806172D01*
Y804339D01*
X634707Y802436D01*
Y801654D01*
X635263Y801098D01*
X636045D01*
X637947Y803000D01*
X639782D01*
X641085Y801697D01*
Y799864D01*
X639411Y798190D01*
Y797470D01*
X640929Y795952D01*
X644122D01*
X645160Y796990D01*
X645161Y796989D01*
X647354D01*
G01X581610Y913989D02*
X582762D01*
X606365Y890386D01*
Y864804D01*
X610840Y860329D01*
Y858001D01*
X611545Y857296D01*
X613873D01*
X615315Y855854D01*
Y853526D01*
X616020Y852821D01*
X618348D01*
X619790Y851379D01*
Y849051D01*
X620495Y848346D01*
X622823D01*
X624489Y846680D01*
Y840216D01*
X636839Y827866D01*
X638668D01*
X639328Y828526D01*
X640858D01*
X641518Y827866D01*
X643048D01*
X643963Y828781D01*
G01X580007Y916459D02*
X582695D01*
X608025Y891129D01*
Y865493D01*
X628047Y845471D01*
Y844687D01*
X626149Y842789D01*
Y840955D01*
X627452Y839652D01*
X629286D01*
X631184Y841550D01*
X631968D01*
X632522Y840996D01*
Y840212D01*
X630624Y838314D01*
Y836480D01*
X631927Y835177D01*
X633761D01*
X635659Y837075D01*
X636443D01*
X636997Y836521D01*
Y835737D01*
X635099Y833839D01*
Y832005D01*
X636402Y830702D01*
X638236D01*
X640134Y832600D01*
X640918D01*
X642025Y831493D01*
X644118D01*
X645157Y830454D01*
X647354D01*
G01X581610Y912719D02*
X582235D01*
X605095Y889859D01*
Y864277D01*
X609570Y859802D01*
Y857474D01*
X611018Y856026D01*
X613346D01*
X614045Y855327D01*
Y852999D01*
X615493Y851551D01*
X617821D01*
X618520Y850852D01*
Y848524D01*
X619968Y847076D01*
X622296D01*
X623219Y846153D01*
Y839689D01*
X636312Y826596D01*
X642802D01*
X643963Y825435D01*
G01X580007Y917729D02*
X583222D01*
X609295Y891656D01*
Y866020D01*
X629317Y845998D01*
Y844160D01*
X627419Y842262D01*
Y841482D01*
X627979Y840922D01*
X628759D01*
X630657Y842820D01*
X632495D01*
X633792Y841523D01*
Y839685D01*
X631894Y837787D01*
Y837007D01*
X632454Y836447D01*
X633234D01*
X635132Y838345D01*
X636970D01*
X638267Y837048D01*
Y835210D01*
X636369Y833312D01*
Y832532D01*
X636929Y831972D01*
X637709D01*
X639607Y833870D01*
X641445D01*
X642552Y832763D01*
X644122D01*
X645160Y833801D01*
X645161Y833800D01*
X647354D01*
G01X560346Y912560D02*
X562184Y911513D01*
G01X580702Y934626D02*
X586757D01*
X623860Y897523D01*
Y882835D01*
X625277Y881418D01*
Y879474D01*
X626244Y878507D01*
X628188D01*
X629752Y876943D01*
Y875299D01*
X631019Y874032D01*
X632663D01*
X634227Y872468D01*
Y870814D01*
X635484Y869557D01*
X637138D01*
X638702Y867993D01*
Y865909D01*
X640054Y864557D01*
X642928D01*
X643963Y865592D01*
G01X580910Y936346D02*
X587402D01*
X625520Y898228D01*
Y883644D01*
X626808Y882356D01*
X628582D01*
X631350Y885124D01*
X632130D01*
X632690Y884564D01*
Y883784D01*
X630054Y881148D01*
Y879310D01*
X631351Y878013D01*
X633189D01*
X635449Y880273D01*
X636229D01*
X636789Y879713D01*
Y878933D01*
X634879Y877023D01*
Y875185D01*
X636176Y873888D01*
X638014D01*
X638962Y874836D01*
X639742D01*
X640302Y874276D01*
Y873496D01*
X639392Y872586D01*
Y870812D01*
X641900Y868304D01*
X644118D01*
X645157Y867265D01*
X647354D01*
G01X580702Y933356D02*
X586230D01*
X622590Y896996D01*
Y882308D01*
X624007Y880891D01*
Y878947D01*
X625717Y877237D01*
X627661D01*
X628482Y876416D01*
Y874772D01*
X630492Y872762D01*
X632136D01*
X632957Y871941D01*
Y870287D01*
X634957Y868287D01*
X636611D01*
X637432Y867466D01*
Y865382D01*
X639527Y863287D01*
X642922D01*
X643963Y862246D01*
G01X580910Y937616D02*
X587929D01*
X626790Y898755D01*
Y884171D01*
X627335Y883626D01*
X628055D01*
X630823Y886394D01*
X632657D01*
X633960Y885091D01*
Y883257D01*
X631324Y880621D01*
Y879837D01*
X631878Y879283D01*
X632662D01*
X634922Y881543D01*
X636756D01*
X638059Y880240D01*
Y878406D01*
X636149Y876496D01*
Y875712D01*
X636703Y875158D01*
X637487D01*
X638435Y876106D01*
X640269D01*
X641572Y874803D01*
Y872969D01*
X640662Y872059D01*
Y871339D01*
X642427Y869574D01*
X644122D01*
X645160Y870612D01*
X645161Y870611D01*
X647354D01*
G01X560346Y931694D02*
X562184Y930647D01*
G01X581200Y954107D02*
X596744D01*
X615751Y935100D01*
X619945D01*
X627665Y927380D01*
Y918180D01*
X641635Y904210D01*
Y901917D01*
X642184Y901368D01*
X642928D01*
X643963Y902403D01*
G01X581398Y956126D02*
X597073D01*
X616439Y936760D01*
X620807D01*
X632814Y924753D01*
Y923973D01*
X629481Y920640D01*
Y918802D01*
X630778Y917505D01*
X632616D01*
X635330Y920219D01*
X636110D01*
X636670Y919659D01*
Y918879D01*
X633956Y916165D01*
Y914327D01*
X643168Y905115D01*
X644118D01*
X645157Y904076D01*
X647354D01*
G01X581200Y952837D02*
X596217D01*
X615224Y933830D01*
X619418D01*
X626395Y926853D01*
Y917653D01*
X640365Y903683D01*
Y901390D01*
X641657Y900098D01*
X642922D01*
X643963Y899057D01*
G01X560346Y950828D02*
X562184Y949781D01*
G01X580390Y970669D02*
X614181D01*
X622859Y961991D01*
Y955455D01*
X641405Y936909D01*
X642922D01*
X643963Y935868D01*
G01X581398Y957396D02*
X597600D01*
X616966Y938030D01*
X621334D01*
X634084Y925280D01*
Y923446D01*
X630751Y920113D01*
Y919329D01*
X631305Y918775D01*
X632089D01*
X634803Y921489D01*
X636637D01*
X637940Y920186D01*
Y918352D01*
X635226Y915638D01*
Y914854D01*
X643695Y906385D01*
X644122D01*
X645160Y907423D01*
X647354D01*
G01X560346Y969962D02*
X562184Y968915D01*
G01X580390Y971939D02*
X614708D01*
X624129Y962518D01*
Y955982D01*
X641932Y938179D01*
X642928D01*
X643963Y939214D01*
G01X580377Y973701D02*
X615295D01*
X626860Y962136D01*
Y959650D01*
X625789Y958579D01*
Y956745D01*
X627092Y955442D01*
X628926D01*
X629997Y956513D01*
X630781D01*
X631335Y955959D01*
Y955175D01*
X630264Y954104D01*
Y952270D01*
X631567Y950967D01*
X633401D01*
X634472Y952038D01*
X635256D01*
X635810Y951484D01*
Y950700D01*
X634739Y949629D01*
Y947795D01*
X636042Y946492D01*
X637876D01*
X638947Y947563D01*
X639731D01*
X640495Y946799D01*
Y943479D01*
X642048Y941926D01*
X644118D01*
X645157Y940887D01*
X647354D01*
G01X580377Y974971D02*
X615822D01*
X628130Y962663D01*
Y959123D01*
X627059Y958052D01*
Y957272D01*
X627619Y956712D01*
X628399D01*
X629470Y957783D01*
X631308D01*
X632605Y956486D01*
Y954648D01*
X631534Y953577D01*
Y952797D01*
X632094Y952237D01*
X632874D01*
X633945Y953308D01*
X635783D01*
X637080Y952011D01*
Y950173D01*
X636009Y949102D01*
Y948322D01*
X636569Y947762D01*
X637349D01*
X638420Y948833D01*
X640258D01*
X641765Y947326D01*
Y944006D01*
X642575Y943196D01*
X644122D01*
X645160Y944234D01*
X647354D01*
G01X582359Y1068477D02*
X620577D01*
X621548Y1069448D01*
X622332D01*
X623303Y1068477D01*
X625137D01*
X626440Y1069780D01*
Y1071614D01*
X624787Y1073267D01*
Y1074051D01*
X625341Y1074605D01*
X626125D01*
X628197Y1072533D01*
X630031D01*
X631334Y1073836D01*
Y1075670D01*
X629230Y1077774D01*
Y1078494D01*
X630374Y1079638D01*
X632694D01*
X634146Y1081090D01*
Y1083410D01*
X634849Y1084113D01*
X637169D01*
X638621Y1085565D01*
Y1087885D01*
X639906Y1089170D01*
X644118D01*
X645157Y1088131D01*
X647354D01*
G01X580978Y1066817D02*
X628106D01*
X632994Y1071705D01*
Y1077417D01*
X641000Y1085423D01*
X642928D01*
X643963Y1086458D01*
G01X582359Y1069747D02*
X620050D01*
X621021Y1070718D01*
X622859D01*
X623830Y1069747D01*
X624610D01*
X625170Y1070307D01*
Y1071087D01*
X623517Y1072740D01*
Y1074578D01*
X624814Y1075875D01*
X626652D01*
X628724Y1073803D01*
X629504D01*
X630064Y1074363D01*
Y1075143D01*
X627960Y1077247D01*
Y1079021D01*
X629847Y1080908D01*
X632167D01*
X632876Y1081617D01*
Y1083937D01*
X634322Y1085383D01*
X636642D01*
X637351Y1086092D01*
Y1088412D01*
X639379Y1090440D01*
X644122D01*
X645160Y1091478D01*
X647354D01*
G01X561527Y1068466D02*
X563365Y1069513D01*
G01X559677Y1065277D02*
X561515Y1066324D01*
G01X582359Y1086549D02*
X609290D01*
X635066Y1112325D01*
Y1113107D01*
X634098Y1114076D01*
Y1115910D01*
X635402Y1117214D01*
X637234Y1117213D01*
X638203Y1116244D01*
X638985D01*
X640215Y1117474D01*
Y1120981D01*
X641468Y1122234D01*
X642928D01*
X643963Y1123269D01*
G01X582359Y1088244D02*
X608518D01*
X618496Y1098222D01*
Y1099998D01*
X617467Y1101027D01*
Y1101810D01*
X618023Y1102366D01*
X618805D01*
X619806Y1101366D01*
X621640D01*
X622944Y1102670D01*
X622943Y1104502D01*
X621942Y1105503D01*
Y1106285D01*
X622498Y1106841D01*
X623280D01*
X624281Y1105841D01*
X626115D01*
X627419Y1107145D01*
X627418Y1108977D01*
X626417Y1109978D01*
Y1110760D01*
X626973Y1111316D01*
X627755D01*
X628756Y1110316D01*
X630590D01*
X631894Y1111620D01*
X631893Y1113452D01*
X630892Y1114453D01*
Y1115235D01*
X641638Y1125981D01*
X644118D01*
X645157Y1124942D01*
X647354D01*
G01X582359Y1089514D02*
X607991D01*
X617226Y1098749D01*
Y1099471D01*
X616197Y1100500D01*
Y1102337D01*
X617496Y1103636D01*
X619331D01*
X620332Y1102636D01*
X621113D01*
X621673Y1103196D01*
X621672Y1103975D01*
X620672Y1104976D01*
Y1106812D01*
X621971Y1108111D01*
X623806D01*
X624807Y1107111D01*
X625588D01*
X626148Y1107671D01*
X626147Y1108450D01*
X625147Y1109451D01*
Y1111287D01*
X626446Y1112586D01*
X628281D01*
X629282Y1111586D01*
X630063D01*
X630623Y1112146D01*
X630622Y1112925D01*
X629622Y1113926D01*
Y1115762D01*
X641111Y1127251D01*
X644122D01*
X645160Y1128289D01*
X647354D01*
G01X561527Y1087600D02*
X563365Y1088647D01*
G01X559677Y1084411D02*
X561515Y1085458D01*
G01X559677Y1103545D02*
X561515Y1104592D01*
G01X582359Y1104512D02*
X593491D01*
X631338Y1142359D01*
Y1143319D01*
X629110Y1145547D01*
Y1147385D01*
X630407Y1148682D01*
X632245D01*
X634473Y1146454D01*
X635253D01*
X635813Y1147014D01*
Y1147794D01*
X633585Y1150022D01*
Y1151860D01*
X640770Y1159045D01*
X642928D01*
X643963Y1160080D01*
G01X582359Y1106657D02*
X593288D01*
X627450Y1140819D01*
Y1148073D01*
X628690Y1149313D01*
Y1151151D01*
X627087Y1152754D01*
Y1153534D01*
X627647Y1154094D01*
X628427D01*
X630030Y1152491D01*
X631868D01*
X633165Y1153788D01*
Y1155626D01*
X631562Y1157229D01*
Y1158009D01*
X632122Y1158569D01*
X632902D01*
X634505Y1156966D01*
X636343D01*
X637640Y1158263D01*
Y1160101D01*
X636037Y1161704D01*
Y1162484D01*
X636597Y1163044D01*
X637377D01*
X638980Y1161441D01*
X640818D01*
X642169Y1162792D01*
X644118D01*
X645157Y1161753D01*
X647354D01*
G01X582359Y1107927D02*
X592761D01*
X626180Y1141346D01*
Y1148600D01*
X627420Y1149840D01*
Y1150624D01*
X625817Y1152227D01*
Y1154061D01*
X627120Y1155364D01*
X628954D01*
X630557Y1153761D01*
X631341D01*
X631895Y1154315D01*
Y1155099D01*
X630292Y1156702D01*
Y1158536D01*
X631595Y1159839D01*
X633429D01*
X635032Y1158236D01*
X635816D01*
X636370Y1158790D01*
Y1159574D01*
X634767Y1161177D01*
Y1163011D01*
X636070Y1164314D01*
X637904D01*
X639507Y1162711D01*
X640291D01*
X641642Y1164062D01*
X644122D01*
X645160Y1165100D01*
X647354D01*
G01X561527Y1106734D02*
X563365Y1107781D01*
G01X582359Y1124719D02*
X588738D01*
X606036Y1142017D01*
Y1159661D01*
X632932Y1186557D01*
Y1187293D01*
X632167Y1188058D01*
Y1189896D01*
X633464Y1191193D01*
X635302D01*
X636067Y1190428D01*
X636847D01*
X637407Y1190988D01*
Y1191768D01*
X636642Y1192533D01*
Y1194371D01*
X638127Y1195856D01*
X642928D01*
X643963Y1196891D01*
G01X582359Y1126406D02*
X588030D01*
X604376Y1142752D01*
Y1164453D01*
X607206Y1167283D01*
X607990D01*
X608592Y1166681D01*
X610426Y1166682D01*
X611730Y1167986D01*
X611729Y1169818D01*
X611126Y1170421D01*
Y1171203D01*
X611681Y1171758D01*
X612465D01*
X613067Y1171156D01*
X614901Y1171157D01*
X616205Y1172461D01*
X616204Y1174293D01*
X615601Y1174896D01*
Y1175678D01*
X616156Y1176233D01*
X616940D01*
X617542Y1175631D01*
X619376Y1175632D01*
X620680Y1176936D01*
X620679Y1178768D01*
X620076Y1179371D01*
Y1180153D01*
X620631Y1180708D01*
X621415D01*
X622017Y1180106D01*
X623851Y1180107D01*
X625155Y1181411D01*
X625154Y1183243D01*
X624551Y1183846D01*
Y1184628D01*
X625106Y1185183D01*
X625890D01*
X626492Y1184581D01*
X628326Y1184582D01*
X629630Y1185886D01*
X629629Y1187718D01*
X629026Y1188321D01*
Y1189103D01*
X639526Y1199603D01*
X644118D01*
X645157Y1198564D01*
X647354D01*
G01X582359Y1127676D02*
X587503D01*
X603106Y1143279D01*
Y1164980D01*
X606679Y1168553D01*
X608517D01*
X609118Y1167952D01*
X609899Y1167953D01*
X610459Y1168512D01*
X610458Y1169291D01*
X609856Y1169894D01*
Y1171730D01*
X611154Y1173028D01*
X612992D01*
X613593Y1172427D01*
X614374Y1172428D01*
X614934Y1172987D01*
X614933Y1173766D01*
X614331Y1174369D01*
Y1176205D01*
X615629Y1177503D01*
X617467D01*
X618068Y1176902D01*
X618849Y1176903D01*
X619409Y1177462D01*
X619408Y1178241D01*
X618806Y1178844D01*
Y1180680D01*
X620104Y1181978D01*
X621942D01*
X622543Y1181377D01*
X623324Y1181378D01*
X623884Y1181937D01*
X623883Y1182716D01*
X623281Y1183319D01*
Y1185155D01*
X624579Y1186453D01*
X626417D01*
X627018Y1185852D01*
X627799Y1185853D01*
X628359Y1186412D01*
X628358Y1187191D01*
X627756Y1187794D01*
Y1189630D01*
X638999Y1200873D01*
X644122D01*
X645160Y1201911D01*
X647354D01*
G01X561527Y1125868D02*
X563365Y1126915D01*
G01X559677Y1122679D02*
X561515Y1123726D01*
G01X581871Y1144519D02*
X583578D01*
X588745Y1149686D01*
Y1175958D01*
X635856Y1223069D01*
Y1223848D01*
X634788Y1224916D01*
Y1226752D01*
X636087Y1228051D01*
X637922D01*
X638990Y1226984D01*
X639771D01*
X640331Y1227544D01*
Y1228323D01*
X639263Y1229391D01*
Y1231227D01*
X640703Y1232667D01*
X642928D01*
X643963Y1233702D01*
G01X581670Y1146210D02*
X582915D01*
X587055Y1150350D01*
Y1176691D01*
X619630Y1209266D01*
Y1211043D01*
X618571Y1212102D01*
Y1212884D01*
X619127Y1213440D01*
X619909D01*
X620940Y1212410D01*
X622774D01*
X624078Y1213714D01*
X624077Y1215546D01*
X623046Y1216577D01*
Y1217359D01*
X623602Y1217915D01*
X624384D01*
X625415Y1216885D01*
X627249D01*
X628553Y1218189D01*
X628552Y1220021D01*
X627521Y1221052D01*
Y1221834D01*
X628077Y1222390D01*
X628859D01*
X629890Y1221360D01*
X631724D01*
X633028Y1222664D01*
X633027Y1224496D01*
X631996Y1225527D01*
Y1226309D01*
X642101Y1236414D01*
X644118D01*
X645157Y1235375D01*
X647354D01*
G01X581670Y1147480D02*
X582388D01*
X585785Y1150877D01*
Y1177218D01*
X618360Y1209793D01*
Y1210516D01*
X617301Y1211575D01*
Y1213411D01*
X618600Y1214710D01*
X620435D01*
X621466Y1213680D01*
X622247D01*
X622807Y1214240D01*
X622806Y1215019D01*
X621776Y1216050D01*
Y1217886D01*
X623075Y1219185D01*
X624910D01*
X625941Y1218155D01*
X626722D01*
X627282Y1218715D01*
X627281Y1219494D01*
X626251Y1220525D01*
Y1222361D01*
X627550Y1223660D01*
X629385D01*
X630416Y1222630D01*
X631197D01*
X631757Y1223190D01*
X631756Y1223969D01*
X630726Y1225000D01*
Y1226836D01*
X641574Y1237684D01*
X644122D01*
X645160Y1238722D01*
X647354D01*
G01X561527Y1145001D02*
X563365Y1146048D01*
G01X559677Y1141812D02*
X561515Y1142859D01*
G01X571686Y1452895D02*
X570621Y1453960D01*
Y1456730D01*
X571786Y1457895D01*
G01X568286Y1452895D02*
X569351Y1453960D01*
Y1456730D01*
X568186Y1457895D01*
G01X564986Y1462595D02*
X563921Y1463660D01*
Y1466430D01*
X565086Y1467595D01*
G01X561586Y1462595D02*
X562651Y1463660D01*
Y1466430D01*
X561486Y1467595D01*
G01X560718Y1523431D02*
X561680Y1524393D01*
X562706D01*
X563668Y1523431D01*
G01D02*
X564585Y1524348D01*
X566653D01*
X567870Y1525565D01*
X570204D01*
G01X560718Y1526631D02*
X561686Y1525663D01*
X562700D01*
X563668Y1526631D01*
G01D02*
X564681Y1525618D01*
X566126D01*
X567343Y1526835D01*
X570279D01*
G01X572839Y1607286D02*
X574004Y1606121D01*
Y1593445D01*
X572939Y1592380D01*
G01X560779Y1607286D02*
X561944Y1606121D01*
Y1593445D01*
X560879Y1592380D01*
G01X564379Y1607286D02*
X563214Y1606121D01*
Y1593445D01*
X564279Y1592380D01*
G01X572839Y1609386D02*
X574004Y1610551D01*
Y1623227D01*
X572939Y1624292D01*
G01X560779Y1609386D02*
X561944Y1610551D01*
Y1623227D01*
X560879Y1624292D01*
G01X564379Y1609386D02*
X563214Y1610551D01*
Y1623227D01*
X564279Y1624292D01*
G01X583125Y751790D02*
X581760Y750425D01*
Y640440D01*
X627136Y595064D01*
Y588038D01*
X630716Y584458D01*
X640716D01*
X646999Y578175D01*
Y572484D01*
X648314Y571169D01*
G01X579125Y751790D02*
X580490Y750425D01*
Y639913D01*
X625866Y594537D01*
Y587511D01*
X630189Y583188D01*
X640189D01*
X645729Y577648D01*
Y572484D01*
X644414Y571169D01*
G01X634794Y590504D02*
X636109Y591819D01*
Y596169D01*
X588886Y643392D01*
Y750493D01*
X587521Y751858D01*
G01X588886Y769200D02*
Y756373D01*
X587521Y755008D01*
G01X581760Y759700D02*
Y756305D01*
X583125Y754940D01*
G01X580490Y769100D02*
Y756305D01*
X579125Y754940D01*
G01X580978Y1065547D02*
X628633D01*
X634264Y1071178D01*
Y1076890D01*
X641527Y1084153D01*
X642922D01*
X643963Y1083112D01*
G01X582359Y1085279D02*
X609817D01*
X636336Y1111798D01*
Y1113633D01*
X635368Y1114602D01*
Y1115383D01*
X635928Y1115943D01*
X636707Y1115942D01*
X637676Y1114974D01*
X639512D01*
X641485Y1116947D01*
Y1120454D01*
X641995Y1120964D01*
X642922D01*
X643963Y1119923D01*
G01X582359Y1103242D02*
X594018D01*
X632608Y1141832D01*
Y1143846D01*
X630380Y1146074D01*
Y1146858D01*
X630934Y1147412D01*
X631718D01*
X633946Y1145184D01*
X635780D01*
X637083Y1146487D01*
Y1148321D01*
X634855Y1150549D01*
Y1151333D01*
X641297Y1157775D01*
X642922D01*
X643963Y1156734D01*
G01X582359Y1123449D02*
X589265D01*
X607306Y1141490D01*
Y1159134D01*
X634202Y1186030D01*
Y1187820D01*
X633437Y1188585D01*
Y1189369D01*
X633991Y1189923D01*
X634775D01*
X635540Y1189158D01*
X637374D01*
X638677Y1190461D01*
Y1192295D01*
X637912Y1193060D01*
Y1193844D01*
X638654Y1194586D01*
X642922D01*
X643963Y1193545D01*
G01X581871Y1143249D02*
X584105D01*
X590015Y1149159D01*
Y1175431D01*
X637126Y1222542D01*
Y1224375D01*
X636058Y1225443D01*
Y1226225D01*
X636614Y1226781D01*
X637396D01*
X638464Y1225714D01*
X640298D01*
X641601Y1227017D01*
Y1228850D01*
X640533Y1229918D01*
Y1230700D01*
X641230Y1231397D01*
X642922D01*
X643963Y1230356D01*
G01X585086Y1472295D02*
X584021Y1473360D01*
Y1476130D01*
X585186Y1477295D01*
G01X581686Y1472295D02*
X582751Y1473360D01*
Y1476130D01*
X581586Y1477295D01*
G01X588386Y1462595D02*
X589451Y1463660D01*
Y1466430D01*
X588286Y1467595D01*
G01X584899Y1607286D02*
X586064Y1606121D01*
Y1593445D01*
X584999Y1592380D01*
G01X576439Y1607286D02*
X575274Y1606121D01*
Y1593445D01*
X576339Y1592380D01*
G01X588499Y1607286D02*
X587334Y1606121D01*
Y1593445D01*
X588399Y1592380D01*
G01X584899Y1609386D02*
X586064Y1610551D01*
Y1623227D01*
X584999Y1624292D01*
G01X576439Y1609386D02*
X575274Y1610551D01*
Y1623227D01*
X576339Y1624292D01*
G01X588499Y1609386D02*
X587334Y1610551D01*
Y1623227D01*
X588399Y1624292D01*
G01X638694Y590504D02*
X637379Y591819D01*
Y596696D01*
X590156Y643919D01*
Y750493D01*
X591521Y751858D01*
G01X650258Y590316D02*
X648943Y591631D01*
Y596402D01*
X598124Y647221D01*
Y750425D01*
X599489Y751790D01*
G01X646358Y590316D02*
X647673Y591631D01*
Y595875D01*
X596854Y646694D01*
Y750425D01*
X595489Y751790D01*
G01X603456Y751804D02*
X604821Y750439D01*
Y696458D01*
X633777Y667502D01*
X659241D01*
X678752Y659420D01*
X714118Y624054D01*
X728476D01*
X763781Y638675D01*
X837729Y712628D01*
X847687Y736668D01*
Y816677D01*
X846968Y817396D01*
Y1254738D01*
X829174Y1272532D01*
Y1323187D01*
G01X603456Y754954D02*
X604821Y756319D01*
Y765271D01*
X602357Y771219D01*
X600647Y772929D01*
G01X590156Y759400D02*
Y756373D01*
X591521Y755008D01*
G01X598124Y759500D02*
Y756305D01*
X599489Y754940D01*
G01X596854Y765500D02*
Y756305D01*
X595489Y754940D01*
G01X598486Y1452895D02*
X597421Y1453960D01*
Y1456730D01*
X598586Y1457895D01*
G01X595086Y1452895D02*
X596151Y1453960D01*
Y1456730D01*
X594986Y1457895D01*
G01X591786Y1462595D02*
X590721Y1463660D01*
Y1466430D01*
X591886Y1467595D01*
G01X596959Y1607286D02*
X598124Y1606121D01*
Y1593445D01*
X597059Y1592380D01*
G01X600559Y1607286D02*
X599394Y1606121D01*
Y1593445D01*
X600459Y1592380D01*
G01X596959Y1609386D02*
X598124Y1610551D01*
Y1623227D01*
X597059Y1624292D01*
G01X600559Y1609386D02*
X599394Y1610551D01*
Y1623227D01*
X600459Y1624292D01*
G01X607456Y751804D02*
X606091Y750439D01*
Y696985D01*
X610629Y692447D01*
X611689D01*
X612765Y691371D01*
Y690311D01*
X613839Y689237D01*
X614900D01*
X615976Y688161D01*
Y687100D01*
X617050Y686026D01*
X618111D01*
X619187Y684950D01*
Y683889D01*
X634304Y668772D01*
X659494D01*
X679472Y660497D01*
X714645Y625324D01*
X728223D01*
X763061Y639753D01*
X828878Y705576D01*
Y706637D01*
X829961Y707720D01*
X831022D01*
X832103Y708801D01*
Y709861D01*
X833186Y710944D01*
X834248D01*
X836652Y713348D01*
X846417Y736921D01*
Y802056D01*
X845667Y802806D01*
Y804336D01*
X846417Y805086D01*
Y806616D01*
X845667Y807366D01*
Y808896D01*
X846417Y809646D01*
Y816150D01*
X845698Y816869D01*
Y1254211D01*
X827904Y1272005D01*
Y1312682D01*
G01X638967Y671774D02*
X637902Y672839D01*
Y678748D01*
X614078Y702572D01*
Y750451D01*
X615443Y751816D01*
G01X635567Y671774D02*
X636632Y672839D01*
Y678221D01*
X612808Y702045D01*
Y750451D01*
X611443Y751816D01*
G01X607456Y754954D02*
X606091Y756319D01*
Y760386D01*
G01X613470Y759230D02*
X614078Y757763D01*
Y756331D01*
X615443Y754966D01*
G01X607057Y771392D02*
X612808Y757510D01*
Y756331D01*
X611443Y754966D01*
G01X611886Y1472295D02*
X610821Y1473360D01*
Y1476130D01*
X611986Y1477295D01*
G01X618586Y1462595D02*
X617521Y1463660D01*
Y1466430D01*
X618686Y1467595D01*
G01X608486Y1472295D02*
X609551Y1473360D01*
Y1476130D01*
X608386Y1477295D01*
G01X615186Y1462595D02*
X616251Y1463660D01*
Y1466430D01*
X615086Y1467595D01*
G01X609019Y1607286D02*
X610184Y1606121D01*
Y1593445D01*
X609119Y1592380D01*
G01X612619Y1607286D02*
X611454Y1606121D01*
Y1593445D01*
X612519Y1592380D01*
G01X609019Y1609386D02*
X610184Y1610551D01*
Y1623227D01*
X609119Y1624292D01*
G01X612619Y1609386D02*
X611454Y1610551D01*
Y1623227D01*
X612519Y1624292D01*
G01X664043Y53543D02*
Y51258D01*
X664586Y50715D01*
Y48937D01*
X660970Y40207D01*
X657503Y36740D01*
X652412Y34631D01*
X644574D01*
X640862Y36169D01*
X633434Y43597D01*
X632227Y46507D01*
Y48713D01*
X632977Y49463D01*
Y50983D01*
X632227Y51733D01*
Y54219D01*
X632977Y54969D01*
Y56489D01*
X632227Y57239D01*
Y58759D01*
X632977Y59509D01*
Y61029D01*
X632227Y61779D01*
Y63299D01*
X632977Y64049D01*
Y65569D01*
X632227Y66319D01*
Y67839D01*
X632977Y68589D01*
Y70109D01*
X632227Y70859D01*
Y72379D01*
X632977Y73129D01*
Y74649D01*
X632227Y75399D01*
Y76895D01*
X633293Y77961D01*
G01X666406Y53543D02*
Y51257D01*
X665856Y50707D01*
Y48684D01*
X662047Y39487D01*
X658223Y35663D01*
X652665Y33361D01*
X644321D01*
X640142Y35092D01*
X632357Y42877D01*
X630957Y46254D01*
Y77151D01*
X630147Y77961D01*
G01X860587Y342210D02*
X859522Y341145D01*
Y338300D01*
X858560Y336453D01*
X854600Y331938D01*
X844385Y324787D01*
X840524Y324106D01*
X811626Y323560D01*
X811602D01*
X782603Y323012D01*
X768513Y320527D01*
X753899Y310296D01*
X751244Y306504D01*
X747561Y294821D01*
Y263752D01*
X749784Y257453D01*
X750180Y247139D01*
X746865Y234806D01*
X740973Y226391D01*
X731659Y206417D01*
X730195Y189683D01*
X726472Y168566D01*
X719453Y155082D01*
X707714Y143343D01*
X701036Y138881D01*
X683190D01*
X662191Y132258D01*
X657155Y128565D01*
X634348Y95996D01*
X632355Y84681D01*
Y80999D01*
X633293Y80061D01*
G01X857187Y342210D02*
X858252Y341145D01*
Y338611D01*
X857503Y337176D01*
X853746Y332891D01*
X843887Y325989D01*
X840401Y325374D01*
X826001Y325102D01*
X811602Y324830D01*
X811578D01*
X804379Y324695D01*
Y324694D01*
X782480Y324280D01*
X768015Y321729D01*
X752987Y311208D01*
X750091Y307073D01*
X746291Y295017D01*
Y263534D01*
X748522Y257212D01*
X748903Y247283D01*
X745696Y235352D01*
X739868Y227029D01*
X730413Y206751D01*
X728934Y189849D01*
X725255Y168979D01*
X718416Y155842D01*
X706904Y144330D01*
X700650Y140151D01*
X682994D01*
X661609Y133407D01*
X656234Y129466D01*
X633146Y96494D01*
X631085Y84792D01*
Y80999D01*
X630147Y80061D01*
G01X628988Y1415094D02*
X639586Y1425692D01*
X652934D01*
X653999Y1426757D01*
G01X625286Y1452895D02*
X624221Y1453960D01*
Y1456730D01*
X625386Y1457895D01*
G01X621886Y1452895D02*
X622951Y1453960D01*
Y1456730D01*
X621786Y1457895D01*
G01X621079Y1607286D02*
X622244Y1606121D01*
Y1593445D01*
X621179Y1592380D01*
G01X633139Y1607286D02*
X634304Y1606121D01*
Y1593445D01*
X633239Y1592380D01*
G01X624679Y1607286D02*
X623514Y1606121D01*
Y1593445D01*
X624579Y1592380D01*
G01X621079Y1609386D02*
X622244Y1610551D01*
Y1623227D01*
X621179Y1624292D01*
G01X633139Y1609386D02*
X634304Y1610551D01*
Y1623227D01*
X633239Y1624292D01*
G01X624679Y1609386D02*
X623514Y1610551D01*
Y1623227D01*
X624579Y1624292D01*
G01X656957Y53543D02*
Y51282D01*
X657503Y50736D01*
Y44138D01*
X657025Y42983D01*
X654104Y40062D01*
X651424Y38953D01*
X644912D01*
X643415Y39573D01*
X638412Y44576D01*
X637428Y46952D01*
Y58888D01*
X638168Y59628D01*
Y61148D01*
X637428Y61888D01*
Y69332D01*
X638168Y70072D01*
Y71592D01*
X637428Y72332D01*
Y73852D01*
X638168Y74592D01*
Y76112D01*
X637428Y76852D01*
Y78372D01*
X638168Y79112D01*
Y80632D01*
X637428Y81372D01*
Y83146D01*
X638071Y86794D01*
X638070Y86795D01*
X638929Y87395D01*
X639192Y88893D01*
X638592Y89751D01*
X638855Y91247D01*
X639713Y91847D01*
X639977Y93345D01*
X639377Y94203D01*
X639640Y95699D01*
X640846Y97423D01*
X641877Y97605D01*
X642749Y98851D01*
X642567Y99882D01*
X661045Y126293D01*
X661507Y126680D01*
X683618Y134728D01*
X702334D01*
X710289Y140043D01*
X722671Y152425D01*
X730381Y167236D01*
X734278Y189335D01*
X735641Y204911D01*
X744405Y223705D01*
X750638Y232606D01*
X754472Y245082D01*
X754120Y259352D01*
X751699Y266031D01*
Y294066D01*
X754844Y304041D01*
X757165Y307353D01*
X770442Y316649D01*
X783005Y318865D01*
X841517Y319970D01*
X851891Y320877D01*
X860763Y324553D01*
X862776Y326566D01*
X863277Y327775D01*
Y329793D01*
X864342Y330858D01*
G01X659319Y53543D02*
Y51282D01*
X658773Y50736D01*
Y43885D01*
X658103Y42263D01*
X654824Y38984D01*
X651677Y37683D01*
X644659D01*
X642694Y38497D01*
X637334Y43856D01*
X636158Y46699D01*
Y83257D01*
X638437Y96197D01*
X660100Y127159D01*
X660863Y127798D01*
X683394Y135998D01*
X701948D01*
X709479Y141030D01*
X721634Y153185D01*
X729164Y167649D01*
X733017Y189501D01*
X734375Y205016D01*
X734395Y205245D01*
X743300Y224343D01*
X749483Y233171D01*
X753197Y245257D01*
X752855Y259114D01*
X750429Y265807D01*
Y294262D01*
X753691Y304610D01*
X756253Y308265D01*
X769944Y317851D01*
X782882Y320133D01*
X841450Y321239D01*
X851585Y322126D01*
X860043Y325630D01*
X861699Y327286D01*
X862007Y328028D01*
Y329793D01*
X860942Y330858D01*
G01X637447Y1421755D02*
X637446D01*
X640113Y1424422D01*
X652934D01*
X653999Y1423357D01*
G01X638686Y1472295D02*
X637621Y1473360D01*
Y1476130D01*
X638786Y1477295D01*
G01X645386Y1462595D02*
X644321Y1463660D01*
Y1466430D01*
X645486Y1467595D01*
G01X635286Y1472295D02*
X636351Y1473360D01*
Y1476130D01*
X635186Y1477295D01*
G01X641986Y1462595D02*
X643051Y1463660D01*
Y1466430D01*
X641886Y1467595D01*
G01X636739Y1607286D02*
X635574Y1606121D01*
Y1593445D01*
X636639Y1592380D01*
G01X636739Y1609386D02*
X635574Y1610551D01*
Y1623227D01*
X636639Y1624292D01*
G01X652086Y1452895D02*
X651021Y1453960D01*
Y1456730D01*
X652186Y1457895D01*
G01X648686Y1452895D02*
X649751Y1453960D01*
Y1456730D01*
X648586Y1457895D01*
G01X662086Y1452895D02*
X663151Y1453960D01*
Y1456730D01*
X661986Y1457895D01*
G01X671130Y53543D02*
Y51246D01*
X671676Y50700D01*
Y43527D01*
X670613Y42464D01*
G01X673492Y53543D02*
Y51434D01*
X672946Y50888D01*
Y43531D01*
X674013Y42464D01*
G01X665486Y1452895D02*
X664421Y1453960D01*
Y1456730D01*
X665586Y1457895D01*
G01X672856Y1484082D02*
X671791Y1483017D01*
X669021D01*
X667856Y1484182D01*
G01X672856Y1480682D02*
X671791Y1481747D01*
X669021D01*
X667856Y1480582D01*
G01X672856Y1497482D02*
X671791Y1496417D01*
X669021D01*
X667856Y1497582D01*
G01X672856Y1494082D02*
X671791Y1495147D01*
X669021D01*
X667856Y1493982D01*
G01X691276Y1455112D02*
X692341Y1456177D01*
Y1458690D01*
X695700Y1462049D01*
X725165D01*
X728192Y1465076D01*
X760078D01*
X762656Y1467654D01*
X818885D01*
G01X697277Y180315D02*
X699987D01*
X700336Y180664D01*
X703706D01*
X704771Y179599D01*
G01X697277Y176378D02*
X699950D01*
X700300Y176028D01*
X708533D01*
X709692Y177187D01*
G01X697277Y174409D02*
X699979D01*
X700328Y174758D01*
X708521D01*
X709692Y173587D01*
G01X697277Y170472D02*
X699947D01*
X700296Y170123D01*
X703706D01*
X704771Y171188D01*
G01X697277Y168504D02*
X699987D01*
X700336Y168853D01*
X703706D01*
X704771Y167788D01*
G01X697277Y182283D02*
X699947D01*
X700296Y181934D01*
X703706D01*
X704771Y182999D01*
G01X697277Y194094D02*
X699947D01*
X700296Y193745D01*
X703706D01*
X704771Y194810D01*
G01X697277Y192126D02*
X699987D01*
X700336Y192475D01*
X703706D01*
X704771Y191410D01*
G01X697277Y188189D02*
X699950D01*
X700300Y187839D01*
X708344D01*
X709692Y189187D01*
G01X697277Y186220D02*
X699979D01*
X700328Y186569D01*
X708710D01*
X709692Y185587D01*
G01X697277Y205905D02*
X699947D01*
X700296Y205556D01*
X703706D01*
X704771Y206621D01*
G01X697277Y203937D02*
X699987D01*
X700336Y204286D01*
X703706D01*
X704771Y203221D01*
G01X697277Y200000D02*
X699950D01*
X700300Y199650D01*
X708655D01*
X709692Y200687D01*
G01X697277Y198031D02*
X699979D01*
X700328Y198380D01*
X708422D01*
X709692Y197110D01*
Y197087D01*
G01Y208921D02*
X708422Y210191D01*
X700328D01*
X699979Y209842D01*
X697277D01*
G01Y217716D02*
X699947D01*
X700296Y217367D01*
X703706D01*
X704771Y218432D01*
G01X697277Y215748D02*
X699987D01*
X700336Y216097D01*
X703706D01*
X704771Y215032D01*
G01X709692Y212521D02*
X708632Y211461D01*
X700300D01*
X699950Y211811D01*
X697277D01*
G01X694676Y1455112D02*
X693611Y1456177D01*
Y1458163D01*
X696227Y1460779D01*
X725692D01*
X728719Y1463806D01*
X760605D01*
X763183Y1466384D01*
X829390D01*
G01X711792Y177187D02*
X712981Y175998D01*
X715610D01*
X716699Y177087D01*
G01X711792Y173587D02*
X712933Y174728D01*
X715658D01*
X716699Y173687D01*
G01X711792Y189187D02*
X712981Y187998D01*
X715610D01*
X716699Y189087D01*
G01X711792Y185587D02*
X712933Y186728D01*
X715658D01*
X716699Y185687D01*
G01X711792Y200687D02*
X712981Y199498D01*
X715610D01*
X716699Y200587D01*
G01X711792Y197087D02*
X712933Y198228D01*
X715658D01*
X716699Y197187D01*
G01X711792Y208921D02*
X712933Y210062D01*
X715658D01*
X716699Y209021D01*
G01X711792Y212521D02*
X712981Y211332D01*
X715610D01*
X716699Y212421D01*
G01X728493Y-24855D02*
X725925Y-25571D01*
G01X728493Y-22887D02*
X725925Y-22171D01*
G01X827904Y1312682D02*
Y1362503D01*
X827154Y1363253D01*
Y1364783D01*
X827904Y1365533D01*
Y1367063D01*
X827154Y1367813D01*
Y1369343D01*
X827904Y1370093D01*
Y1371623D01*
X827154Y1372373D01*
Y1373903D01*
X827904Y1374653D01*
Y1376183D01*
X826823Y1377264D01*
X825762D01*
X824679Y1378347D01*
Y1379408D01*
X818932Y1385155D01*
X815406D01*
X814296Y1384045D01*
G01X829174Y1323187D02*
Y1376710D01*
X819459Y1386425D01*
X815316D01*
X814296Y1387445D01*
G01X1442532Y1278335D02*
X1441167Y1279700D01*
Y1280825D01*
X1451251Y1290909D01*
Y1391307D01*
X1371709Y1470849D01*
X1173682D01*
X1166278Y1478253D01*
X1114602D01*
X1097781Y1461432D01*
X994628D01*
X977204Y1444008D01*
X920436D01*
X918805Y1445639D01*
X906003D01*
X890693Y1460949D01*
X869854D01*
X863149Y1467654D01*
X818885D01*
G01X839752Y-20995D02*
X842320Y-21711D01*
G01X839752Y-19027D02*
X842320Y-18311D01*
G01X1179972Y-995D02*
X1179332D01*
X1178983Y-646D01*
X1162390D01*
X1159164Y1608D01*
X1157900Y8767D01*
X1157310Y9181D01*
X1151893Y8221D01*
X1151479Y7631D01*
X1154187Y-7700D01*
X1153172Y-9152D01*
X1146710Y-10294D01*
X1145260Y-9279D01*
X1142091Y8657D01*
X1141501Y9071D01*
X1136084Y8112D01*
X1135670Y7522D01*
X1138355Y-7682D01*
X1137338Y-9135D01*
X1130877Y-10277D01*
X1129429Y-9262D01*
X1126261Y8667D01*
X1125671Y9081D01*
X1120254Y8122D01*
X1119840Y7532D01*
X1122531Y-7698D01*
X1121516Y-9150D01*
X1115053Y-10292D01*
X1113603Y-9277D01*
X1110429Y8682D01*
X1109839Y9096D01*
X1104422Y8137D01*
X1104008Y7547D01*
X1106694Y-7648D01*
X1105679Y-9100D01*
X1099216Y-10242D01*
X1097766Y-9227D01*
X1094605Y8661D01*
X1094015Y9075D01*
X1088598Y8116D01*
X1088184Y7527D01*
X1090874Y-7694D01*
X1089858Y-9144D01*
X1083396Y-10286D01*
X1081946Y-9271D01*
X1078782Y8635D01*
X1078192Y9049D01*
X1072775Y8090D01*
X1072361Y7500D01*
X1075031Y-7614D01*
X1074015Y-9064D01*
X1067552Y-10206D01*
X1066102Y-9190D01*
X1062946Y8674D01*
X1062356Y9088D01*
X1056939Y8129D01*
X1056525Y7539D01*
X1059205Y-7627D01*
X1058190Y-9079D01*
X1051727Y-10221D01*
X1050277Y-9206D01*
X1047121Y8656D01*
X1046533Y9070D01*
X1041115Y8111D01*
X1040701Y7521D01*
X1043368Y-7575D01*
X1042353Y-9027D01*
X1035890Y-10169D01*
X1034440Y-9154D01*
X1031286Y8694D01*
X1030698Y9108D01*
X1025280Y8148D01*
X1024866Y7558D01*
X1027533Y-7535D01*
X1026518Y-8987D01*
X1020055Y-10129D01*
X1018605Y-9114D01*
X1015451Y8740D01*
X1014860Y9154D01*
X1009443Y8195D01*
X1009029Y7605D01*
X1011704Y-7534D01*
X1010688Y-8985D01*
X1004226Y-10127D01*
X1002776Y-9112D01*
X999633Y8672D01*
X999044Y9086D01*
X993627Y8127D01*
X993213Y7536D01*
X995894Y-7642D01*
X994878Y-9093D01*
X988416Y-10235D01*
X986966Y-9220D01*
X983799Y8714D01*
X983208Y9128D01*
X977791Y8169D01*
X977377Y7580D01*
X980070Y-7659D01*
X979054Y-9110D01*
X972592Y-10252D01*
X971142Y-9237D01*
X967989Y8603D01*
X967398Y9017D01*
X961981Y8058D01*
X961567Y7468D01*
X964236Y-7633D01*
X963220Y-9084D01*
X956758Y-10226D01*
X955308Y-9211D01*
X952148Y8669D01*
X951558Y9083D01*
X946141Y8124D01*
X945727Y7535D01*
X948406Y-7619D01*
X947390Y-9069D01*
X940928Y-10211D01*
X939477Y-9196D01*
X936292Y8831D01*
X935703Y9245D01*
X930286Y8286D01*
X929872Y7696D01*
X932569Y-7571D01*
X931554Y-9023D01*
X925090Y-10165D01*
X923641Y-9148D01*
X920490Y8691D01*
X919899Y9105D01*
X914482Y8146D01*
X914068Y7556D01*
X916751Y-7627D01*
X915736Y-9079D01*
X909272Y-10221D01*
X907823Y-9204D01*
X904652Y8738D01*
X904063Y9152D01*
X898646Y8193D01*
X898232Y7601D01*
X900922Y-7629D01*
X899907Y-9081D01*
X893444Y-10223D01*
X891994Y-9208D01*
X888823Y8742D01*
X888233Y9156D01*
X882816Y8197D01*
X882402Y7607D01*
X885085Y-7576D01*
X884070Y-9028D01*
X877608Y-10170D01*
X876158Y-9155D01*
X872984Y8803D01*
X872394Y9217D01*
X866977Y8258D01*
X866563Y7668D01*
X869271Y-7658D01*
X868256Y-9107D01*
X861794Y-10249D01*
X860343Y-9235D01*
X859172Y-2606D01*
X856372Y-646D01*
X840629D01*
X840280Y-995D01*
X839752D01*
G01X1179972Y973D02*
X1179352D01*
X1179003Y624D01*
X1162790D01*
X1160324Y2348D01*
X1159060Y9506D01*
X1157608Y10524D01*
X1151154Y9381D01*
X1150136Y7929D01*
X1152844Y-7403D01*
X1152432Y-7992D01*
X1147007Y-8951D01*
X1146420Y-8540D01*
X1143251Y9396D01*
X1141799Y10414D01*
X1135345Y9272D01*
X1134327Y7820D01*
X1137012Y-7385D01*
X1136599Y-7975D01*
X1131175Y-8934D01*
X1130589Y-8523D01*
X1127421Y9406D01*
X1125969Y10424D01*
X1119515Y9282D01*
X1118497Y7830D01*
X1121188Y-7401D01*
X1120776Y-7990D01*
X1115350Y-8949D01*
X1114763Y-8538D01*
X1111589Y9421D01*
X1110137Y10439D01*
X1103683Y9297D01*
X1102665Y7845D01*
X1105351Y-7351D01*
X1104939Y-7940D01*
X1099513Y-8899D01*
X1098926Y-8488D01*
X1095765Y9400D01*
X1094313Y10418D01*
X1087860Y9276D01*
X1086841Y7825D01*
X1089531Y-7396D01*
X1089119Y-7984D01*
X1083693Y-8943D01*
X1083106Y-8532D01*
X1079942Y9374D01*
X1078490Y10392D01*
X1072036Y9250D01*
X1071018Y7798D01*
X1073688Y-7316D01*
X1073276Y-7904D01*
X1067850Y-8863D01*
X1067262Y-8451D01*
X1064106Y9413D01*
X1062654Y10431D01*
X1056200Y9289D01*
X1055182Y7837D01*
X1057862Y-7330D01*
X1057450Y-7919D01*
X1052024Y-8878D01*
X1051437Y-8467D01*
X1048281Y9393D01*
X1046832Y10413D01*
X1040376Y9271D01*
X1039358Y7819D01*
X1042025Y-7278D01*
X1041613Y-7867D01*
X1036187Y-8826D01*
X1035600Y-8415D01*
X1032446Y9431D01*
X1030997Y10451D01*
X1024541Y9308D01*
X1023523Y7856D01*
X1026190Y-7238D01*
X1025778Y-7827D01*
X1020352Y-8786D01*
X1019765Y-8375D01*
X1016611Y9479D01*
X1015157Y10497D01*
X1008704Y9355D01*
X1007686Y7903D01*
X1010361Y-7236D01*
X1009949Y-7825D01*
X1007237Y-8303D01*
Y-8304D01*
X1004523Y-8784D01*
X1003936Y-8373D01*
X1000793Y9410D01*
X999342Y10429D01*
X992888Y9286D01*
X991870Y7834D01*
X994551Y-7344D01*
X994139Y-7933D01*
X991427Y-8411D01*
Y-8412D01*
X988713Y-8892D01*
X988126Y-8481D01*
X984959Y9453D01*
X983505Y10471D01*
X977053Y9329D01*
X976034Y7879D01*
X978727Y-7361D01*
X978315Y-7950D01*
X975603Y-8428D01*
Y-8429D01*
X972889Y-8909D01*
X972302Y-8498D01*
X969149Y9342D01*
X967695Y10360D01*
X961242Y9218D01*
X960224Y7766D01*
X962893Y-7336D01*
X962481Y-7924D01*
X959769Y-8402D01*
Y-8403D01*
X957055Y-8883D01*
X956468Y-8472D01*
X953308Y9408D01*
X951856Y10426D01*
X945403Y9284D01*
X944384Y7834D01*
X947063Y-7321D01*
X946651Y-7909D01*
X941225Y-8868D01*
X940637Y-8456D01*
X937452Y9569D01*
X936002Y10588D01*
X929547Y9446D01*
X928529Y7994D01*
X931226Y-7274D01*
X930814Y-7863D01*
X928102Y-8341D01*
Y-8342D01*
X925388Y-8822D01*
X924801Y-8410D01*
X921650Y9430D01*
X920196Y10448D01*
X913743Y9306D01*
X912725Y7854D01*
X915408Y-7330D01*
X914996Y-7919D01*
X909570Y-8878D01*
X908983Y-8466D01*
X905812Y9477D01*
X904361Y10495D01*
X897907Y9352D01*
X896889Y7899D01*
X899579Y-7332D01*
X899167Y-7921D01*
X893741Y-8880D01*
X893154Y-8469D01*
X889983Y9481D01*
X888531Y10499D01*
X882077Y9357D01*
X881059Y7905D01*
X883742Y-7279D01*
X883330Y-7868D01*
X877905Y-8827D01*
X877318Y-8416D01*
X874144Y9542D01*
X872692Y10560D01*
X866238Y9418D01*
X865220Y7966D01*
X867928Y-7360D01*
X867517Y-7947D01*
X862091Y-8906D01*
X861503Y-8495D01*
X860332Y-1867D01*
X856773Y624D01*
X840633D01*
X840284Y973D01*
X839752D01*
G01Y19005D02*
X842320Y18289D01*
G01X839752Y20973D02*
X842320Y21689D01*
G01X1438532Y1278335D02*
X1439897Y1279700D01*
Y1281352D01*
X1449981Y1291436D01*
Y1390780D01*
X1405780Y1434981D01*
X1404734D01*
X1403651Y1436064D01*
Y1437110D01*
X1402570Y1438191D01*
X1401523D01*
X1400440Y1439274D01*
Y1440321D01*
X1399359Y1441402D01*
X1398312D01*
X1397229Y1442485D01*
Y1443532D01*
X1396148Y1444613D01*
X1395101D01*
X1394018Y1445696D01*
Y1446743D01*
X1392937Y1447824D01*
X1391876D01*
X1390793Y1448907D01*
Y1449968D01*
X1389712Y1451049D01*
X1388651D01*
X1387568Y1452132D01*
Y1453193D01*
X1386487Y1454274D01*
X1385426D01*
X1384343Y1455357D01*
Y1456418D01*
X1371182Y1469579D01*
X1173155D01*
X1165751Y1476983D01*
X1115129D01*
X1098308Y1460162D01*
X995155D01*
X977731Y1442738D01*
X919909D01*
X918278Y1444369D01*
X905476D01*
X890166Y1459679D01*
X869327D01*
X862622Y1466384D01*
X829390D01*
G01X1007587Y838356D02*
X1006689Y839254D01*
X1003067D01*
X1002126Y838863D01*
X1001616Y838354D01*
Y837293D01*
X1000540Y836217D01*
X999479D01*
X998405Y835143D01*
Y834082D01*
X997329Y833006D01*
X996268D01*
X994243Y830982D01*
X993662Y829578D01*
X994068Y828598D01*
X993486Y827193D01*
X992505Y826787D01*
X991924Y825383D01*
X992324Y824416D01*
X991743Y823011D01*
X990775Y822611D01*
X985104Y808921D01*
X984240Y801658D01*
X984887Y800836D01*
X984707Y799326D01*
X983884Y798678D01*
X983885D01*
X983678Y796940D01*
X984326Y796117D01*
X984146Y794607D01*
X983323Y793960D01*
X983108Y792152D01*
X983755Y791330D01*
X983576Y789819D01*
X982752Y789172D01*
X982753D01*
X959051Y590095D01*
X895678Y328713D01*
X896650Y270736D01*
Y229648D01*
X897526Y225242D01*
X900883Y217140D01*
X904971Y211022D01*
X908074Y207919D01*
X909834Y207190D01*
X910857D01*
X911403Y207736D01*
X913386D01*
G01X1007587Y827354D02*
X1006612Y828329D01*
X1004563D01*
X1001594Y827098D01*
X995797Y821302D01*
X988848Y806990D01*
X988132Y800964D01*
X988788Y800131D01*
X988608Y798621D01*
X987774Y797964D01*
X987572Y796263D01*
X988228Y795430D01*
X988048Y793920D01*
X987214Y793264D01*
X987035Y791755D01*
X987691Y790922D01*
X987511Y789411D01*
X986677Y788755D01*
X986678D01*
X978721Y721920D01*
X967896Y630988D01*
X968552Y630154D01*
X968372Y628644D01*
X967538Y627988D01*
X967359Y626479D01*
X968015Y625646D01*
X967835Y624135D01*
X967001Y623479D01*
X966822Y621970D01*
X967478Y621137D01*
X967298Y619626D01*
X966464Y618970D01*
X966285Y617461D01*
X966941Y616628D01*
X966761Y615117D01*
X965927Y614461D01*
X963436Y593533D01*
X899104Y328201D01*
X900099Y268760D01*
Y229867D01*
X900777Y226458D01*
X902005Y223491D01*
X905920Y217632D01*
X908240Y215312D01*
X909221Y214656D01*
X910136Y214277D01*
X910913D01*
X911459Y214823D01*
X913386D01*
G01X1007587Y841756D02*
X1006355Y840524D01*
X1002814D01*
X1001406Y839941D01*
X993166Y831702D01*
X983863Y809245D01*
X981492Y789323D01*
X973467Y721920D01*
X957798Y590321D01*
X926130Y459704D01*
Y459703D01*
X894405Y328854D01*
X895380Y270725D01*
Y229522D01*
X896304Y224871D01*
X899757Y216538D01*
X903984Y210212D01*
X907354Y206842D01*
X909581Y205920D01*
X910869D01*
X911415Y205374D01*
X913386D01*
G01X1007587Y830754D02*
X1006432Y829599D01*
X1004310D01*
X1000874Y828176D01*
X994747Y822049D01*
X987612Y807353D01*
X962183Y593759D01*
X897831Y328342D01*
X898829Y268749D01*
Y229741D01*
X899555Y226087D01*
X900879Y222890D01*
X904933Y216822D01*
X907430Y214325D01*
X908620Y213530D01*
X909883Y213007D01*
X910967D01*
X911513Y212461D01*
X913386D01*
G01X1007587Y819752D02*
X1006378Y818543D01*
X1004884D01*
X1002805Y817682D01*
X992709Y807586D01*
X991569Y805236D01*
X967288Y601297D01*
X901004Y327916D01*
X902013Y267647D01*
Y231720D01*
X903021Y226651D01*
X903453Y225607D01*
X905161Y223052D01*
X906789Y221424D01*
X907771Y220768D01*
X909400Y220093D01*
X910889D01*
X911435Y219547D01*
X913386D01*
G01X1007587Y816352D02*
X1006666Y817273D01*
X1005137D01*
X1003525Y816604D01*
X993759Y806839D01*
X992805Y804874D01*
X992331Y800892D01*
X992332Y800891D01*
X992989Y800058D01*
X992809Y798548D01*
X991974Y797891D01*
X991795Y796382D01*
X992451Y795549D01*
X992271Y794038D01*
X991437Y793382D01*
X991258Y791873D01*
X991914Y791040D01*
X991734Y789529D01*
X990900Y788873D01*
Y788864D01*
X982930Y721920D01*
X972142Y631312D01*
X972798Y630479D01*
X972618Y628968D01*
X971784Y628312D01*
X971605Y626803D01*
X972261Y625970D01*
X972081Y624459D01*
X971247Y623803D01*
X971068Y622294D01*
X971724Y621461D01*
X971544Y619950D01*
X970710Y619294D01*
X970531Y617785D01*
X971187Y616952D01*
X971007Y615441D01*
X970173Y614785D01*
X968541Y601071D01*
X902277Y327775D01*
X903283Y267658D01*
Y231846D01*
X904243Y227021D01*
X904579Y226209D01*
X906148Y223862D01*
X907599Y222411D01*
X908373Y221894D01*
X909653Y221363D01*
X911033D01*
X911579Y221909D01*
X913386D01*
G01X1007587Y805418D02*
X1006588Y806417D01*
X1002865D01*
X1001012Y805649D01*
X997874Y803552D01*
X997451Y803129D01*
X996987Y802174D01*
X996827Y800824D01*
X997483Y799991D01*
X997304Y798481D01*
X996469Y797825D01*
X996290Y796316D01*
X996946Y795483D01*
X996766Y793972D01*
X995932Y793316D01*
X995752Y791797D01*
X996408Y790964D01*
X996227Y789444D01*
X995392Y788787D01*
X974292Y611541D01*
X905370Y327293D01*
X906402Y265607D01*
Y255315D01*
X907152Y254565D01*
Y253045D01*
X906402Y252295D01*
Y250775D01*
X907152Y250025D01*
Y248505D01*
X906402Y247755D01*
Y240797D01*
X907152Y240047D01*
Y238527D01*
X906402Y237777D01*
Y236257D01*
X907152Y235507D01*
Y233987D01*
X906402Y233237D01*
Y231835D01*
X907117Y230110D01*
X908020Y229208D01*
X909847Y228450D01*
X911003D01*
X911549Y228996D01*
X913386D01*
G01X1007587Y808818D02*
X1006456Y807687D01*
X1002612D01*
X1000410Y806775D01*
X997064Y804539D01*
X996401Y803876D01*
X995751Y802537D01*
X994733Y793990D01*
X994732Y793989D01*
X973039Y611767D01*
X904097Y327434D01*
X905132Y265596D01*
Y231582D01*
X906040Y229390D01*
X907300Y228130D01*
X909594Y227180D01*
X910979D01*
X911525Y226634D01*
X913386D01*
G01X942596Y208375D02*
X943761Y207210D01*
X948064D01*
X949334Y207736D01*
X951063Y209465D01*
Y210526D01*
X952139Y211602D01*
X953200D01*
X954274Y212676D01*
Y213736D01*
X955350Y214812D01*
X956410D01*
X957674Y216076D01*
X958531Y218146D01*
X958131Y219113D01*
X958712Y220518D01*
X959680Y220919D01*
X960261Y222323D01*
X959861Y223290D01*
X960443Y224695D01*
X961411Y225095D01*
X962100Y226760D01*
Y255858D01*
X976988Y540397D01*
X981090Y570776D01*
X1021268Y754231D01*
Y780698D01*
X1020518Y781448D01*
Y782968D01*
X1021268Y783718D01*
Y784648D01*
X1020850Y785656D01*
X1017487Y789019D01*
X1016426D01*
X1015350Y790095D01*
Y791156D01*
X1014276Y792230D01*
X1013215D01*
X1012139Y793306D01*
Y794367D01*
X1011363Y795142D01*
X1010427Y795531D01*
X1008634D01*
X1007587Y794484D01*
G01X942596Y204775D02*
X943761Y205940D01*
X948317D01*
X950054Y206658D01*
X951962Y208566D01*
Y208567D01*
X958751Y215356D01*
X963370Y226507D01*
Y255824D01*
X978254Y540279D01*
X982342Y570555D01*
X1022538Y754093D01*
Y784901D01*
X1021927Y786376D01*
X1012083Y796220D01*
X1010680Y796801D01*
X1008670D01*
X1007587Y797884D01*
G01X940496Y208375D02*
X939311Y207190D01*
X933898D01*
X933352Y207736D01*
X931496D01*
G01X940496Y204775D02*
X939351Y205920D01*
X933798D01*
X933252Y205374D01*
X931496D01*
G01X1025493Y765719D02*
X1026842Y764370D01*
X1027790D01*
X1029213Y762947D01*
Y756395D01*
X1028580Y754033D01*
X1018270Y715525D01*
X980454Y503256D01*
X967450Y254732D01*
Y225693D01*
X961384Y211047D01*
X948547Y198210D01*
X937076D01*
X936455Y198831D01*
X934086D01*
X933542Y198287D01*
X931496D01*
G01X1025493Y761819D02*
X1026774Y763100D01*
X1027263D01*
X1027943Y762420D01*
Y756563D01*
X1027550Y755095D01*
X1026631Y754565D01*
X1026238Y753095D01*
X1026768Y752177D01*
X1026375Y750709D01*
X1025456Y750179D01*
X1025063Y748709D01*
X1025593Y747791D01*
X1025200Y746323D01*
X1024281Y745793D01*
X1023888Y744323D01*
X1024418Y743405D01*
X1024419Y743404D01*
X1017029Y715801D01*
X979189Y503401D01*
X966180Y254766D01*
Y225946D01*
X960307Y211767D01*
X957653Y209113D01*
X956592D01*
X955516Y208037D01*
Y206976D01*
X954442Y205902D01*
X953381D01*
X952305Y204826D01*
Y203765D01*
X951231Y202691D01*
X950170D01*
X949094Y201615D01*
Y200554D01*
X948020Y199480D01*
X944194D01*
X943444Y200230D01*
X941924D01*
X941174Y199480D01*
X937603D01*
X936982Y200101D01*
X934074D01*
X933526Y200649D01*
X931496D01*
G01X1007587Y783482D02*
X1008647Y784542D01*
X1009822D01*
X1010884Y784100D01*
X1017120Y777866D01*
X1017431Y777115D01*
X1017432D01*
Y774034D01*
X1016682Y773284D01*
Y771764D01*
X1017432Y771014D01*
Y769494D01*
X1016682Y768744D01*
Y767224D01*
X1017432Y766474D01*
Y752892D01*
X978173Y573639D01*
X973726Y540702D01*
X959170Y262500D01*
Y233963D01*
X958430Y233223D01*
Y231703D01*
X959170Y230963D01*
Y229443D01*
X957840Y226234D01*
X956873Y225833D01*
X956291Y224428D01*
X956691Y223461D01*
X954840Y218993D01*
X953404Y217557D01*
X952343D01*
X951260Y216474D01*
Y215413D01*
X950179Y214332D01*
X948717D01*
X947977Y215072D01*
X946457D01*
X945717Y214332D01*
X943761D01*
X942596Y215497D01*
G01X1007587Y786882D02*
X1008657Y785812D01*
X1010076D01*
X1011604Y785178D01*
X1018197Y778586D01*
X1018702Y777368D01*
Y752754D01*
X979425Y573418D01*
X974992Y540584D01*
X960440Y262466D01*
Y229190D01*
X957865Y222975D01*
X957864Y222974D01*
X955917Y218273D01*
X950706Y213062D01*
X943761D01*
X942596Y211897D01*
G01X940496Y215497D02*
X939276Y214277D01*
X933908D01*
X933362Y214823D01*
X931496D01*
G01X947196Y222548D02*
X946011Y221363D01*
X933986D01*
X933440Y221909D01*
X931496D01*
G01X940496Y211897D02*
X939386Y213007D01*
X933810D01*
X933264Y212461D01*
X931496D01*
G01X947196Y218948D02*
X946051Y220093D01*
X933842D01*
X933296Y219547D01*
X931496D01*
G01X942596Y226035D02*
X943761Y227200D01*
X944838D01*
X947445Y228280D01*
X948503Y229337D01*
X948921Y230124D01*
X953860Y254952D01*
X968909Y542627D01*
X973822Y582207D01*
X1002404Y758887D01*
X1003357Y760810D01*
X1005218Y762671D01*
X1006462D01*
X1007587Y761546D01*
G01X942596Y229635D02*
X943761Y228470D01*
X944585D01*
X946725Y229357D01*
X947470Y230102D01*
X947712Y230556D01*
X952596Y255110D01*
X967643Y542739D01*
X972564Y582387D01*
X995136Y721920D01*
X1001180Y759279D01*
X1002311Y761561D01*
X1004691Y763941D01*
X1006582D01*
X1007587Y764946D01*
G01X940496Y226035D02*
X939351Y227180D01*
X933942D01*
X933396Y226634D01*
X931496D01*
G01X940496Y229635D02*
X939311Y228450D01*
X933930D01*
X933384Y228996D01*
X931496D01*
G01X949296Y222548D02*
X950461Y221383D01*
X951197D01*
X951707Y221893D01*
X952288Y223297D01*
X951888Y224264D01*
X952469Y225669D01*
X953437Y226069D01*
X955301Y230570D01*
Y233012D01*
X954551Y233762D01*
Y235282D01*
X955301Y236032D01*
Y237552D01*
X954551Y238302D01*
Y239822D01*
X955301Y240572D01*
Y242092D01*
X954551Y242842D01*
Y244362D01*
X955301Y245112D01*
Y247790D01*
X970641Y540990D01*
X975928Y580151D01*
X1012531Y747278D01*
Y757791D01*
X1011781Y758541D01*
Y760061D01*
X1012531Y760811D01*
Y762331D01*
X1011781Y763081D01*
Y764601D01*
X1012531Y765351D01*
Y766871D01*
X1011781Y767621D01*
Y769141D01*
X1012531Y769891D01*
Y771024D01*
X1012256Y771686D01*
X1010692Y773250D01*
X1010017Y773530D01*
X1008637D01*
X1007587Y772480D01*
G01X949296Y218948D02*
X950461Y220113D01*
X951724D01*
X952784Y221173D01*
X956571Y230317D01*
Y247756D01*
X971907Y540872D01*
X977180Y579930D01*
X1008278Y721920D01*
X1013801Y747140D01*
Y771277D01*
X1013333Y772406D01*
X1011412Y774327D01*
X1010270Y774800D01*
X1008667D01*
X1007587Y775880D01*
G01X1090958Y1646528D02*
X1092045Y1647615D01*
X1108870D01*
X1109529Y1648274D01*
X1114861D01*
X1115210Y1647925D01*
X1116166D01*
G01X1090958Y1649928D02*
X1092001Y1648885D01*
X1108343D01*
X1109002Y1649544D01*
X1114853D01*
X1115203Y1649894D01*
X1116166D01*
G01X1189242Y1465128D02*
X1169958D01*
X1161409Y1473677D01*
X1152550D01*
X1148809Y1469936D01*
X1116163D01*
X1115098Y1468871D01*
G01X1178737Y1466398D02*
X1170485D01*
X1161936Y1474947D01*
X1152023D01*
X1148282Y1471206D01*
X1116163D01*
X1115098Y1472271D01*
G01X1128469Y1637591D02*
Y1636635D01*
X1128120Y1636286D01*
Y1627850D01*
X1116182Y1615912D01*
Y1605619D01*
X1117247Y1604554D01*
G01X1126500Y1637591D02*
Y1636628D01*
X1126850Y1636278D01*
Y1628377D01*
X1114912Y1616439D01*
Y1605619D01*
X1113847Y1604554D01*
G01X1134866Y1645957D02*
X1135629D01*
X1135979Y1645607D01*
X1140019D01*
X1141084Y1646672D01*
G01X1134866Y1643988D02*
X1135634D01*
X1135983Y1644337D01*
X1140019D01*
X1141084Y1643272D01*
G01X1134866Y1651862D02*
X1135823D01*
X1136171Y1651514D01*
X1137844D01*
X1140873Y1654543D01*
X1145436D01*
X1146501Y1655608D01*
G01X1134866Y1649894D02*
X1135829D01*
X1136179Y1650244D01*
X1138371D01*
X1141400Y1653273D01*
X1145436D01*
X1146501Y1652208D01*
G01X1126500Y1656291D02*
Y1657247D01*
X1126849Y1657596D01*
Y1661640D01*
X1125784Y1662705D01*
G01X1128469Y1656291D02*
Y1657254D01*
X1128119Y1657604D01*
Y1661640D01*
X1129184Y1662705D01*
G01X1179972Y-20995D02*
X1177404Y-21711D01*
G01X1179972Y-19027D02*
X1177404Y-18311D01*
G01X1179972Y19005D02*
X1177404Y18289D01*
G01X1179972Y20973D02*
X1177404Y21689D01*
G01X1421211Y1261941D02*
X1420096Y1263056D01*
Y1269540D01*
X1439723Y1289167D01*
Y1391662D01*
X1364987Y1466398D01*
X1178737D01*
G01X1183824Y1490895D02*
X1184989Y1489730D01*
Y1486960D01*
X1183924Y1485895D01*
G01X1180724Y1500595D02*
X1179559Y1499430D01*
Y1496660D01*
X1180624Y1495595D01*
G01X1177124Y1500595D02*
X1178289Y1499430D01*
Y1496660D01*
X1177224Y1495595D01*
G01X1170986Y1516590D02*
X1172051Y1515525D01*
X1174821D01*
X1175986Y1516690D01*
G01X1170986Y1513190D02*
X1172051Y1514255D01*
X1174821D01*
X1175986Y1513090D01*
G01Y1534890D02*
X1174821Y1536055D01*
X1172051D01*
X1170986Y1534990D01*
G01X1175986Y1538490D02*
X1174821Y1537325D01*
X1172051D01*
X1170986Y1538390D01*
G01X1176356Y1556431D02*
X1177318Y1557393D01*
X1178344D01*
X1179306Y1556431D01*
G01D02*
X1180223Y1557348D01*
X1182291D01*
X1183508Y1558565D01*
X1185842D01*
G01X1176356Y1559631D02*
X1177324Y1558663D01*
X1178338D01*
X1179306Y1559631D01*
G01D02*
X1180319Y1558618D01*
X1181764D01*
X1182981Y1559835D01*
X1185917D01*
G01X1170404Y1556331D02*
X1171469Y1557396D01*
X1173291D01*
X1174256Y1556431D01*
G01X1170404Y1559731D02*
X1171469Y1558666D01*
X1173291D01*
X1174256Y1559631D01*
G01X1276081Y895562D02*
X1269212Y888693D01*
Y852670D01*
X1262651Y846109D01*
Y842870D01*
X1216101Y796318D01*
X1214505D01*
X1213502Y795315D01*
G01X1275181Y896460D02*
X1275182D01*
X1267942Y889220D01*
Y853197D01*
X1261381Y846636D01*
Y843397D01*
X1260300Y842316D01*
X1259366D01*
X1258283Y841233D01*
Y840299D01*
X1215574Y797588D01*
X1214575D01*
X1213502Y798661D01*
G01X1275181Y916878D02*
X1272664D01*
X1251942Y896156D01*
Y864375D01*
X1221827Y834261D01*
X1217355D01*
X1216256Y833162D01*
X1214538D01*
X1213502Y832126D01*
G01X1275181Y918148D02*
X1272137D01*
X1250672Y896683D01*
Y864902D01*
X1221300Y835531D01*
X1216828D01*
X1215729Y834432D01*
X1214542D01*
X1213502Y835472D01*
G01X1275303Y936525D02*
X1267711D01*
X1234672Y903486D01*
Y884274D01*
X1220373Y869975D01*
X1214540D01*
X1213502Y868937D01*
G01X1275303Y937795D02*
X1267184D01*
X1233402Y904013D01*
Y884801D01*
X1219846Y871245D01*
X1214540D01*
X1213502Y872283D01*
G01X1275175Y955525D02*
X1258075D01*
X1221616Y919066D01*
Y915530D01*
X1217061Y910975D01*
Y908021D01*
X1215808Y906768D01*
X1214521D01*
X1213502Y905749D01*
G01X1275175Y956795D02*
X1257548D01*
X1220346Y919593D01*
Y916057D01*
X1215791Y911502D01*
Y908548D01*
X1215281Y908038D01*
X1214559D01*
X1213502Y909095D01*
G01X1275181Y974478D02*
X1239668D01*
X1223292Y958102D01*
Y954056D01*
X1217627Y948391D01*
Y945241D01*
X1215904Y943518D01*
X1214460D01*
X1213502Y942560D01*
G01X1275181Y975748D02*
X1239141D01*
X1222022Y958629D01*
Y954583D01*
X1216357Y948918D01*
Y945768D01*
X1215377Y944788D01*
X1214620D01*
X1213502Y945906D01*
G01X1275990Y1068946D02*
X1270495D01*
X1267937Y1066388D01*
X1240129D01*
X1215659Y1090858D01*
X1214941D01*
X1213887Y1089804D01*
G01X1275990Y1070216D02*
X1269968D01*
X1267410Y1067658D01*
X1240656D01*
X1216186Y1092128D01*
X1214947D01*
X1213925Y1093150D01*
G01X1275181Y1087866D02*
X1252887D01*
X1218528Y1122225D01*
Y1124900D01*
X1215736Y1127692D01*
X1214518D01*
X1213441Y1126615D01*
G01X1275181Y1089136D02*
X1253414D01*
X1219798Y1122752D01*
Y1125427D01*
X1216263Y1128962D01*
X1214516D01*
X1213517Y1129961D01*
G01X1275181Y1106705D02*
X1264345D01*
X1234833Y1136217D01*
Y1147756D01*
X1218085Y1164504D01*
X1214519D01*
X1213441Y1163426D01*
G01X1275181Y1107975D02*
X1264872D01*
X1236103Y1136744D01*
Y1148283D01*
X1218612Y1165774D01*
X1214515D01*
X1213517Y1166772D01*
G01X1275181Y1125944D02*
X1269727D01*
X1252288Y1143383D01*
Y1165957D01*
X1216928Y1201317D01*
X1214521D01*
X1213441Y1200237D01*
G01X1275181Y1127214D02*
X1270254D01*
X1253558Y1143910D01*
Y1166484D01*
X1217455Y1202587D01*
X1214513D01*
X1213517Y1203583D01*
G01X1275041Y1146983D02*
X1269696Y1152328D01*
Y1178396D01*
X1269036Y1179056D01*
Y1180586D01*
X1269696Y1181246D01*
Y1182776D01*
X1217486Y1234986D01*
Y1236323D01*
X1215684Y1238125D01*
X1214518D01*
X1213441Y1237048D01*
G01X1275941Y1147882D02*
X1270966Y1152855D01*
Y1183303D01*
X1218756Y1235513D01*
Y1236850D01*
X1216211Y1239395D01*
X1214516D01*
X1213517Y1240394D01*
G01X1417711Y1261941D02*
X1418826Y1263056D01*
Y1270067D01*
X1438453Y1289694D01*
Y1391135D01*
X1364460Y1465128D01*
X1362261D01*
X1361511Y1464378D01*
X1359981D01*
X1359231Y1465128D01*
X1357701D01*
X1356951Y1464378D01*
X1355421D01*
X1354671Y1465128D01*
X1353141D01*
X1352391Y1464378D01*
X1350861D01*
X1350111Y1465128D01*
X1189242D01*
G01X1187424Y1490895D02*
X1186259Y1489730D01*
Y1486960D01*
X1187324Y1485895D01*
G01X1200824Y1510295D02*
X1199659Y1509130D01*
Y1506360D01*
X1200724Y1505295D01*
G01X1197224Y1510295D02*
X1198389Y1509130D01*
Y1506360D01*
X1197324Y1505295D01*
G01X1195939Y1640286D02*
X1197104Y1639121D01*
Y1626445D01*
X1196039Y1625380D01*
G01X1199539Y1640286D02*
X1198374Y1639121D01*
Y1626445D01*
X1199439Y1625380D01*
G01X1195939Y1642386D02*
X1197104Y1643551D01*
Y1656227D01*
X1196039Y1657292D01*
G01X1199539Y1642386D02*
X1198374Y1643551D01*
Y1656227D01*
X1199439Y1657292D01*
G01X1277248Y892413D02*
Y892414D01*
X1272142Y887308D01*
Y845742D01*
X1270302Y843902D01*
X1268526D01*
X1266921Y845507D01*
X1266203D01*
X1265581Y844885D01*
Y844167D01*
X1267186Y842562D01*
Y840786D01*
X1262890Y836490D01*
X1260546D01*
X1259849Y835793D01*
Y833449D01*
X1258415Y832015D01*
X1256071D01*
X1255374Y831318D01*
Y828974D01*
X1253940Y827540D01*
X1251596D01*
X1250899Y826843D01*
Y824499D01*
X1249465Y823065D01*
X1247121D01*
X1246424Y822368D01*
Y820024D01*
X1244990Y818590D01*
X1242646D01*
X1241949Y817893D01*
Y815549D01*
X1240515Y814115D01*
X1238171D01*
X1237474Y813418D01*
Y811074D01*
X1236040Y809640D01*
X1233696D01*
X1232999Y808943D01*
Y806599D01*
X1231565Y805165D01*
X1229221D01*
X1228524Y804468D01*
Y802124D01*
X1227090Y800690D01*
X1224746D01*
X1224049Y799993D01*
Y797649D01*
X1222615Y796215D01*
X1220271D01*
X1219574Y795518D01*
Y793174D01*
X1217734Y791334D01*
X1213254D01*
X1212216Y790296D01*
X1210111D01*
G01X1276350Y893313D02*
X1270872Y887835D01*
Y850823D01*
X1270212Y850163D01*
Y848633D01*
X1270872Y847973D01*
Y846269D01*
X1269775Y845172D01*
X1269053D01*
X1267448Y846777D01*
X1265676D01*
X1264311Y845412D01*
Y843640D01*
X1265916Y842035D01*
Y841313D01*
X1262363Y837760D01*
X1260019D01*
X1258579Y836320D01*
Y833976D01*
X1257888Y833285D01*
X1255544D01*
X1254104Y831845D01*
Y829501D01*
X1253413Y828810D01*
X1251069D01*
X1249629Y827370D01*
Y825026D01*
X1248938Y824335D01*
X1246594D01*
X1245154Y822895D01*
Y820551D01*
X1244463Y819860D01*
X1242119D01*
X1240679Y818420D01*
Y816076D01*
X1239988Y815385D01*
X1237644D01*
X1236204Y813945D01*
Y811601D01*
X1235513Y810910D01*
X1233169D01*
X1231729Y809470D01*
Y807126D01*
X1231038Y806435D01*
X1228694D01*
X1227254Y804995D01*
Y802651D01*
X1226563Y801960D01*
X1224219D01*
X1222779Y800520D01*
Y798176D01*
X1222088Y797485D01*
X1219744D01*
X1218304Y796045D01*
Y793701D01*
X1217207Y792604D01*
X1213254D01*
X1212216Y793642D01*
X1210111D01*
G01X1276056Y915038D02*
X1273227D01*
X1253602Y895413D01*
Y863687D01*
X1248873Y858958D01*
Y857182D01*
X1249725Y856330D01*
Y855612D01*
X1249103Y854990D01*
X1248385D01*
X1247533Y855842D01*
X1245757D01*
X1244398Y854483D01*
Y852707D01*
X1245250Y851855D01*
Y851137D01*
X1244628Y850515D01*
X1243910D01*
X1243058Y851367D01*
X1241282D01*
X1239923Y850008D01*
Y848232D01*
X1240775Y847380D01*
Y846662D01*
X1240153Y846040D01*
X1239435D01*
X1238583Y846892D01*
X1236807D01*
X1235448Y845533D01*
Y843757D01*
X1236300Y842905D01*
Y842187D01*
X1235678Y841565D01*
X1234960D01*
X1234108Y842417D01*
X1232332D01*
X1230973Y841058D01*
Y839282D01*
X1231825Y838430D01*
Y837712D01*
X1231203Y837090D01*
X1230485D01*
X1229633Y837942D01*
X1227857D01*
X1226498Y836583D01*
Y834807D01*
X1226961Y834344D01*
Y833626D01*
X1226339Y833004D01*
X1225621D01*
X1225158Y833467D01*
X1223382D01*
X1222509Y832594D01*
X1218121D01*
X1214942Y829415D01*
X1213254D01*
X1212216Y830453D01*
X1210111D01*
G01X1276056Y913768D02*
X1273754D01*
X1254872Y894886D01*
Y863160D01*
X1250143Y858431D01*
Y857709D01*
X1250995Y856857D01*
Y855085D01*
X1249630Y853720D01*
X1247858D01*
X1247006Y854572D01*
X1246284D01*
X1245668Y853956D01*
Y853234D01*
X1246520Y852382D01*
Y850610D01*
X1245155Y849245D01*
X1243383D01*
X1242531Y850097D01*
X1241809D01*
X1241193Y849481D01*
Y848759D01*
X1242045Y847907D01*
Y846135D01*
X1240680Y844770D01*
X1238908D01*
X1238056Y845622D01*
X1237334D01*
X1236718Y845006D01*
Y844284D01*
X1237570Y843432D01*
Y841660D01*
X1236205Y840295D01*
X1234433D01*
X1233581Y841147D01*
X1232859D01*
X1232243Y840531D01*
Y839809D01*
X1233095Y838957D01*
Y837185D01*
X1231730Y835820D01*
X1229958D01*
X1229106Y836672D01*
X1228384D01*
X1227768Y836056D01*
Y835334D01*
X1228231Y834871D01*
Y833099D01*
X1226866Y831734D01*
X1225094D01*
X1224631Y832197D01*
X1223909D01*
X1223036Y831324D01*
X1218648D01*
X1215469Y828145D01*
X1213254D01*
X1212216Y827107D01*
X1210111D01*
G01X1275941Y933475D02*
X1268861D01*
X1237602Y902216D01*
Y882993D01*
X1235616Y881007D01*
Y880285D01*
X1237539Y878362D01*
Y876590D01*
X1236174Y875225D01*
X1234402D01*
X1232479Y877148D01*
X1231757D01*
X1231141Y876532D01*
Y875810D01*
X1233719Y873232D01*
Y871460D01*
X1232354Y870095D01*
X1230582D01*
X1228004Y872673D01*
X1227282D01*
X1226666Y872057D01*
Y871335D01*
X1228589Y869412D01*
Y867640D01*
X1227224Y866275D01*
X1225452D01*
X1223529Y868198D01*
X1222807D01*
X1219565Y864956D01*
X1213254D01*
X1212216Y863918D01*
X1210111D01*
G01X1275941Y934745D02*
X1268334D01*
X1236332Y902743D01*
Y883520D01*
X1234346Y881534D01*
Y879758D01*
X1236269Y877835D01*
Y877117D01*
X1235647Y876495D01*
X1234929D01*
X1233006Y878418D01*
X1231230D01*
X1229871Y877059D01*
Y875283D01*
X1232449Y872705D01*
Y871987D01*
X1231827Y871365D01*
X1231109D01*
X1228531Y873943D01*
X1226755D01*
X1225396Y872584D01*
Y870808D01*
X1227319Y868885D01*
Y868167D01*
X1226697Y867545D01*
X1225979D01*
X1224056Y869468D01*
X1222280D01*
X1219038Y866226D01*
X1213254D01*
X1212216Y867264D01*
X1210111D01*
G01X1275181Y953806D02*
X1262395D01*
X1257375Y948786D01*
X1256653D01*
X1256055Y949384D01*
X1254283D01*
X1252918Y948019D01*
Y946247D01*
X1253516Y945649D01*
Y944927D01*
X1252900Y944311D01*
X1252178D01*
X1251580Y944909D01*
X1249808D01*
X1248443Y943544D01*
Y941772D01*
X1249041Y941174D01*
Y940452D01*
X1248425Y939836D01*
X1247703D01*
X1247105Y940434D01*
X1245333D01*
X1243968Y939069D01*
Y937297D01*
X1244566Y936699D01*
Y935977D01*
X1243950Y935361D01*
X1243228D01*
X1242630Y935959D01*
X1240858D01*
X1239493Y934594D01*
Y932822D01*
X1240091Y932224D01*
Y931502D01*
X1239475Y930886D01*
X1238753D01*
X1238155Y931484D01*
X1236383D01*
X1235018Y930119D01*
Y928347D01*
X1235616Y927749D01*
Y927027D01*
X1235000Y926411D01*
X1234278D01*
X1233680Y927009D01*
X1231908D01*
X1230543Y925644D01*
Y923872D01*
X1231141Y923274D01*
Y922552D01*
X1230525Y921936D01*
X1229803D01*
X1229205Y922534D01*
X1227433D01*
X1226068Y921169D01*
Y919397D01*
X1226666Y918799D01*
Y918077D01*
X1218765Y910176D01*
Y907076D01*
X1214726Y903037D01*
X1213254D01*
X1212216Y904075D01*
X1210111D01*
G01X1275181Y952536D02*
X1262922D01*
X1257902Y947516D01*
X1256126D01*
X1255528Y948114D01*
X1254810D01*
X1254188Y947492D01*
Y946774D01*
X1254786Y946176D01*
Y944400D01*
X1253427Y943041D01*
X1251651D01*
X1251053Y943639D01*
X1250335D01*
X1249713Y943017D01*
Y942299D01*
X1250311Y941701D01*
Y939925D01*
X1248952Y938566D01*
X1247176D01*
X1246578Y939164D01*
X1245860D01*
X1245238Y938542D01*
Y937824D01*
X1245836Y937226D01*
Y935450D01*
X1244477Y934091D01*
X1242701D01*
X1242103Y934689D01*
X1241385D01*
X1240763Y934067D01*
Y933349D01*
X1241361Y932751D01*
Y930975D01*
X1240002Y929616D01*
X1238226D01*
X1237628Y930214D01*
X1236910D01*
X1236288Y929592D01*
Y928874D01*
X1236886Y928276D01*
Y926500D01*
X1235527Y925141D01*
X1233751D01*
X1233153Y925739D01*
X1232435D01*
X1231813Y925117D01*
Y924399D01*
X1232411Y923801D01*
Y922025D01*
X1231052Y920666D01*
X1229276D01*
X1228678Y921264D01*
X1227960D01*
X1227338Y920642D01*
Y919924D01*
X1227936Y919326D01*
Y917550D01*
X1220035Y909649D01*
Y906549D01*
X1215253Y901767D01*
X1213254D01*
X1212216Y900729D01*
X1210111D01*
G01X1277046Y972440D02*
X1239979D01*
X1238410Y970871D01*
Y969095D01*
X1240153Y967351D01*
X1240154Y966634D01*
X1239532Y966013D01*
X1238813Y966012D01*
X1237069Y967756D01*
X1235295D01*
X1233935Y966396D01*
Y964620D01*
X1235678Y962876D01*
X1235679Y962159D01*
X1235057Y961538D01*
X1234338Y961537D01*
X1232594Y963281D01*
X1230820D01*
X1229460Y961921D01*
Y960145D01*
X1231203Y958401D01*
X1231204Y957684D01*
X1230582Y957063D01*
X1229863Y957062D01*
X1228119Y958806D01*
X1226345D01*
X1224952Y957413D01*
Y953367D01*
X1219287Y947702D01*
Y944498D01*
X1214577Y939788D01*
X1213314D01*
X1212216Y940886D01*
X1210111D01*
G01X1277046Y971170D02*
X1240506D01*
X1239680Y970344D01*
Y969622D01*
X1241424Y967878D01*
X1241425Y966108D01*
X1240059Y964742D01*
X1238287Y964741D01*
X1236542Y966486D01*
X1235822D01*
X1235205Y965869D01*
Y965147D01*
X1236949Y963403D01*
X1236950Y961633D01*
X1235584Y960267D01*
X1233812Y960266D01*
X1232067Y962011D01*
X1231347D01*
X1230730Y961394D01*
Y960672D01*
X1232474Y958928D01*
X1232475Y957158D01*
X1231109Y955792D01*
X1229337Y955791D01*
X1227592Y957536D01*
X1226872D01*
X1226222Y956886D01*
Y952840D01*
X1220557Y947175D01*
Y943971D01*
X1215104Y938518D01*
X1213194D01*
X1212216Y937540D01*
X1210111D01*
G01X1276849Y1067256D02*
X1271161D01*
X1265948Y1062043D01*
X1264943D01*
X1264433Y1062553D01*
Y1063475D01*
X1263180Y1064728D01*
X1261255D01*
X1260002Y1063475D01*
Y1062553D01*
X1259492Y1062043D01*
X1258621D01*
X1258111Y1062553D01*
Y1063475D01*
X1256858Y1064728D01*
X1254933D01*
X1253680Y1063475D01*
Y1062553D01*
X1253170Y1062043D01*
X1252299D01*
X1251789Y1062553D01*
Y1063475D01*
X1250536Y1064728D01*
X1248611D01*
X1247358Y1063475D01*
Y1062553D01*
X1246848Y1062043D01*
X1245977D01*
X1245467Y1062553D01*
Y1063475D01*
X1244214Y1064728D01*
X1242289D01*
X1241036Y1063475D01*
Y1062553D01*
X1240526Y1062043D01*
X1239622D01*
X1237864Y1063801D01*
Y1065921D01*
X1236312Y1067473D01*
X1234192D01*
X1233389Y1068276D01*
Y1070396D01*
X1231837Y1071948D01*
X1229717D01*
X1228914Y1072751D01*
Y1074871D01*
X1227362Y1076423D01*
X1225242D01*
X1224439Y1077226D01*
Y1079346D01*
X1222887Y1080898D01*
X1220767D01*
X1219964Y1081701D01*
Y1083821D01*
X1218412Y1085373D01*
X1216292D01*
X1214573Y1087092D01*
X1213254D01*
X1212216Y1088130D01*
X1210111D01*
G01X1276849Y1065986D02*
X1271688D01*
X1266475Y1060773D01*
X1264416D01*
X1263163Y1062026D01*
Y1062948D01*
X1262653Y1063458D01*
X1261782D01*
X1261272Y1062948D01*
Y1062026D01*
X1260019Y1060773D01*
X1258094D01*
X1256841Y1062026D01*
Y1062948D01*
X1256331Y1063458D01*
X1255460D01*
X1254950Y1062948D01*
Y1062026D01*
X1253697Y1060773D01*
X1251772D01*
X1250519Y1062026D01*
Y1062948D01*
X1250009Y1063458D01*
X1249138D01*
X1248628Y1062948D01*
Y1062026D01*
X1247375Y1060773D01*
X1245450D01*
X1244197Y1062026D01*
Y1062948D01*
X1243687Y1063458D01*
X1242816D01*
X1242306Y1062948D01*
Y1062026D01*
X1241053Y1060773D01*
X1239095D01*
X1236594Y1063274D01*
Y1065394D01*
X1235785Y1066203D01*
X1233665D01*
X1232119Y1067749D01*
Y1069869D01*
X1231310Y1070678D01*
X1229190D01*
X1227644Y1072224D01*
Y1074344D01*
X1226835Y1075153D01*
X1224715D01*
X1223169Y1076699D01*
Y1078819D01*
X1222360Y1079628D01*
X1220240D01*
X1218694Y1081174D01*
Y1083294D01*
X1217885Y1084103D01*
X1215765D01*
X1214046Y1085822D01*
X1213254D01*
X1212216Y1084784D01*
X1210111D01*
G01X1275707Y1085133D02*
X1274934D01*
X1273879Y1086188D01*
X1271048D01*
X1269993Y1085133D01*
X1268612D01*
X1267557Y1086188D01*
X1264726D01*
X1263671Y1085133D01*
X1262290D01*
X1261235Y1086188D01*
X1258404D01*
X1257349Y1085133D01*
X1255968D01*
X1254913Y1086188D01*
X1252082D01*
X1251027Y1085133D01*
X1249989D01*
X1248899Y1086223D01*
Y1086945D01*
X1249293Y1087339D01*
Y1089111D01*
X1247928Y1090476D01*
X1246156D01*
X1245762Y1090082D01*
X1245040D01*
X1244424Y1090698D01*
Y1091420D01*
X1244818Y1091814D01*
Y1093586D01*
X1243453Y1094951D01*
X1241681D01*
X1241287Y1094557D01*
X1240565D01*
X1239949Y1095173D01*
Y1095895D01*
X1240343Y1096289D01*
Y1098061D01*
X1238978Y1099426D01*
X1237206D01*
X1236812Y1099032D01*
X1236090D01*
X1235474Y1099648D01*
Y1100370D01*
X1235868Y1100764D01*
Y1102536D01*
X1234503Y1103901D01*
X1232731D01*
X1232337Y1103507D01*
X1231615D01*
X1230999Y1104123D01*
Y1104845D01*
X1231393Y1105239D01*
Y1107011D01*
X1230028Y1108376D01*
X1228256D01*
X1227862Y1107982D01*
X1227140D01*
X1226524Y1108598D01*
Y1109320D01*
X1226918Y1109714D01*
Y1111486D01*
X1225553Y1112851D01*
X1223781D01*
X1223387Y1112457D01*
X1222665D01*
X1222049Y1113073D01*
Y1113795D01*
X1222443Y1114189D01*
Y1115961D01*
X1221078Y1117326D01*
X1219306D01*
X1218912Y1116932D01*
X1218190D01*
X1216846Y1118276D01*
Y1121877D01*
X1214820Y1123903D01*
X1213254D01*
X1212216Y1124941D01*
X1210111D01*
G01X1275707Y1083863D02*
X1274407D01*
X1273352Y1084918D01*
X1271575D01*
X1270520Y1083863D01*
X1268085D01*
X1267030Y1084918D01*
X1265253D01*
X1264198Y1083863D01*
X1261763D01*
X1260708Y1084918D01*
X1258931D01*
X1257876Y1083863D01*
X1255441D01*
X1254386Y1084918D01*
X1252609D01*
X1251554Y1083863D01*
X1249462D01*
X1247629Y1085696D01*
Y1087472D01*
X1248023Y1087866D01*
Y1088584D01*
X1247401Y1089206D01*
X1246683D01*
X1246289Y1088812D01*
X1244513D01*
X1243154Y1090171D01*
Y1091947D01*
X1243548Y1092341D01*
Y1093059D01*
X1242926Y1093681D01*
X1242208D01*
X1241814Y1093287D01*
X1240038D01*
X1238679Y1094646D01*
Y1096422D01*
X1239073Y1096816D01*
Y1097534D01*
X1238451Y1098156D01*
X1237733D01*
X1237339Y1097762D01*
X1235563D01*
X1234204Y1099121D01*
Y1100897D01*
X1234598Y1101291D01*
Y1102009D01*
X1233976Y1102631D01*
X1233258D01*
X1232864Y1102237D01*
X1231088D01*
X1229729Y1103596D01*
Y1105372D01*
X1230123Y1105766D01*
Y1106484D01*
X1229501Y1107106D01*
X1228783D01*
X1228389Y1106712D01*
X1226613D01*
X1225254Y1108071D01*
Y1109847D01*
X1225648Y1110241D01*
Y1110959D01*
X1225026Y1111581D01*
X1224308D01*
X1223914Y1111187D01*
X1222138D01*
X1220779Y1112546D01*
Y1114322D01*
X1221173Y1114716D01*
Y1115434D01*
X1220551Y1116056D01*
X1219833D01*
X1219439Y1115662D01*
X1217663D01*
X1215576Y1117749D01*
Y1121350D01*
X1214293Y1122633D01*
X1213254D01*
X1212216Y1121595D01*
X1210111D01*
G01X1275181Y1104875D02*
X1261644D01*
X1260453Y1106066D01*
Y1108232D01*
X1258924Y1109761D01*
X1256758D01*
X1255978Y1110541D01*
Y1112707D01*
X1254449Y1114236D01*
X1252283D01*
X1251503Y1115016D01*
Y1117182D01*
X1249974Y1118711D01*
X1247808D01*
X1247028Y1119491D01*
Y1121657D01*
X1245499Y1123186D01*
X1243333D01*
X1242553Y1123966D01*
Y1126132D01*
X1241024Y1127661D01*
X1238858D01*
X1238078Y1128441D01*
Y1130607D01*
X1236549Y1132136D01*
X1234383D01*
X1233146Y1133373D01*
Y1134971D01*
X1231667Y1136450D01*
Y1137605D01*
X1233146Y1139084D01*
Y1147069D01*
X1231275Y1148940D01*
X1229123D01*
X1228330Y1149733D01*
Y1151885D01*
X1223869Y1156346D01*
X1222093D01*
X1218817Y1153070D01*
X1218098Y1153071D01*
X1217476Y1153692D01*
X1217477Y1154409D01*
X1220754Y1157686D01*
Y1159461D01*
X1219501Y1160714D01*
X1213254D01*
X1212216Y1161752D01*
X1210111D01*
G01X1275181Y1103605D02*
X1261117D01*
X1259183Y1105539D01*
Y1107705D01*
X1258397Y1108491D01*
X1256231D01*
X1254708Y1110014D01*
Y1112180D01*
X1253922Y1112966D01*
X1251756D01*
X1250233Y1114489D01*
Y1116655D01*
X1249447Y1117441D01*
X1247281D01*
X1245758Y1118964D01*
Y1121130D01*
X1244972Y1121916D01*
X1242806D01*
X1241283Y1123439D01*
Y1125605D01*
X1240497Y1126391D01*
X1238331D01*
X1236808Y1127914D01*
Y1130080D01*
X1236022Y1130866D01*
X1233856D01*
X1231876Y1132846D01*
Y1134444D01*
X1230397Y1135923D01*
Y1138132D01*
X1231876Y1139611D01*
Y1146542D01*
X1230748Y1147670D01*
X1228596D01*
X1227060Y1149206D01*
Y1151358D01*
X1223342Y1155076D01*
X1222620D01*
X1219343Y1151799D01*
X1217571Y1151800D01*
X1216205Y1153166D01*
X1216206Y1154936D01*
X1219484Y1158214D01*
Y1158934D01*
X1218974Y1159444D01*
X1213254D01*
X1212216Y1158406D01*
X1210111D01*
G01X1275181Y1124275D02*
X1269039D01*
X1250593Y1142721D01*
Y1161218D01*
X1249432Y1162379D01*
Y1163101D01*
X1250227Y1163896D01*
Y1165668D01*
X1248862Y1167033D01*
X1247090D01*
X1246295Y1166238D01*
X1245573D01*
X1244957Y1166854D01*
Y1167576D01*
X1245752Y1168371D01*
Y1170143D01*
X1244387Y1171508D01*
X1242615D01*
X1241820Y1170713D01*
X1241098D01*
X1240482Y1171329D01*
Y1172051D01*
X1241277Y1172846D01*
Y1174618D01*
X1239912Y1175983D01*
X1238140D01*
X1237345Y1175188D01*
X1236623D01*
X1236007Y1175804D01*
Y1176526D01*
X1236802Y1177321D01*
Y1179093D01*
X1235437Y1180458D01*
X1233665D01*
X1232870Y1179663D01*
X1232148D01*
X1231532Y1180279D01*
Y1181001D01*
X1232327Y1181796D01*
Y1183568D01*
X1230962Y1184933D01*
X1229190D01*
X1228395Y1184138D01*
X1227673D01*
X1227057Y1184754D01*
Y1185476D01*
X1227852Y1186271D01*
Y1188043D01*
X1226487Y1189408D01*
X1224715D01*
X1223920Y1188613D01*
X1223198D01*
X1222582Y1189229D01*
Y1189951D01*
X1223377Y1190746D01*
Y1192518D01*
X1222012Y1193883D01*
X1220240D01*
X1219445Y1193088D01*
X1218723D01*
X1214286Y1197525D01*
X1212954D01*
X1211916Y1198563D01*
X1210111D01*
G01X1275181Y1123005D02*
X1268512D01*
X1249323Y1142194D01*
Y1160691D01*
X1248162Y1161852D01*
Y1163628D01*
X1248957Y1164423D01*
Y1165141D01*
X1248335Y1165763D01*
X1247617D01*
X1246822Y1164968D01*
X1245046D01*
X1243687Y1166327D01*
Y1168103D01*
X1244482Y1168898D01*
Y1169616D01*
X1243860Y1170238D01*
X1243142D01*
X1242347Y1169443D01*
X1240571D01*
X1239212Y1170802D01*
Y1172578D01*
X1240007Y1173373D01*
Y1174091D01*
X1239385Y1174713D01*
X1238667D01*
X1237872Y1173918D01*
X1236096D01*
X1234737Y1175277D01*
Y1177053D01*
X1235532Y1177848D01*
Y1178566D01*
X1234910Y1179188D01*
X1234192D01*
X1233397Y1178393D01*
X1231621D01*
X1230262Y1179752D01*
Y1181528D01*
X1231057Y1182323D01*
Y1183041D01*
X1230435Y1183663D01*
X1229717D01*
X1228922Y1182868D01*
X1227146D01*
X1225787Y1184227D01*
Y1186003D01*
X1226582Y1186798D01*
Y1187516D01*
X1225960Y1188138D01*
X1225242D01*
X1224447Y1187343D01*
X1222671D01*
X1221312Y1188702D01*
Y1190478D01*
X1222107Y1191273D01*
Y1191991D01*
X1221485Y1192613D01*
X1220767D01*
X1219972Y1191818D01*
X1218196D01*
X1213759Y1196255D01*
X1212954D01*
X1211916Y1195217D01*
X1210111D01*
G01X1275181Y1143639D02*
X1274715D01*
X1268026Y1150328D01*
Y1176535D01*
X1265100Y1179461D01*
Y1180183D01*
X1266634Y1181717D01*
Y1183489D01*
X1265269Y1184854D01*
X1263497D01*
X1261963Y1183320D01*
X1261241D01*
X1260625Y1183936D01*
Y1184658D01*
X1262159Y1186192D01*
Y1187964D01*
X1260794Y1189329D01*
X1259022D01*
X1257488Y1187795D01*
X1256766D01*
X1256150Y1188411D01*
Y1189133D01*
X1257684Y1190667D01*
Y1192439D01*
X1256319Y1193804D01*
X1254547D01*
X1253013Y1192270D01*
X1252291D01*
X1251675Y1192886D01*
Y1193608D01*
X1253209Y1195142D01*
Y1196914D01*
X1251844Y1198279D01*
X1250072D01*
X1248538Y1196745D01*
X1247816D01*
X1246589Y1197972D01*
Y1203450D01*
X1215703Y1234336D01*
X1213254D01*
X1212216Y1235374D01*
X1210111D01*
G01X1275181Y1142369D02*
X1274188D01*
X1266756Y1149801D01*
Y1176008D01*
X1263830Y1178934D01*
Y1180710D01*
X1265364Y1182244D01*
Y1182962D01*
X1264742Y1183584D01*
X1264024D01*
X1262490Y1182050D01*
X1260714D01*
X1259355Y1183409D01*
Y1185185D01*
X1260889Y1186719D01*
Y1187437D01*
X1260267Y1188059D01*
X1259549D01*
X1258015Y1186525D01*
X1256239D01*
X1254880Y1187884D01*
Y1189660D01*
X1256414Y1191194D01*
Y1191912D01*
X1255792Y1192534D01*
X1255074D01*
X1253540Y1191000D01*
X1251764D01*
X1250405Y1192359D01*
Y1194135D01*
X1251939Y1195669D01*
Y1196387D01*
X1251317Y1197009D01*
X1250599D01*
X1249065Y1195475D01*
X1247289D01*
X1245319Y1197445D01*
Y1202923D01*
X1218274Y1229968D01*
X1217340D01*
X1216257Y1231051D01*
Y1231985D01*
X1215176Y1233066D01*
X1213254D01*
X1212216Y1232028D01*
X1210111D01*
G01X1214224Y1490895D02*
X1213059Y1489730D01*
Y1486960D01*
X1214124Y1485895D01*
G01X1210624Y1490895D02*
X1211789Y1489730D01*
Y1486960D01*
X1210724Y1485895D01*
G01X1207524Y1500595D02*
X1206359Y1499430D01*
Y1496660D01*
X1207424Y1495595D01*
G01X1203924Y1500595D02*
X1205089Y1499430D01*
Y1496660D01*
X1204024Y1495595D01*
G01X1207999Y1640286D02*
X1209164Y1639121D01*
Y1626445D01*
X1208099Y1625380D01*
G01X1211599Y1640286D02*
X1210434Y1639121D01*
Y1626445D01*
X1211499Y1625380D01*
G01X1207999Y1642386D02*
X1209164Y1643551D01*
Y1656227D01*
X1208099Y1657292D01*
G01X1211599Y1642386D02*
X1210434Y1643551D01*
Y1656227D01*
X1211499Y1657292D01*
G01X1227624Y1510295D02*
X1226459Y1509130D01*
Y1506360D01*
X1227524Y1505295D01*
G01X1224024Y1510295D02*
X1225189Y1509130D01*
Y1506360D01*
X1224124Y1505295D01*
G01X1220059Y1640286D02*
X1221224Y1639121D01*
Y1626445D01*
X1220159Y1625380D01*
G01X1223659Y1640286D02*
X1222494Y1639121D01*
Y1626445D01*
X1223559Y1625380D01*
G01X1220059Y1642386D02*
X1221224Y1643551D01*
Y1656227D01*
X1220159Y1657292D01*
G01X1223659Y1642386D02*
X1222494Y1643551D01*
Y1656227D01*
X1223559Y1657292D01*
G01X1243272Y-19027D02*
X1245840Y-18311D01*
G01X1243272Y-20995D02*
X1245840Y-21711D01*
G01X1243272Y973D02*
X1245840Y1689D01*
G01X1243272Y-995D02*
X1245840Y-1711D01*
G01X1438831Y20973D02*
X1438215D01*
X1437866Y20624D01*
X1421821D01*
X1419516Y22237D01*
X1418398Y28569D01*
X1416877Y29637D01*
X1410541Y28515D01*
X1409474Y26994D01*
X1411821Y13710D01*
X1411409Y13121D01*
X1405983Y12162D01*
X1405396Y12573D01*
X1402584Y28490D01*
X1401132Y29508D01*
X1394678Y28366D01*
X1393660Y26914D01*
X1395993Y13709D01*
X1395581Y13120D01*
X1390155Y12161D01*
X1389568Y12572D01*
X1386752Y28508D01*
X1385300Y29526D01*
X1378846Y28384D01*
X1377828Y26932D01*
X1380132Y13892D01*
X1379720Y13304D01*
X1374294Y12345D01*
X1373706Y12756D01*
X1370925Y28496D01*
X1369475Y29515D01*
X1363020Y28372D01*
X1362002Y26920D01*
X1364328Y13757D01*
X1363916Y13168D01*
X1358490Y12209D01*
X1357903Y12620D01*
X1355105Y28458D01*
X1353651Y29476D01*
X1347199Y28334D01*
X1346180Y26884D01*
X1348510Y13698D01*
X1348098Y13110D01*
X1342672Y12151D01*
X1342084Y12562D01*
X1339266Y28508D01*
X1337815Y29527D01*
X1331361Y28385D01*
X1330343Y26933D01*
X1332633Y13971D01*
X1332221Y13382D01*
X1326795Y12423D01*
X1326208Y12834D01*
X1323438Y28507D01*
X1321988Y29526D01*
X1315533Y28383D01*
X1314515Y26931D01*
X1316824Y13861D01*
X1316412Y13272D01*
X1310986Y12313D01*
X1310399Y12724D01*
X1307620Y28454D01*
X1306168Y29472D01*
X1299714Y28330D01*
X1298696Y26878D01*
X1301037Y13629D01*
X1300625Y13041D01*
X1295199Y12082D01*
X1294611Y12493D01*
X1291790Y28456D01*
X1290340Y29475D01*
X1283884Y28334D01*
X1282867Y26879D01*
X1285165Y13873D01*
X1284753Y13284D01*
X1279327Y12325D01*
X1278740Y12736D01*
X1275958Y28484D01*
X1274506Y29502D01*
X1268052Y28360D01*
X1267034Y26908D01*
X1269343Y13841D01*
X1268931Y13253D01*
X1263505Y12294D01*
X1262918Y12705D01*
X1261936Y18262D01*
X1258561Y20624D01*
X1244195D01*
X1243846Y20973D01*
X1243272D01*
G01X1438831Y19005D02*
X1438199D01*
X1437850Y19354D01*
X1421420D01*
X1418356Y21498D01*
X1417238Y27831D01*
X1416579Y28294D01*
X1411280Y27355D01*
X1410817Y26696D01*
X1413164Y13412D01*
X1412149Y11961D01*
X1405686Y10819D01*
X1404236Y11834D01*
X1401424Y27751D01*
X1400834Y28165D01*
X1395417Y27206D01*
X1395003Y26616D01*
X1397336Y13412D01*
X1396321Y11960D01*
X1389858Y10818D01*
X1388408Y11833D01*
X1385592Y27769D01*
X1385002Y28183D01*
X1379585Y27224D01*
X1379171Y26634D01*
X1381475Y13594D01*
X1380459Y12144D01*
X1373997Y11002D01*
X1372546Y12016D01*
X1369765Y27758D01*
X1369176Y28172D01*
X1363759Y27213D01*
X1363345Y26622D01*
X1365671Y13460D01*
X1364656Y12008D01*
X1358193Y10866D01*
X1356743Y11881D01*
X1353945Y27719D01*
X1353354Y28133D01*
X1347937Y27174D01*
X1347523Y26585D01*
X1349853Y13400D01*
X1348837Y11950D01*
X1342375Y10808D01*
X1340924Y11822D01*
X1338106Y27770D01*
X1337517Y28184D01*
X1332100Y27225D01*
X1331686Y26635D01*
X1333976Y13674D01*
X1332961Y12222D01*
X1326498Y11080D01*
X1325048Y12095D01*
X1322278Y27769D01*
X1321689Y28183D01*
X1316272Y27224D01*
X1315858Y26633D01*
X1318167Y13564D01*
X1317152Y12112D01*
X1310689Y10970D01*
X1309239Y11985D01*
X1306460Y27715D01*
X1305870Y28129D01*
X1300453Y27170D01*
X1300039Y26580D01*
X1302380Y13331D01*
X1301364Y11881D01*
X1294902Y10739D01*
X1293451Y11753D01*
X1290630Y27718D01*
X1290041Y28132D01*
X1284624Y27174D01*
X1284210Y26582D01*
X1286508Y13576D01*
X1285493Y12124D01*
X1279030Y10982D01*
X1277580Y11997D01*
X1274798Y27745D01*
X1274208Y28159D01*
X1268791Y27200D01*
X1268377Y26610D01*
X1270686Y13544D01*
X1269671Y12093D01*
X1263208Y10951D01*
X1261758Y11966D01*
X1260776Y17523D01*
X1258160Y19354D01*
X1244277D01*
X1243928Y19005D01*
X1243272D01*
G01X1241024Y1490895D02*
X1239859Y1489730D01*
Y1486960D01*
X1240924Y1485895D01*
G01X1237424Y1490895D02*
X1238589Y1489730D01*
Y1486960D01*
X1237524Y1485895D01*
G01X1234324Y1500595D02*
X1233159Y1499430D01*
Y1496660D01*
X1234224Y1495595D01*
G01X1230724Y1500595D02*
X1231889Y1499430D01*
Y1496660D01*
X1230824Y1495595D01*
G01X1232119Y1640286D02*
X1233284Y1639121D01*
Y1626445D01*
X1232219Y1625380D01*
G01X1244179Y1640286D02*
X1245344Y1639121D01*
Y1626445D01*
X1244279Y1625380D01*
G01X1235719Y1640286D02*
X1234554Y1639121D01*
Y1626445D01*
X1235619Y1625380D01*
G01X1232119Y1642386D02*
X1233284Y1643551D01*
Y1656227D01*
X1232219Y1657292D01*
G01X1244179Y1642386D02*
X1245344Y1643551D01*
Y1656227D01*
X1244279Y1657292D01*
G01X1235719Y1642386D02*
X1234554Y1643551D01*
Y1656227D01*
X1235619Y1657292D01*
G01X1254424Y1510295D02*
X1253259Y1509130D01*
Y1506360D01*
X1254324Y1505295D01*
G01X1250824Y1510295D02*
X1251989Y1509130D01*
Y1506360D01*
X1250924Y1505295D01*
G01X1257524Y1500595D02*
X1258689Y1499430D01*
Y1496660D01*
X1257624Y1495595D01*
G01X1256339Y1625380D02*
X1257404Y1626445D01*
Y1639121D01*
X1256239Y1640286D01*
G01X1247779D02*
X1246614Y1639121D01*
Y1626445D01*
X1247679Y1625380D01*
G01X1259739D02*
X1258674Y1626445D01*
Y1639121D01*
X1259839Y1640286D01*
G01X1256239Y1642386D02*
X1257404Y1643551D01*
Y1656227D01*
X1256339Y1657292D01*
G01X1247779Y1642386D02*
X1246614Y1643551D01*
Y1656227D01*
X1247679Y1657292D01*
G01X1259839Y1642386D02*
X1258674Y1643551D01*
Y1656227D01*
X1259739Y1657292D01*
G01X1267824Y1490895D02*
X1266659Y1489730D01*
Y1486960D01*
X1267724Y1485895D01*
G01X1264224Y1490895D02*
X1265389Y1489730D01*
Y1486960D01*
X1264324Y1485895D01*
G01X1261124Y1500595D02*
X1259959Y1499430D01*
Y1496660D01*
X1261024Y1495595D01*
G01X1268299Y1640286D02*
X1269464Y1639121D01*
Y1626445D01*
X1268399Y1625380D01*
G01X1271899Y1640286D02*
X1270734Y1639121D01*
Y1626445D01*
X1271799Y1625380D01*
G01X1268299Y1642386D02*
X1269464Y1643551D01*
Y1656227D01*
X1268399Y1657292D01*
G01X1271899Y1642386D02*
X1270734Y1643551D01*
Y1656227D01*
X1271799Y1657292D01*
G01X1277624Y1490895D02*
X1278789Y1489730D01*
Y1486960D01*
X1277724Y1485895D01*
G01X1281224Y1490895D02*
X1280059Y1489730D01*
Y1486960D01*
X1281124Y1485895D01*
G01X1283494Y1517182D02*
X1284659Y1516017D01*
X1287429D01*
X1288494Y1517082D01*
G01X1283494Y1513582D02*
X1284659Y1514747D01*
X1287429D01*
X1288494Y1513682D01*
G01X1283494Y1530582D02*
X1284659Y1529417D01*
X1287429D01*
X1288494Y1530482D01*
G01X1283494Y1526982D02*
X1284659Y1528147D01*
X1287429D01*
X1288494Y1527082D01*
G01X1280359Y1640286D02*
X1281524Y1639121D01*
Y1626445D01*
X1280459Y1625380D01*
G01X1283959Y1640286D02*
X1282794Y1639121D01*
Y1626445D01*
X1283859Y1625380D01*
G01X1280359Y1642386D02*
X1281524Y1643551D01*
Y1656227D01*
X1280459Y1657292D01*
G01X1283959Y1642386D02*
X1282794Y1643551D01*
Y1656227D01*
X1283859Y1657292D01*
G01X1297787Y896615D02*
X1295949Y895568D01*
G01X1301488Y896615D02*
X1299650Y895568D01*
G01X1295937Y893426D02*
X1294099Y892379D01*
G01X1303338Y899804D02*
X1301500Y898757D01*
G01X1297787Y915748D02*
X1295949Y914701D01*
G01X1301488Y915748D02*
X1299650Y914701D01*
G01X1295937Y912559D02*
X1294099Y911512D01*
G01X1303338Y918937D02*
X1301500Y917890D01*
G01X1297787Y934882D02*
X1295949Y933835D01*
G01X1301488Y934882D02*
X1299650Y933835D01*
G01X1295937Y931693D02*
X1294099Y930646D01*
G01X1303338Y938071D02*
X1301500Y937024D01*
G01X1297787Y954016D02*
X1295949Y952969D01*
G01X1301488Y954016D02*
X1299650Y952969D01*
G01X1295937Y950827D02*
X1294099Y949780D01*
G01X1295937Y969961D02*
X1294099Y968914D01*
G01X1303338Y957205D02*
X1301500Y956158D01*
G01X1297787Y973150D02*
X1295949Y972103D01*
G01X1301488Y973150D02*
X1299650Y972103D01*
G01X1303338Y976339D02*
X1301500Y975292D01*
G01X1297118Y1030197D02*
X1295280Y1031244D01*
G01X1298968Y1027008D02*
X1297130Y1028055D01*
G01X1304520Y1042953D02*
X1302682Y1044000D01*
G01X1297118Y1055709D02*
X1295280Y1056756D01*
G01X1298968Y1046142D02*
X1297130Y1047189D01*
G01X1302669Y1052520D02*
X1300831Y1053567D01*
G01X1304520Y1068465D02*
X1302681Y1069512D01*
G01X1297118Y1068465D02*
X1295280Y1069512D01*
G01X1302669Y1071654D02*
X1300831Y1072701D01*
G01X1298968Y1065276D02*
X1297130Y1066323D01*
G01X1297118Y1087599D02*
X1295280Y1088646D01*
G01X1304520Y1087599D02*
X1302681Y1088646D01*
G01X1298968Y1084410D02*
X1297130Y1085457D01*
G01X1298968Y1103544D02*
X1297130Y1104591D01*
G01X1302669Y1090788D02*
X1300831Y1091835D01*
G01X1297118Y1106733D02*
X1295280Y1107780D01*
G01X1304520Y1106733D02*
X1302681Y1107780D01*
G01X1302669Y1109922D02*
X1300831Y1110969D01*
G01X1297118Y1125867D02*
X1295280Y1126914D01*
G01X1304520Y1125867D02*
X1302681Y1126914D01*
G01X1298968Y1122678D02*
X1297130Y1123725D01*
G01X1302669Y1129056D02*
X1300831Y1130102D01*
G01X1297118Y1145000D02*
X1295280Y1146047D01*
G01X1304520Y1145000D02*
X1302681Y1146047D01*
G01X1298968Y1141811D02*
X1297130Y1142858D01*
G01X1302669Y1148189D02*
X1300831Y1149236D01*
G01X1302669Y1160945D02*
X1300831Y1161992D01*
G01X1304520Y1164134D02*
X1302682Y1165181D01*
G01X1304048Y1516690D02*
X1302883Y1515525D01*
X1300113D01*
X1299048Y1516590D01*
G01X1304048Y1513090D02*
X1302883Y1514255D01*
X1300113D01*
X1299048Y1513190D01*
G01X1304048Y1534890D02*
X1302883Y1536055D01*
X1300113D01*
X1299048Y1534990D01*
G01X1304048Y1538490D02*
X1302883Y1537325D01*
X1300113D01*
X1299048Y1538390D01*
G01X1298466Y1556331D02*
X1299531Y1557396D01*
X1301353D01*
X1302318Y1556431D01*
G01X1298466Y1559731D02*
X1299531Y1558666D01*
X1301353D01*
X1302318Y1559631D01*
G01X1292419Y1640286D02*
X1293584Y1639121D01*
Y1626445D01*
X1292519Y1625380D01*
G01X1296019Y1640286D02*
X1294854Y1639121D01*
Y1626445D01*
X1295919Y1625380D01*
G01X1292419Y1642386D02*
X1293584Y1643551D01*
Y1656227D01*
X1292519Y1657292D01*
G01X1296019Y1642386D02*
X1294854Y1643551D01*
Y1656227D01*
X1295919Y1657292D01*
G01X1308890Y896615D02*
X1307052Y895568D01*
G01X1316291Y896615D02*
X1314453Y895568D01*
G01X1310740Y893426D02*
X1308902Y892379D01*
G01X1314441Y899804D02*
X1312603Y898757D01*
G01X1308890Y915748D02*
X1307052Y914701D01*
G01X1316291Y915748D02*
X1314453Y914701D01*
G01X1310740Y912559D02*
X1308902Y911512D01*
G01X1314441Y918937D02*
X1312603Y917890D01*
G01X1308890Y934882D02*
X1307052Y933835D01*
G01X1316291Y934882D02*
X1314453Y933835D01*
G01X1310740Y931693D02*
X1308902Y930646D01*
G01X1314441Y938071D02*
X1312603Y937024D01*
G01X1308890Y954016D02*
X1307052Y952969D01*
G01X1316291Y954016D02*
X1314453Y952969D01*
G01X1310740Y950827D02*
X1308902Y949780D01*
G01X1310740Y969961D02*
X1308902Y968914D01*
G01X1314441Y957205D02*
X1312603Y956158D01*
G01X1308890Y973150D02*
X1307052Y972103D01*
G01X1316291Y973150D02*
X1314453Y972103D01*
G01X1314441Y976339D02*
X1312603Y975292D01*
G01X1311921Y1030197D02*
X1310083Y1031244D01*
G01X1310071Y1027008D02*
X1308233Y1028055D01*
G01X1315622Y1042953D02*
X1313784Y1044000D01*
G01X1311921Y1055709D02*
X1310083Y1056756D01*
G01X1310071Y1046142D02*
X1308233Y1047189D01*
G01X1317472Y1052520D02*
X1315634Y1053567D01*
G01X1315622Y1068465D02*
X1313784Y1069512D01*
G01X1311921Y1068465D02*
X1310083Y1069512D01*
G01X1317472Y1071654D02*
X1315634Y1072701D01*
G01X1310071Y1065276D02*
X1308233Y1066323D01*
G01X1311921Y1087599D02*
X1310083Y1088646D01*
G01X1315622Y1087599D02*
X1313784Y1088646D01*
G01X1310071Y1084410D02*
X1308233Y1085457D01*
G01X1310071Y1103544D02*
X1308233Y1104591D01*
G01X1317472Y1090788D02*
X1315634Y1091835D01*
G01X1311921Y1106733D02*
X1310083Y1107780D01*
G01X1315622Y1106733D02*
X1313784Y1107780D01*
G01X1317472Y1109922D02*
X1315634Y1110969D01*
G01X1311921Y1125867D02*
X1310083Y1126914D01*
G01X1315622Y1125867D02*
X1313784Y1126914D01*
G01X1310071Y1122678D02*
X1308233Y1123725D01*
G01X1317472Y1129056D02*
X1315634Y1130102D01*
G01X1311921Y1145000D02*
X1310083Y1146047D01*
G01X1315622Y1145000D02*
X1313784Y1146047D01*
G01X1310071Y1141811D02*
X1308233Y1142858D01*
G01X1317472Y1148189D02*
X1315634Y1149236D01*
G01X1310071Y1160945D02*
X1308233Y1161992D01*
G01X1311921Y1164134D02*
X1310083Y1165181D01*
G01X1317472Y1160945D02*
X1315634Y1161992D01*
G01X1319323Y1164134D02*
X1317485Y1165181D01*
G01X1315486Y1490895D02*
X1314321Y1489730D01*
Y1486960D01*
X1315386Y1485895D01*
G01X1311886Y1490895D02*
X1313051Y1489730D01*
Y1486960D01*
X1311986Y1485895D01*
G01X1308786Y1500595D02*
X1307621Y1499430D01*
Y1496660D01*
X1308686Y1495595D01*
G01X1305186Y1500595D02*
X1306351Y1499430D01*
Y1496660D01*
X1305286Y1495595D01*
G01X1304418Y1556431D02*
X1305380Y1557393D01*
X1306406D01*
X1307368Y1556431D01*
G01D02*
X1308285Y1557348D01*
X1310353D01*
X1311570Y1558565D01*
X1313904D01*
G01X1304418Y1559631D02*
X1305386Y1558663D01*
X1306400D01*
X1307368Y1559631D01*
G01D02*
X1308381Y1558618D01*
X1309826D01*
X1311043Y1559835D01*
X1313979D01*
G01X1316539Y1640286D02*
X1317704Y1639121D01*
Y1626445D01*
X1316639Y1625380D01*
G01X1304479Y1640286D02*
X1305644Y1639121D01*
Y1626445D01*
X1304579Y1625380D01*
G01X1308079Y1640286D02*
X1306914Y1639121D01*
Y1626445D01*
X1307979Y1625380D01*
G01X1320139Y1640286D02*
X1318974Y1639121D01*
Y1626445D01*
X1320039Y1625380D01*
G01X1316539Y1642386D02*
X1317704Y1643551D01*
Y1656227D01*
X1316639Y1657292D01*
G01X1304479Y1642386D02*
X1305644Y1643551D01*
Y1656227D01*
X1304579Y1657292D01*
G01X1320139Y1642386D02*
X1318974Y1643551D01*
Y1656227D01*
X1320039Y1657292D01*
G01X1308079Y1642386D02*
X1306914Y1643551D01*
Y1656227D01*
X1307979Y1657292D01*
G01X1480976Y874292D02*
X1482192Y873076D01*
Y871103D01*
X1480536Y869447D01*
X1438423Y865299D01*
X1368912D01*
X1336052Y862063D01*
X1334177Y860188D01*
Y857748D01*
X1332812Y856383D01*
G01X1323693Y896615D02*
X1321855Y895568D01*
G01X1327394Y896615D02*
X1325556Y895568D01*
G01X1321842Y893426D02*
X1320004Y892379D01*
G01X1334795Y896615D02*
X1332957Y895568D01*
G01X1329244Y899804D02*
X1327406Y898757D01*
G01X1323693Y915748D02*
X1321855Y914701D01*
G01X1327394Y915748D02*
X1325556Y914701D01*
G01X1321842Y912559D02*
X1320004Y911512D01*
G01X1329244Y918937D02*
X1327406Y917890D01*
G01X1334795Y915748D02*
X1332957Y914701D01*
G01X1323693Y934882D02*
X1321855Y933835D01*
G01X1327394Y934882D02*
X1325556Y933835D01*
G01X1321842Y931693D02*
X1320004Y930646D01*
G01X1329244Y938071D02*
X1327406Y937024D01*
G01X1334795Y934882D02*
X1332957Y933835D01*
G01X1323693Y954016D02*
X1321855Y952969D01*
G01X1327394Y954016D02*
X1325556Y952969D01*
G01X1321842Y950827D02*
X1320004Y949780D01*
G01X1334795Y954016D02*
X1332957Y952969D01*
G01X1321842Y969961D02*
X1320004Y968914D01*
G01X1329244Y957205D02*
X1327406Y956158D01*
G01X1323693Y973150D02*
X1321855Y972103D01*
G01X1327394Y973150D02*
X1325556Y972103D01*
G01X1329244Y976339D02*
X1327406Y975292D01*
G01X1334795Y973150D02*
X1332957Y972103D01*
G01X1323023Y1030197D02*
X1321185Y1031244D01*
G01X1324874Y1027008D02*
X1323036Y1028055D01*
G01X1330425Y1042953D02*
X1328587Y1044000D01*
G01X1323023Y1055709D02*
X1321185Y1056756D01*
G01X1324874Y1046142D02*
X1323036Y1047189D01*
G01X1328575Y1052520D02*
X1326737Y1053567D01*
G01X1330425Y1068465D02*
X1328587Y1069512D01*
G01X1323023Y1068465D02*
X1321185Y1069512D01*
G01X1328575Y1071654D02*
X1326737Y1072701D01*
G01X1324874Y1065276D02*
X1323036Y1066323D01*
G01X1323023Y1087599D02*
X1321185Y1088646D01*
G01X1330425Y1087599D02*
X1328587Y1088646D01*
G01X1324874Y1084410D02*
X1323036Y1085457D01*
G01X1324874Y1103544D02*
X1323036Y1104591D01*
G01X1328575Y1090788D02*
X1326737Y1091835D01*
G01X1323023Y1106733D02*
X1321185Y1107780D01*
G01X1330425Y1106733D02*
X1328587Y1107780D01*
G01X1328575Y1109922D02*
X1326737Y1110969D01*
G01X1323023Y1125867D02*
X1321185Y1126914D01*
G01X1330425Y1125867D02*
X1328587Y1126914D01*
G01X1324874Y1122678D02*
X1323036Y1123725D01*
G01X1328575Y1129056D02*
X1326737Y1130102D01*
G01X1323023Y1145000D02*
X1321185Y1146047D01*
G01X1330425Y1145000D02*
X1328587Y1146047D01*
G01X1324874Y1141811D02*
X1323036Y1142858D01*
G01X1328575Y1148189D02*
X1326737Y1149236D01*
G01X1417711Y1258791D02*
X1418826Y1257676D01*
Y1254571D01*
X1399097Y1234842D01*
X1352127D01*
X1333712Y1216427D01*
Y1206087D01*
X1331742Y1201322D01*
Y1176999D01*
X1336011Y1172730D01*
X1356978D01*
X1361247Y1168461D01*
Y1165350D01*
X1360031Y1164134D01*
G01X1421211Y1258791D02*
X1420096Y1257676D01*
Y1254044D01*
X1399624Y1233572D01*
X1352654D01*
X1334982Y1215900D01*
Y1205834D01*
X1333012Y1201069D01*
Y1177526D01*
X1336538Y1174000D01*
X1357505D01*
X1362517Y1168988D01*
Y1165349D01*
X1363732Y1164134D01*
G01X1328886Y1510295D02*
X1327721Y1509130D01*
Y1506360D01*
X1328786Y1505295D01*
G01X1325286Y1510295D02*
X1326451Y1509130D01*
Y1506360D01*
X1325386Y1505295D01*
G01X1331986Y1500595D02*
X1333151Y1499430D01*
Y1496660D01*
X1332086Y1495595D01*
G01X1328599Y1640286D02*
X1329764Y1639121D01*
Y1626445D01*
X1328699Y1625380D01*
G01X1332199Y1640286D02*
X1331034Y1639121D01*
Y1626445D01*
X1332099Y1625380D01*
G01X1328599Y1642386D02*
X1329764Y1643551D01*
Y1656227D01*
X1328699Y1657292D01*
G01X1332199Y1642386D02*
X1331034Y1643551D01*
Y1656227D01*
X1332099Y1657292D01*
G01X1484677Y874292D02*
X1483462Y873077D01*
Y870576D01*
X1481113Y868227D01*
X1438486Y864029D01*
X1368975D01*
X1336629Y860843D01*
X1335447Y859661D01*
Y857748D01*
X1336812Y856383D01*
G01X1349598Y896615D02*
X1347760Y895568D01*
G01X1347748Y893426D02*
X1345910Y892379D01*
G01X1342197Y896615D02*
X1340359Y895568D01*
G01X1336646Y893426D02*
X1334807Y892379D01*
G01X1340346Y899804D02*
X1338508Y898757D01*
G01X1349598Y915748D02*
X1347760Y914701D01*
G01X1347748Y912559D02*
X1345910Y911512D01*
G01X1342197Y915748D02*
X1340359Y914701D01*
G01X1336646Y912559D02*
X1334807Y911512D01*
G01X1340346Y918937D02*
X1338508Y917890D01*
G01X1349598Y934882D02*
X1347760Y933835D01*
G01X1347748Y931693D02*
X1345910Y930646D01*
G01X1342197Y934882D02*
X1340359Y933835D01*
G01X1336646Y931693D02*
X1334807Y930646D01*
G01X1340346Y938071D02*
X1338508Y937024D01*
G01X1349598Y954016D02*
X1347760Y952969D01*
G01X1347748Y950827D02*
X1345910Y949780D01*
G01X1342197Y954016D02*
X1340359Y952969D01*
G01X1336646Y950827D02*
X1334807Y949780D01*
G01X1347748Y969961D02*
X1345910Y968914D01*
G01X1336646Y969961D02*
X1334807Y968914D01*
G01X1340346Y957205D02*
X1338508Y956158D01*
G01X1349598Y973150D02*
X1347760Y972103D01*
G01X1342197Y973150D02*
X1340359Y972103D01*
G01X1340346Y976339D02*
X1338508Y975292D01*
G01X1341527Y1042953D02*
X1339689Y1044000D01*
G01X1337827Y1055709D02*
X1335989Y1056756D01*
G01X1335976Y1046142D02*
X1334138Y1047189D01*
G01X1343378Y1052520D02*
X1341540Y1053567D01*
G01X1348929Y1055709D02*
X1347091Y1056756D01*
G01X1348929Y1068465D02*
X1347091Y1069512D01*
G01X1341527Y1068465D02*
X1339689Y1069512D01*
G01X1337827Y1068465D02*
X1335989Y1069512D01*
G01X1343378Y1071654D02*
X1341540Y1072701D01*
G01X1335976Y1065276D02*
X1334138Y1066323D01*
G01X1348929Y1087599D02*
X1347091Y1088646D01*
G01X1337827Y1087599D02*
X1335989Y1088646D01*
G01X1341527Y1087599D02*
X1339689Y1088646D01*
G01X1335976Y1084410D02*
X1334138Y1085457D01*
G01X1335976Y1103544D02*
X1334138Y1104591D01*
G01X1343378Y1090788D02*
X1341540Y1091835D01*
G01X1348929Y1106733D02*
X1347091Y1107780D01*
G01X1337827Y1106733D02*
X1335989Y1107780D01*
G01X1341527Y1106733D02*
X1339689Y1107780D01*
G01X1343378Y1109922D02*
X1341540Y1110969D01*
G01X1348929Y1125867D02*
X1347091Y1126914D01*
G01X1337827Y1125867D02*
X1335989Y1126914D01*
G01X1341527Y1125867D02*
X1339689Y1126914D01*
G01X1335976Y1122678D02*
X1334138Y1123725D01*
G01X1343378Y1129056D02*
X1341540Y1130102D01*
G01X1348929Y1145000D02*
X1347091Y1146047D01*
G01X1337827Y1145000D02*
X1335989Y1146047D01*
G01X1341527Y1145000D02*
X1339689Y1146047D01*
G01X1335976Y1141811D02*
X1334138Y1142858D01*
G01X1343378Y1148189D02*
X1341540Y1149236D01*
G01X1337827Y1164134D02*
X1335989Y1165181D01*
G01X1335976Y1160945D02*
X1334138Y1161992D01*
G01X1345228Y1157756D02*
X1343390Y1158803D01*
G01X1343378Y1160945D02*
X1341540Y1161992D01*
G01X1393338Y1164134D02*
X1394554Y1165350D01*
Y1166072D01*
X1385614Y1175012D01*
X1375658Y1179136D01*
X1342403D01*
X1340948Y1177681D01*
G01X1397039Y1164134D02*
X1395824Y1165349D01*
Y1166599D01*
X1386334Y1176089D01*
X1375911Y1180406D01*
X1342223D01*
X1340948Y1181681D01*
G01X1404441Y1164134D02*
X1405657Y1165350D01*
Y1167737D01*
X1397220Y1176174D01*
X1350226Y1195640D01*
X1344947Y1200919D01*
Y1206456D01*
X1358059Y1219568D01*
X1396976D01*
X1439897Y1262489D01*
Y1273820D01*
X1438532Y1275185D01*
G01X1408142Y1164134D02*
X1406927Y1165349D01*
Y1168264D01*
X1397940Y1177251D01*
X1350946Y1196717D01*
X1346217Y1201446D01*
Y1205929D01*
X1358586Y1218298D01*
X1397503D01*
X1441167Y1261962D01*
Y1273820D01*
X1442532Y1275185D01*
G01X1342286Y1490895D02*
X1341121Y1489730D01*
Y1486960D01*
X1342186Y1485895D01*
G01X1338686Y1490895D02*
X1339851Y1489730D01*
Y1486960D01*
X1338786Y1485895D01*
G01X1335586Y1500595D02*
X1334421Y1499430D01*
Y1496660D01*
X1335486Y1495595D01*
G01X1340659Y1640286D02*
X1341824Y1639121D01*
Y1626445D01*
X1340759Y1625380D01*
G01X1344259Y1640286D02*
X1343094Y1639121D01*
Y1626445D01*
X1344159Y1625380D01*
G01X1340659Y1642386D02*
X1341824Y1643551D01*
Y1656227D01*
X1340759Y1657292D01*
G01X1344259Y1642386D02*
X1343094Y1643551D01*
Y1656227D01*
X1344159Y1657292D01*
G01X1362551Y893426D02*
X1360713Y892379D01*
G01X1353299Y896615D02*
X1351461Y895568D01*
G01X1362551Y906181D02*
X1360713Y905134D01*
G01X1362551Y899804D02*
X1360713Y898757D01*
G01X1355149Y899804D02*
X1353311Y898757D01*
G01X1362551Y912559D02*
X1360713Y911512D01*
G01X1362551Y918937D02*
X1360713Y917890D01*
G01X1362551Y925315D02*
X1360713Y924268D01*
G01X1353299Y915748D02*
X1351461Y914701D01*
G01X1355149Y918937D02*
X1353311Y917890D01*
G01X1362551Y931693D02*
X1360713Y930646D01*
G01X1353299Y934882D02*
X1351461Y933835D01*
G01X1355149Y938071D02*
X1353311Y937024D01*
G01X1362551Y944449D02*
X1360713Y943402D01*
G01X1362551Y950827D02*
X1360713Y949780D01*
G01X1353299Y954016D02*
X1351461Y952969D01*
G01X1362551Y957205D02*
X1360713Y956158D01*
G01X1362551Y963583D02*
X1360713Y962536D01*
G01X1362551Y969961D02*
X1360713Y968914D01*
G01X1355149Y957205D02*
X1353311Y956158D01*
G01X1362551Y976339D02*
X1360713Y975292D01*
G01X1353299Y973150D02*
X1351461Y972103D01*
G01X1355149Y976339D02*
X1353311Y975292D01*
G01X1356331Y1042953D02*
X1354493Y1044000D01*
G01X1350779Y1046142D02*
X1348941Y1047189D01*
G01X1354480Y1052520D02*
X1352642Y1053567D01*
G01X1356331Y1068465D02*
X1354493Y1069512D01*
G01X1354480Y1071654D02*
X1352642Y1072701D01*
G01X1350779Y1065276D02*
X1348941Y1066323D01*
G01X1363732Y1068465D02*
X1361894Y1069512D01*
G01X1363732Y1062087D02*
X1361894Y1063134D01*
G01X1356331Y1087599D02*
X1354493Y1088646D01*
G01X1350779Y1084410D02*
X1348941Y1085457D01*
G01X1363732Y1074843D02*
X1361894Y1075890D01*
G01X1363732Y1087599D02*
X1361894Y1088646D01*
G01X1363732Y1081221D02*
X1361894Y1082268D01*
G01X1350779Y1103544D02*
X1348941Y1104591D01*
G01X1354480Y1090788D02*
X1352642Y1091835D01*
G01X1363732Y1093977D02*
X1361894Y1095024D01*
G01X1356331Y1106733D02*
X1354493Y1107780D01*
G01X1354480Y1109922D02*
X1352642Y1110969D01*
G01X1363732Y1113111D02*
X1361894Y1114158D01*
G01X1363732Y1106733D02*
X1361894Y1107780D01*
G01X1356331Y1125867D02*
X1354493Y1126914D01*
G01X1350779Y1122678D02*
X1348941Y1123725D01*
G01X1354480Y1129056D02*
X1352642Y1130102D01*
G01X1363732Y1119489D02*
X1361894Y1120536D01*
G01X1363732Y1125867D02*
X1361894Y1126914D01*
G01X1363732Y1132245D02*
X1361894Y1133292D01*
G01X1356331Y1145000D02*
X1354493Y1146047D01*
G01X1350779Y1141811D02*
X1348941Y1142858D01*
G01X1354480Y1148189D02*
X1352642Y1149236D01*
G01X1363732Y1138622D02*
X1361894Y1139669D01*
G01X1363732Y1145000D02*
X1361894Y1146047D01*
G01X1363732Y1157756D02*
X1361894Y1158803D01*
G01X1360031Y1157756D02*
X1358193Y1158803D01*
G01X1363732Y1151378D02*
X1361894Y1152425D01*
G01X1355686Y1510295D02*
X1354521Y1509130D01*
Y1506360D01*
X1355586Y1505295D01*
G01X1362386Y1500595D02*
X1361221Y1499430D01*
Y1496660D01*
X1362286Y1495595D01*
G01X1352086Y1510295D02*
X1353251Y1509130D01*
Y1506360D01*
X1352186Y1505295D01*
G01X1358786Y1500595D02*
X1359951Y1499430D01*
Y1496660D01*
X1358886Y1495595D01*
G01X1352719Y1640286D02*
X1353884Y1639121D01*
Y1626445D01*
X1352819Y1625380D01*
G01X1356319Y1640286D02*
X1355154Y1639121D01*
Y1626445D01*
X1356219Y1625380D01*
G01X1352719Y1642386D02*
X1353884Y1643551D01*
Y1656227D01*
X1352819Y1657292D01*
G01X1356319Y1642386D02*
X1355154Y1643551D01*
Y1656227D01*
X1356219Y1657292D01*
G01X1369953Y880670D02*
X1368115Y879623D01*
G01X1373653Y880670D02*
X1371815Y879623D01*
G01X1377354Y893426D02*
X1375516Y892379D01*
G01X1366252Y893426D02*
X1364414Y892379D01*
G01X1373653Y893426D02*
X1371815Y892379D01*
G01X1373653Y887048D02*
X1371815Y886001D01*
G01X1377354Y887048D02*
X1375516Y886001D01*
G01X1377354Y899804D02*
X1375516Y898757D01*
G01X1366252Y906181D02*
X1364414Y905134D01*
G01X1366252Y899804D02*
X1364414Y898757D01*
G01X1377354Y906181D02*
X1375516Y905134D01*
G01X1373653Y899804D02*
X1371815Y898757D01*
G01X1373653Y906181D02*
X1371815Y905134D01*
G01X1366252Y912559D02*
X1364414Y911512D01*
G01X1377354Y912559D02*
X1375516Y911512D01*
G01X1377354Y918937D02*
X1375516Y917890D01*
G01X1377354Y925315D02*
X1375516Y924268D01*
G01X1366252Y918937D02*
X1364414Y917890D01*
G01X1366252Y925315D02*
X1364414Y924268D01*
G01X1373653Y912559D02*
X1371815Y911512D01*
G01X1373653Y918937D02*
X1371815Y917890D01*
G01X1373653Y925315D02*
X1371815Y924268D01*
G01X1366252Y931693D02*
X1364414Y930646D01*
G01X1377354Y931693D02*
X1375516Y930646D01*
G01X1373653Y931693D02*
X1371815Y930646D01*
G01X1373653Y944449D02*
X1371815Y943402D01*
G01X1373653Y950827D02*
X1371815Y949780D01*
G01X1377354Y944449D02*
X1375516Y943402D01*
G01X1377354Y950827D02*
X1375516Y949780D01*
G01X1366252Y944449D02*
X1364414Y943402D01*
G01X1366252Y950827D02*
X1364414Y949780D01*
G01X1373653Y957205D02*
X1371815Y956158D01*
G01X1377354Y957205D02*
X1375516Y956158D01*
G01X1366252Y957205D02*
X1364414Y956158D01*
G01X1373653Y963583D02*
X1371815Y962536D01*
G01X1373653Y969961D02*
X1371815Y968914D01*
G01X1377354Y963583D02*
X1375516Y962536D01*
G01X1377354Y969961D02*
X1375516Y968914D01*
G01X1366252Y963583D02*
X1364414Y962536D01*
G01X1366252Y969961D02*
X1364414Y968914D01*
G01X1373653Y976339D02*
X1371815Y975292D01*
G01X1377354Y976339D02*
X1375516Y975292D01*
G01X1366252Y976339D02*
X1364414Y975292D01*
G01X1374835Y1068465D02*
X1372997Y1069512D01*
G01X1374835Y1074843D02*
X1372997Y1075890D01*
G01X1374835Y1062087D02*
X1372997Y1063134D01*
G01X1367433Y1068465D02*
X1365595Y1069512D01*
G01X1367433Y1074843D02*
X1365595Y1075890D01*
G01X1367433Y1062087D02*
X1365595Y1063134D01*
G01X1378535Y1068465D02*
X1376697Y1069512D01*
G01X1378535Y1062087D02*
X1376697Y1063134D01*
G01X1378535Y1074843D02*
X1376697Y1075890D01*
G01X1374835Y1087599D02*
X1372997Y1088646D01*
G01X1374835Y1081221D02*
X1372997Y1082268D01*
G01X1367433Y1087599D02*
X1365595Y1088646D01*
G01X1367433Y1081221D02*
X1365595Y1082268D01*
G01X1378535Y1087599D02*
X1376697Y1088646D01*
G01X1378535Y1081221D02*
X1376697Y1082268D01*
G01X1374835Y1093977D02*
X1372997Y1095024D01*
G01X1367433Y1093977D02*
X1365595Y1095024D01*
G01X1378535Y1093977D02*
X1376697Y1095024D01*
G01X1367433Y1113111D02*
X1365595Y1114158D01*
G01X1367433Y1119489D02*
X1365595Y1120536D01*
G01X1367433Y1106733D02*
X1365595Y1107780D01*
G01X1378535Y1113111D02*
X1376697Y1114158D01*
G01X1378535Y1119489D02*
X1376697Y1120536D01*
G01X1378535Y1106733D02*
X1376697Y1107780D01*
G01X1374835Y1113111D02*
X1372997Y1114158D01*
G01X1374835Y1119489D02*
X1372997Y1120536D01*
G01X1374835Y1106733D02*
X1372997Y1107780D01*
G01X1378535Y1125867D02*
X1376697Y1126914D01*
G01X1374835Y1125867D02*
X1372997Y1126914D01*
G01X1367433Y1125867D02*
X1365595Y1126914D01*
G01X1367433Y1132245D02*
X1365595Y1133292D01*
G01X1378535Y1132245D02*
X1376697Y1133292D01*
G01X1374835Y1132245D02*
X1372997Y1133292D01*
G01X1367433Y1138622D02*
X1365595Y1139669D01*
G01X1367433Y1145000D02*
X1365595Y1146047D01*
G01X1378535Y1138622D02*
X1376697Y1139669D01*
G01X1378535Y1145000D02*
X1376697Y1146047D01*
G01X1374835Y1138622D02*
X1372997Y1139669D01*
G01X1374835Y1145000D02*
X1372997Y1146047D01*
G01X1374835Y1157756D02*
X1372997Y1158803D01*
G01X1371134Y1157756D02*
X1369296Y1158803D01*
G01X1367433Y1151378D02*
X1365595Y1152425D01*
G01X1378535Y1151378D02*
X1376697Y1152425D01*
G01X1374835Y1151378D02*
X1372997Y1152425D01*
G01X1369086Y1490895D02*
X1367921Y1489730D01*
Y1486960D01*
X1368986Y1485895D01*
G01X1365486Y1490895D02*
X1366651Y1489730D01*
Y1486960D01*
X1365586Y1485895D01*
G01X1364779Y1640286D02*
X1365944Y1639121D01*
Y1626445D01*
X1364879Y1625380D01*
G01X1376839Y1640286D02*
X1378004Y1639121D01*
Y1626445D01*
X1376939Y1625380D01*
G01X1368379Y1640286D02*
X1367214Y1639121D01*
Y1626445D01*
X1368279Y1625380D01*
G01X1364779Y1642386D02*
X1365944Y1643551D01*
Y1656227D01*
X1364879Y1657292D01*
G01X1376839Y1642386D02*
X1378004Y1643551D01*
Y1656227D01*
X1376939Y1657292D01*
G01X1368379Y1642386D02*
X1367214Y1643551D01*
Y1656227D01*
X1368279Y1657292D01*
G01X1392157Y880670D02*
X1390320Y879623D01*
G01X1388457Y893426D02*
X1386619Y892379D01*
G01X1384756Y893426D02*
X1382918Y892379D01*
G01X1388457Y906181D02*
X1386619Y905134D01*
G01X1388457Y899804D02*
X1386619Y898757D01*
G01X1384756Y906181D02*
X1382918Y905134D01*
G01X1384756Y899804D02*
X1382918Y898757D01*
G01X1388457Y925315D02*
X1386619Y924268D01*
G01X1388457Y912559D02*
X1386619Y911512D01*
G01X1388457Y918937D02*
X1386619Y917890D01*
G01X1384756Y925315D02*
X1382918Y924268D01*
G01X1384756Y912559D02*
X1382918Y911512D01*
G01X1384756Y918937D02*
X1382918Y917890D01*
G01X1384756Y944449D02*
X1382918Y943402D01*
G01X1384756Y950827D02*
X1382918Y949780D01*
G01X1388457Y944449D02*
X1386619Y943402D01*
G01X1388457Y950827D02*
X1386619Y949780D01*
G01X1384756Y957205D02*
X1382918Y956158D01*
G01X1388457Y957205D02*
X1386619Y956158D01*
G01X1384756Y963583D02*
X1382918Y962536D01*
G01X1384756Y969961D02*
X1382918Y968914D01*
G01X1388457Y963583D02*
X1386619Y962536D01*
G01X1388457Y969961D02*
X1386619Y968914D01*
G01X1384756Y976339D02*
X1382918Y975292D01*
G01X1388457Y976339D02*
X1386619Y975292D01*
G01X1385937Y1068465D02*
X1384099Y1069512D01*
G01X1385937Y1074843D02*
X1384099Y1075890D01*
G01X1385937Y1062087D02*
X1384099Y1063134D01*
G01X1389638Y1068465D02*
X1387800Y1069512D01*
G01X1389638Y1074843D02*
X1387800Y1075890D01*
G01X1389638Y1062087D02*
X1387800Y1063134D01*
G01X1385937Y1087599D02*
X1384099Y1088646D01*
G01X1385937Y1081221D02*
X1384099Y1082268D01*
G01X1389638Y1087599D02*
X1387800Y1088646D01*
G01X1389638Y1081221D02*
X1387800Y1082268D01*
G01X1385937Y1093977D02*
X1384099Y1095024D01*
G01X1389638Y1093977D02*
X1387800Y1095024D01*
G01X1389638Y1119489D02*
X1387800Y1120536D01*
G01X1389638Y1113111D02*
X1387800Y1114158D01*
G01X1385937Y1119489D02*
X1384099Y1120536D01*
G01X1385937Y1113111D02*
X1384099Y1114158D01*
G01X1389638Y1125867D02*
X1387800Y1126914D01*
G01X1385937Y1125867D02*
X1384099Y1126914D01*
G01X1389638Y1132245D02*
X1387800Y1133292D01*
G01X1385937Y1132245D02*
X1384099Y1133292D01*
G01X1389638Y1138622D02*
X1387800Y1139669D01*
G01X1389638Y1145000D02*
X1387800Y1146047D01*
G01X1385937Y1138622D02*
X1384099Y1139669D01*
G01X1385937Y1145000D02*
X1384099Y1146047D01*
G01X1385937Y1157756D02*
X1384099Y1158803D01*
G01X1382236Y1157756D02*
X1380398Y1158803D01*
G01X1393338Y1157756D02*
X1391500Y1158803D01*
G01X1389638Y1151378D02*
X1387800Y1152425D01*
G01X1385937Y1151378D02*
X1384099Y1152425D01*
G01X1392286Y1490895D02*
X1393451Y1489730D01*
Y1486960D01*
X1392386Y1485895D01*
G01X1382486Y1510295D02*
X1381321Y1509130D01*
Y1506360D01*
X1382386Y1505295D01*
G01X1389186Y1500595D02*
X1388021Y1499430D01*
Y1496660D01*
X1389086Y1495595D01*
G01X1378886Y1510295D02*
X1380051Y1509130D01*
Y1506360D01*
X1378986Y1505295D01*
G01X1385586Y1500595D02*
X1386751Y1499430D01*
Y1496660D01*
X1385686Y1495595D01*
G01X1380439Y1640286D02*
X1379274Y1639121D01*
Y1626445D01*
X1380339Y1625380D01*
G01X1380439Y1642386D02*
X1379274Y1643551D01*
Y1656227D01*
X1380339Y1657292D01*
G01X1395858Y880670D02*
X1394021Y879623D01*
G01X1406960Y880670D02*
X1405123Y879623D01*
G01X1403260Y880670D02*
X1401423Y879623D01*
G01X1408811Y896615D02*
X1406973Y895568D01*
G01X1399559Y893426D02*
X1397721Y892379D01*
G01X1405110Y896615D02*
X1403272Y895568D01*
G01X1395858Y893426D02*
X1394020Y892379D01*
G01X1395858Y887048D02*
X1394021Y886001D01*
G01X1399559Y887048D02*
X1397722Y886001D01*
G01X1406960Y887048D02*
X1405123Y886001D01*
G01X1408811Y909370D02*
X1406973Y908324D01*
G01X1408811Y902993D02*
X1406973Y901946D01*
G01X1399559Y906181D02*
X1397721Y905134D01*
G01X1399559Y899804D02*
X1397721Y898757D01*
G01X1405110Y909370D02*
X1403272Y908324D01*
G01X1405110Y902993D02*
X1403272Y901946D01*
G01X1395858Y906181D02*
X1394020Y905134D01*
G01X1395858Y899804D02*
X1394020Y898757D01*
G01X1408811Y922126D02*
X1406973Y921079D01*
G01X1408811Y915748D02*
X1406973Y914701D01*
G01X1399559Y925315D02*
X1397721Y924268D01*
G01X1399559Y912559D02*
X1397721Y911512D01*
G01X1399559Y918937D02*
X1397721Y917890D01*
G01X1405110Y922126D02*
X1403272Y921079D01*
G01X1405110Y915748D02*
X1403272Y914701D01*
G01X1395858Y925315D02*
X1394020Y924268D01*
G01X1395858Y912559D02*
X1394020Y911512D01*
G01X1395858Y918937D02*
X1394020Y917890D01*
G01X1405110Y941260D02*
X1403272Y940213D01*
G01X1395858Y938071D02*
X1394020Y937024D01*
G01X1408811Y941260D02*
X1406973Y940213D01*
G01X1399559Y938071D02*
X1397721Y937024D01*
G01X1408811Y928504D02*
X1406973Y927457D01*
G01X1405110Y928504D02*
X1403272Y927457D01*
G01X1405110Y954016D02*
X1403272Y952969D01*
G01X1405110Y947638D02*
X1403272Y946591D01*
G01X1395858Y944449D02*
X1394020Y943402D01*
G01X1395858Y950827D02*
X1394020Y949780D01*
G01X1408811Y954016D02*
X1406973Y952969D01*
G01X1408811Y947638D02*
X1406973Y946591D01*
G01X1399559Y944449D02*
X1397721Y943402D01*
G01X1399559Y950827D02*
X1397721Y949780D01*
G01X1395858Y957205D02*
X1394020Y956158D01*
G01X1399559Y957205D02*
X1397721Y956158D01*
G01X1405110Y960394D02*
X1403272Y959347D01*
G01X1405110Y966772D02*
X1403272Y965725D01*
G01X1395858Y963583D02*
X1394020Y962536D01*
G01X1395858Y969961D02*
X1394020Y968914D01*
G01X1408811Y960394D02*
X1406973Y959347D01*
G01X1408811Y966772D02*
X1406973Y965725D01*
G01X1399559Y963583D02*
X1397721Y962536D01*
G01X1399559Y969961D02*
X1397721Y968914D01*
G01X1405110Y979528D02*
X1403272Y978481D01*
G01X1405110Y973150D02*
X1403272Y972103D01*
G01X1395858Y976339D02*
X1394020Y975292D01*
G01X1408811Y979528D02*
X1406973Y978481D01*
G01X1408811Y973150D02*
X1406973Y972103D01*
G01X1399559Y976339D02*
X1397721Y975292D01*
G01X1406291Y1058898D02*
X1404453Y1059945D01*
G01X1409992Y1058898D02*
X1408154Y1059945D01*
G01X1397039Y1074843D02*
X1395201Y1075890D01*
G01X1397039Y1062087D02*
X1395201Y1063134D01*
G01X1406291Y1071654D02*
X1404453Y1072701D01*
G01X1406291Y1065276D02*
X1404453Y1066323D01*
G01X1397039Y1068465D02*
X1395201Y1069512D01*
G01X1400740Y1074843D02*
X1398902Y1075890D01*
G01X1400740Y1062087D02*
X1398902Y1063134D01*
G01X1409992Y1071654D02*
X1408154Y1072701D01*
G01X1409992Y1065276D02*
X1408154Y1066323D01*
G01X1400740Y1068465D02*
X1398902Y1069512D01*
G01X1406291Y1078032D02*
X1404453Y1079079D01*
G01X1409992Y1078032D02*
X1408154Y1079079D01*
G01X1397039Y1081221D02*
X1395201Y1082268D01*
G01X1406291Y1084410D02*
X1404453Y1085457D01*
G01X1397039Y1087599D02*
X1395201Y1088646D01*
G01X1400740Y1081221D02*
X1398902Y1082268D01*
G01X1409992Y1084410D02*
X1408154Y1085457D01*
G01X1400740Y1087599D02*
X1398902Y1088646D01*
G01X1397039Y1093977D02*
X1395201Y1095024D01*
G01X1397039Y1100355D02*
X1395201Y1101402D01*
G01X1406291Y1097166D02*
X1404453Y1098213D01*
G01X1406291Y1090788D02*
X1404453Y1091835D01*
G01X1400740Y1093977D02*
X1398902Y1095024D01*
G01X1400740Y1100355D02*
X1398902Y1101402D01*
G01X1409992Y1097166D02*
X1408154Y1098213D01*
G01X1409992Y1090788D02*
X1408154Y1091835D01*
G01X1400740Y1119489D02*
X1398902Y1120536D01*
G01X1400740Y1113111D02*
X1398902Y1114158D01*
G01X1409992Y1116300D02*
X1408154Y1117347D01*
G01X1409992Y1109922D02*
X1408154Y1110969D01*
G01X1397039Y1119489D02*
X1395201Y1120536D01*
G01X1397039Y1113111D02*
X1395201Y1114158D01*
G01X1406291Y1116300D02*
X1404453Y1117347D01*
G01X1406291Y1109922D02*
X1404453Y1110969D01*
G01X1400740Y1125867D02*
X1398902Y1126914D01*
G01X1409992Y1122678D02*
X1408154Y1123725D01*
G01X1397039Y1125867D02*
X1395201Y1126914D01*
G01X1406291Y1122678D02*
X1404453Y1123725D01*
G01X1400740Y1132245D02*
X1398902Y1133292D01*
G01X1409992Y1129056D02*
X1408154Y1130102D01*
G01X1397039Y1132245D02*
X1395201Y1133292D01*
G01X1406291Y1129056D02*
X1404453Y1130102D01*
G01X1400740Y1138622D02*
X1398902Y1139669D01*
G01X1400740Y1145000D02*
X1398902Y1146047D01*
G01X1409992Y1141811D02*
X1408154Y1142858D01*
G01X1409992Y1135433D02*
X1408154Y1136480D01*
G01X1397039Y1138622D02*
X1395201Y1139669D01*
G01X1397039Y1145000D02*
X1395201Y1146047D01*
G01X1406291Y1141811D02*
X1404453Y1142858D01*
G01X1406291Y1135433D02*
X1404453Y1136480D01*
G01X1397039Y1157756D02*
X1395201Y1158803D01*
G01X1400740Y1151378D02*
X1398902Y1152425D01*
G01X1397039Y1151378D02*
X1395201Y1152425D01*
G01X1395886Y1490895D02*
X1394721Y1489730D01*
Y1486960D01*
X1395786Y1485895D01*
G01X1409186D02*
X1408121Y1486960D01*
Y1489730D01*
X1409286Y1490895D01*
G01X1405786Y1485895D02*
X1406851Y1486960D01*
Y1489730D01*
X1405686Y1490895D01*
G01X1410661Y887048D02*
X1408824Y886001D01*
G01X1411556Y1513582D02*
X1412721Y1514747D01*
X1415491D01*
X1416556Y1513682D01*
G01X1411556Y1517182D02*
X1412721Y1516017D01*
X1415491D01*
X1416556Y1517082D01*
G01X1411556Y1530582D02*
X1412721Y1529417D01*
X1415491D01*
X1416556Y1530482D01*
G01X1411556Y1526982D02*
X1412721Y1528147D01*
X1415491D01*
X1416556Y1527082D01*
G01X1438831Y-19027D02*
X1436263Y-18311D01*
G01X1438831Y-20995D02*
X1436263Y-21711D01*
G01X1438831Y973D02*
X1436263Y1689D01*
G01X1438831Y-995D02*
X1436263Y-1711D01*
G01X1432866Y893426D02*
X1434704Y892379D01*
G01X1423614Y896615D02*
X1425452Y895568D01*
G01X1436567Y893426D02*
X1438405Y892379D01*
G01X1427315Y896615D02*
X1429153Y895568D01*
G01X1432866Y899804D02*
X1434704Y898757D01*
G01X1432866Y906181D02*
X1434704Y905134D01*
G01X1423614Y902993D02*
X1425452Y901946D01*
G01X1423614Y909370D02*
X1425452Y908324D01*
G01X1436567Y899804D02*
X1438405Y898757D01*
G01X1436567Y906181D02*
X1438405Y905134D01*
G01X1427315Y902993D02*
X1429153Y901946D01*
G01X1427315Y909370D02*
X1429153Y908324D01*
G01X1432866Y918937D02*
X1434704Y917890D01*
G01X1432866Y912559D02*
X1434704Y911512D01*
G01X1432866Y925315D02*
X1434704Y924268D01*
G01X1423614Y915748D02*
X1425452Y914701D01*
G01X1423614Y922126D02*
X1425452Y921079D01*
G01X1436567Y918937D02*
X1438405Y917890D01*
G01X1436567Y912559D02*
X1438405Y911512D01*
G01X1436567Y925315D02*
X1438405Y924268D01*
G01X1427315Y915748D02*
X1429153Y914701D01*
G01X1427315Y922126D02*
X1429153Y921079D01*
G01X1436567Y938071D02*
X1438405Y937024D01*
G01X1427315Y941260D02*
X1429153Y940213D01*
G01X1432866Y938071D02*
X1434704Y937024D01*
G01X1423614Y941260D02*
X1425452Y940213D01*
G01X1423614Y928504D02*
X1425452Y927457D01*
G01X1427315Y928504D02*
X1429153Y927457D01*
G01X1436567Y944449D02*
X1438405Y943402D01*
G01X1427315Y947638D02*
X1429153Y946591D01*
G01X1427315Y954016D02*
X1429153Y952969D01*
G01X1436567Y950827D02*
X1438405Y949780D01*
G01X1432866Y944449D02*
X1434704Y943402D01*
G01X1423614Y947638D02*
X1425452Y946591D01*
G01X1423614Y954016D02*
X1425452Y952969D01*
G01X1432866Y950827D02*
X1434704Y949780D01*
G01X1436567Y957205D02*
X1438405Y956158D01*
G01X1432866Y957205D02*
X1434704Y956158D01*
G01X1436567Y963583D02*
X1438405Y962536D01*
G01X1427315Y966772D02*
X1429153Y965725D01*
G01X1427315Y960394D02*
X1429153Y959347D01*
G01X1436567Y969961D02*
X1438405Y968914D01*
G01X1432866Y963583D02*
X1434704Y962536D01*
G01X1423614Y966772D02*
X1425452Y965725D01*
G01X1423614Y960394D02*
X1425452Y959347D01*
G01X1432866Y969961D02*
X1434704Y968914D01*
G01X1436567Y976339D02*
X1438405Y975292D01*
G01X1427315Y973150D02*
X1429153Y972103D01*
G01X1427315Y979528D02*
X1429153Y978481D01*
G01X1432866Y976339D02*
X1434704Y975292D01*
G01X1423614Y973150D02*
X1425452Y972103D01*
G01X1423614Y979528D02*
X1425452Y978481D01*
G01X1428496Y1058898D02*
X1430334Y1059945D01*
G01X1424795Y1058898D02*
X1426633Y1059945D01*
G01X1428496Y1065276D02*
X1430334Y1066323D01*
G01X1428496Y1071654D02*
X1430334Y1072701D01*
G01X1437748Y1062087D02*
X1439586Y1063134D01*
G01X1437748Y1074843D02*
X1439586Y1075890D01*
G01X1437748Y1068465D02*
X1439586Y1069512D01*
G01X1424795Y1065276D02*
X1426633Y1066323D01*
G01X1424795Y1071654D02*
X1426633Y1072701D01*
G01X1434047Y1062087D02*
X1435885Y1063134D01*
G01X1434047Y1074843D02*
X1435885Y1075890D01*
G01X1434047Y1068465D02*
X1435885Y1069512D01*
G01X1428496Y1078032D02*
X1430334Y1079079D01*
G01X1424795Y1078032D02*
X1426633Y1079079D01*
G01X1437748Y1087599D02*
X1439586Y1088646D01*
G01X1434047Y1087599D02*
X1435885Y1088646D01*
G01X1428496Y1084410D02*
X1430334Y1085457D01*
G01X1437748Y1081221D02*
X1439586Y1082268D01*
G01X1424795Y1084410D02*
X1426633Y1085457D01*
G01X1434047Y1081221D02*
X1435885Y1082268D01*
G01X1437748Y1100355D02*
X1439586Y1101402D01*
G01X1437748Y1093977D02*
X1439586Y1095024D01*
G01X1434047Y1100355D02*
X1435885Y1101402D01*
G01X1434047Y1093977D02*
X1435885Y1095024D01*
G01X1428496Y1090788D02*
X1430334Y1091835D01*
G01X1428496Y1097166D02*
X1430334Y1098213D01*
G01X1424795Y1090788D02*
X1426633Y1091835D01*
G01X1424795Y1097166D02*
X1426633Y1098213D01*
G01X1424795Y1109922D02*
X1426633Y1110969D01*
G01X1424795Y1116300D02*
X1426633Y1117347D01*
G01X1434047Y1113111D02*
X1435885Y1114158D01*
G01X1434047Y1119489D02*
X1435885Y1120536D01*
G01X1428496Y1109922D02*
X1430334Y1110969D01*
G01X1428496Y1116300D02*
X1430334Y1117347D01*
G01X1437748Y1113111D02*
X1439586Y1114158D01*
G01X1437748Y1119489D02*
X1439586Y1120536D01*
G01X1428496Y1129056D02*
X1430334Y1130102D01*
G01X1424795Y1129056D02*
X1426633Y1130102D01*
G01X1424795Y1122678D02*
X1426633Y1123725D01*
G01X1434047Y1125867D02*
X1435885Y1126914D01*
G01X1428496Y1122678D02*
X1430334Y1123725D01*
G01X1437748Y1125867D02*
X1439586Y1126914D01*
G01X1434047Y1132245D02*
X1435885Y1133292D01*
G01X1437748Y1132245D02*
X1439586Y1133292D01*
G01X1434047Y1145000D02*
X1435885Y1146047D01*
G01X1434047Y1138622D02*
X1435885Y1139669D01*
G01X1437748Y1145000D02*
X1439586Y1146047D01*
G01X1437748Y1138622D02*
X1439586Y1139669D01*
G01X1424795Y1135433D02*
X1426633Y1136480D01*
G01X1424795Y1141811D02*
X1426633Y1142858D01*
G01X1428496Y1135433D02*
X1430334Y1136480D01*
G01X1428496Y1141811D02*
X1430334Y1142858D01*
G01X1435160Y1516590D02*
X1436225Y1515525D01*
X1438995D01*
X1440160Y1516690D01*
G01X1435160Y1513190D02*
X1436225Y1514255D01*
X1438995D01*
X1440160Y1513090D01*
G01X1435160Y1534990D02*
X1436225Y1536055D01*
X1438995D01*
X1440160Y1534890D01*
G01X1435160Y1538390D02*
X1436225Y1537325D01*
X1438995D01*
X1440160Y1538490D01*
G01X1434578Y1556331D02*
X1435643Y1557396D01*
X1437465D01*
X1438430Y1556431D01*
G01X1434578Y1559731D02*
X1435643Y1558666D01*
X1437465D01*
X1438430Y1559631D01*
G01X1447669Y874292D02*
X1449507Y873245D01*
G01X1451370Y874292D02*
X1453208Y873245D01*
G01X1443968Y893426D02*
X1445806Y892379D01*
G01X1447669Y893426D02*
X1449507Y892379D01*
G01X1443968Y899804D02*
X1445806Y898757D01*
G01X1443968Y906181D02*
X1445806Y905134D01*
G01X1447669Y899804D02*
X1449507Y898757D01*
G01X1447669Y906181D02*
X1449507Y905134D01*
G01X1443968Y918937D02*
X1445806Y917890D01*
G01X1443968Y912559D02*
X1445806Y911512D01*
G01X1443968Y925315D02*
X1445806Y924268D01*
G01X1447669Y918937D02*
X1449507Y917890D01*
G01X1447669Y912559D02*
X1449507Y911512D01*
G01X1447669Y925315D02*
X1449507Y924268D01*
G01X1447669Y950827D02*
X1449507Y949780D01*
G01X1447669Y944449D02*
X1449507Y943402D01*
G01X1443968Y950827D02*
X1445806Y949780D01*
G01X1443968Y944449D02*
X1445806Y943402D01*
G01X1447669Y957205D02*
X1449507Y956158D01*
G01X1443968Y957205D02*
X1445806Y956158D01*
G01X1447669Y969961D02*
X1449507Y968914D01*
G01X1447669Y963583D02*
X1449507Y962536D01*
G01X1443968Y969961D02*
X1445806Y968914D01*
G01X1443968Y963583D02*
X1445806Y962536D01*
G01X1447669Y976339D02*
X1449507Y975292D01*
G01X1443968Y976339D02*
X1445806Y975292D01*
G01X1448850Y1062087D02*
X1450688Y1063134D01*
G01X1448850Y1074843D02*
X1450688Y1075890D01*
G01X1448850Y1068465D02*
X1450688Y1069512D01*
G01X1445149Y1062087D02*
X1446987Y1063134D01*
G01X1445149Y1074843D02*
X1446987Y1075890D01*
G01X1445149Y1068465D02*
X1446987Y1069512D01*
G01X1448850Y1081221D02*
X1450688Y1082268D01*
G01X1445149Y1081221D02*
X1446987Y1082268D01*
G01X1448850Y1087599D02*
X1450688Y1088646D01*
G01X1445149Y1087599D02*
X1446987Y1088646D01*
G01X1448850Y1093977D02*
X1450688Y1095024D01*
G01X1445149Y1093977D02*
X1446987Y1095024D01*
G01X1445149Y1113111D02*
X1446987Y1114158D01*
G01X1445149Y1119489D02*
X1446987Y1120536D01*
G01X1448850Y1113111D02*
X1450688Y1114158D01*
G01X1448850Y1119489D02*
X1450688Y1120536D01*
G01X1445149Y1125867D02*
X1446987Y1126914D01*
G01X1448850Y1125867D02*
X1450688Y1126914D01*
G01X1445149Y1132245D02*
X1446987Y1133292D01*
G01X1448850Y1132245D02*
X1450688Y1133292D01*
G01X1445149Y1138622D02*
X1446987Y1139669D01*
G01X1448850Y1138622D02*
X1450688Y1139669D01*
G01X1445149Y1145000D02*
X1446987Y1146047D01*
G01X1448850Y1145000D02*
X1450688Y1146047D01*
G01X1451498Y1485895D02*
X1450433Y1486960D01*
Y1489730D01*
X1451598Y1490895D01*
G01X1448098Y1485895D02*
X1449163Y1486960D01*
Y1489730D01*
X1447998Y1490895D01*
G01X1444798Y1495595D02*
X1443733Y1496660D01*
Y1499430D01*
X1444898Y1500595D01*
G01X1441398Y1495595D02*
X1442463Y1496660D01*
Y1499430D01*
X1441298Y1500595D01*
G01X1440530Y1556431D02*
X1441492Y1557393D01*
X1442518D01*
X1443480Y1556431D01*
G01D02*
X1444397Y1557348D01*
X1446465D01*
X1447682Y1558565D01*
X1450016D01*
G01X1440530Y1559631D02*
X1441498Y1558663D01*
X1442512D01*
X1443480Y1559631D01*
G01D02*
X1444493Y1558618D01*
X1445938D01*
X1447155Y1559835D01*
X1450091D01*
G01X1462472Y874292D02*
X1464310Y873245D01*
G01X1458771Y874292D02*
X1460609Y873245D01*
G01X1458771Y880670D02*
X1460609Y879623D01*
G01X1462472Y880670D02*
X1464310Y879623D01*
G01X1466173Y893426D02*
X1468011Y892379D01*
G01X1455071Y893426D02*
X1456909Y892379D01*
G01X1458771Y893426D02*
X1460609Y892379D01*
G01X1458771Y887048D02*
X1460609Y886001D01*
G01X1455071Y887048D02*
X1456909Y886001D01*
G01X1466173Y899804D02*
X1468011Y898757D01*
G01X1466173Y906181D02*
X1468011Y905134D01*
G01X1455071Y899804D02*
X1456909Y898757D01*
G01X1455071Y906181D02*
X1456909Y905134D01*
G01X1458771Y899804D02*
X1460609Y898757D01*
G01X1458771Y906181D02*
X1460609Y905134D01*
G01X1466173Y912559D02*
X1468011Y911512D01*
G01X1466173Y925315D02*
X1468011Y924268D01*
G01X1466173Y918937D02*
X1468011Y917890D01*
G01X1455071Y925315D02*
X1456909Y924268D01*
G01X1455071Y918937D02*
X1456909Y917890D01*
G01X1455071Y912559D02*
X1456909Y911512D01*
G01X1458771Y925315D02*
X1460609Y924268D01*
G01X1458771Y918937D02*
X1460609Y917890D01*
G01X1458771Y912559D02*
X1460609Y911512D01*
G01X1466173Y931693D02*
X1468011Y930646D01*
G01X1455071Y931693D02*
X1456909Y930646D01*
G01X1458771Y931693D02*
X1460609Y930646D01*
G01X1458771Y950827D02*
X1460609Y949780D01*
G01X1458771Y944449D02*
X1460609Y943402D01*
G01X1466173Y950827D02*
X1468011Y949780D01*
G01X1466173Y944449D02*
X1468011Y943402D01*
G01X1455071Y950827D02*
X1456909Y949780D01*
G01X1455071Y944449D02*
X1456909Y943402D01*
G01X1458771Y957205D02*
X1460609Y956158D01*
G01X1466173Y957205D02*
X1468011Y956158D01*
G01X1455071Y957205D02*
X1456909Y956158D01*
G01X1458771Y969961D02*
X1460609Y968914D01*
G01X1458771Y963583D02*
X1460609Y962536D01*
G01X1466173Y969961D02*
X1468011Y968914D01*
G01X1466173Y963583D02*
X1468011Y962536D01*
G01X1455071Y969961D02*
X1456909Y968914D01*
G01X1455071Y963583D02*
X1456909Y962536D01*
G01X1458771Y976339D02*
X1460609Y975292D01*
G01X1466173Y976339D02*
X1468011Y975292D01*
G01X1455071Y976339D02*
X1456909Y975292D01*
G01X1459953Y1062087D02*
X1461791Y1063134D01*
G01X1459953Y1074843D02*
X1461791Y1075890D01*
G01X1459953Y1068465D02*
X1461791Y1069512D01*
G01X1456252Y1062087D02*
X1458090Y1063134D01*
G01X1456252Y1074843D02*
X1458090Y1075890D01*
G01X1456252Y1068465D02*
X1458090Y1069512D01*
G01X1467354Y1062087D02*
X1469192Y1063134D01*
G01X1467354Y1074843D02*
X1469192Y1075890D01*
G01X1467354Y1068465D02*
X1469192Y1069512D01*
G01X1459953Y1081221D02*
X1461791Y1082268D01*
G01X1459953Y1087599D02*
X1461791Y1088646D01*
G01X1456252Y1081221D02*
X1458090Y1082268D01*
G01X1456252Y1087599D02*
X1458090Y1088646D01*
G01X1467354Y1081221D02*
X1469192Y1082268D01*
G01X1467354Y1087599D02*
X1469192Y1088646D01*
G01X1459953Y1093977D02*
X1461791Y1095024D01*
G01X1456252Y1093977D02*
X1458090Y1095024D01*
G01X1467354Y1093977D02*
X1469192Y1095024D01*
G01X1456252Y1119489D02*
X1458090Y1120536D01*
G01X1456252Y1113111D02*
X1458090Y1114158D01*
G01X1467354Y1106733D02*
X1469192Y1107780D01*
G01X1467354Y1119489D02*
X1469192Y1120536D01*
G01X1467354Y1113111D02*
X1469192Y1114158D01*
G01X1456252Y1106733D02*
X1458090Y1107780D01*
G01X1459953Y1119489D02*
X1461791Y1120536D01*
G01X1459953Y1113111D02*
X1461791Y1114158D01*
G01X1459953Y1106733D02*
X1461791Y1107780D01*
G01X1456252Y1132245D02*
X1458090Y1133292D01*
G01X1459953Y1132245D02*
X1461791Y1133292D01*
G01X1456252Y1125867D02*
X1458090Y1126914D01*
G01X1459953Y1125867D02*
X1461791Y1126914D01*
G01X1467354Y1132245D02*
X1469192Y1133292D01*
G01X1467354Y1125867D02*
X1469192Y1126914D01*
G01X1456252Y1145000D02*
X1458090Y1146047D01*
G01X1456252Y1138622D02*
X1458090Y1139669D01*
G01X1459953Y1145000D02*
X1461791Y1146047D01*
G01X1459953Y1138622D02*
X1461791Y1139669D01*
G01X1467354Y1145000D02*
X1469192Y1146047D01*
G01X1467354Y1138622D02*
X1469192Y1139669D01*
G01X1464898Y1505295D02*
X1463833Y1506360D01*
Y1509130D01*
X1464998Y1510295D01*
G01X1461498Y1505295D02*
X1462563Y1506360D01*
Y1509130D01*
X1461398Y1510295D01*
G01X1468198Y1495595D02*
X1469263Y1496660D01*
Y1499430D01*
X1468098Y1500595D01*
G01X1459713Y1631377D02*
X1460878Y1630212D01*
Y1628841D01*
X1461278Y1627875D01*
Y1626445D01*
X1460213Y1625380D01*
G01X1463313Y1631377D02*
X1462148Y1630212D01*
Y1629094D01*
X1462548Y1628128D01*
Y1626445D01*
X1463613Y1625380D01*
G01X1459713Y1633477D02*
X1460878Y1634642D01*
Y1651580D01*
X1461278Y1651980D01*
Y1656227D01*
X1460213Y1657292D01*
G01X1463313Y1633477D02*
X1462148Y1634642D01*
Y1651053D01*
X1462548Y1651453D01*
Y1656227D01*
X1463613Y1657292D01*
G01X1469874Y893426D02*
X1471712Y892379D01*
G01X1479126Y896615D02*
X1480964Y895568D01*
G01X1469874Y899804D02*
X1471712Y898757D01*
G01X1469874Y906181D02*
X1471712Y905134D01*
G01X1482827Y896615D02*
X1484665Y895568D01*
G01X1477275Y899804D02*
X1479113Y898757D01*
G01X1469874Y912559D02*
X1471712Y911512D01*
G01X1482827Y915748D02*
X1484665Y914701D01*
G01X1479126Y915748D02*
X1480964Y914701D01*
G01X1477275Y918937D02*
X1479113Y917890D01*
G01X1469874Y925315D02*
X1471712Y924268D01*
G01X1469874Y918937D02*
X1471712Y917890D01*
G01X1482827Y934882D02*
X1484665Y933835D01*
G01X1479126Y934882D02*
X1480964Y933835D01*
G01X1477275Y938071D02*
X1479113Y937024D01*
G01X1469874Y931693D02*
X1471712Y930646D01*
G01X1469874Y950827D02*
X1471712Y949780D01*
G01X1469874Y944449D02*
X1471712Y943402D01*
G01X1482827Y954016D02*
X1484665Y952969D01*
G01X1479126Y954016D02*
X1480964Y952969D01*
G01X1469874Y957205D02*
X1471712Y956158D01*
G01X1477275Y957205D02*
X1479113Y956158D01*
G01X1469874Y969961D02*
X1471712Y968914D01*
G01X1469874Y963583D02*
X1471712Y962536D01*
G01X1482827Y973150D02*
X1484665Y972103D01*
G01X1479126Y973150D02*
X1480964Y972103D01*
G01X1477275Y976339D02*
X1479113Y975292D01*
G01X1469874Y976339D02*
X1471712Y975292D01*
G01X1478457Y1068465D02*
X1480295Y1069512D01*
G01X1480307Y1071654D02*
X1482145Y1072701D01*
G01X1471055Y1062087D02*
X1472893Y1063134D01*
G01X1471055Y1074843D02*
X1472893Y1075890D01*
G01X1471055Y1068465D02*
X1472893Y1069512D01*
G01X1478457Y1087599D02*
X1480295Y1088646D01*
G01X1471055Y1081221D02*
X1472893Y1082268D01*
G01X1471055Y1087599D02*
X1472893Y1088646D01*
G01X1480307Y1090788D02*
X1482145Y1091835D01*
G01X1471055Y1093977D02*
X1472893Y1095024D01*
G01X1478457Y1106733D02*
X1480295Y1107780D01*
G01X1480307Y1109922D02*
X1482145Y1110969D01*
G01X1471055Y1106733D02*
X1472893Y1107780D01*
G01X1471055Y1119489D02*
X1472893Y1120536D01*
G01X1471055Y1113111D02*
X1472893Y1114158D01*
G01X1478457Y1125867D02*
X1480295Y1126914D01*
G01X1480307Y1129056D02*
X1482145Y1130102D01*
G01X1471055Y1132245D02*
X1472893Y1133292D01*
G01X1471055Y1125867D02*
X1472893Y1126914D01*
G01X1478457Y1145000D02*
X1480295Y1146047D01*
G01X1480307Y1148189D02*
X1482145Y1149236D01*
G01X1471055Y1145000D02*
X1472893Y1146047D01*
G01X1471055Y1138622D02*
X1472893Y1139669D01*
G01X1478298Y1485895D02*
X1477233Y1486960D01*
Y1489730D01*
X1478398Y1490895D01*
G01X1474898Y1485895D02*
X1475963Y1486960D01*
Y1489730D01*
X1474798Y1490895D01*
G01X1471598Y1495595D02*
X1470533Y1496660D01*
Y1499430D01*
X1471698Y1500595D01*
G01X1472173Y1640286D02*
X1473338Y1639121D01*
Y1626445D01*
X1472273Y1625380D01*
G01X1475773Y1640286D02*
X1474608Y1639121D01*
Y1626445D01*
X1475673Y1625380D01*
G01X1472173Y1642386D02*
X1473338Y1643551D01*
Y1656227D01*
X1472273Y1657292D01*
G01X1475773Y1642386D02*
X1474608Y1643551D01*
Y1656227D01*
X1475673Y1657292D01*
G01X1484677Y893426D02*
X1486515Y892379D01*
G01X1490228Y896615D02*
X1492066Y895568D01*
G01X1495779Y893426D02*
X1497617Y892379D01*
G01X1497630Y896615D02*
X1499468Y895568D01*
G01X1492079Y899804D02*
X1493917Y898757D01*
G01X1484677Y912559D02*
X1486515Y911512D01*
G01X1497630Y915748D02*
X1499468Y914701D01*
G01X1490228Y915748D02*
X1492066Y914701D01*
G01X1495779Y912559D02*
X1497617Y911512D01*
G01X1492079Y918937D02*
X1493917Y917890D01*
G01X1484677Y931693D02*
X1486515Y930646D01*
G01X1497630Y934882D02*
X1499468Y933835D01*
G01X1490228Y934882D02*
X1492066Y933835D01*
G01X1495779Y931693D02*
X1497617Y930646D01*
G01X1492079Y938071D02*
X1493917Y937024D01*
G01X1484677Y950827D02*
X1486515Y949780D01*
G01X1497630Y954016D02*
X1499468Y952969D01*
G01X1490228Y954016D02*
X1492066Y952969D01*
G01X1495779Y950827D02*
X1497617Y949780D01*
G01X1484677Y969961D02*
X1486515Y968914D01*
G01X1495779Y969961D02*
X1497617Y968914D01*
G01X1492079Y957205D02*
X1493917Y956158D01*
G01X1497630Y973150D02*
X1499468Y972103D01*
G01X1490228Y973150D02*
X1492066Y972103D01*
G01X1492079Y976339D02*
X1493917Y975292D01*
G01X1485858Y1068465D02*
X1487696Y1069512D01*
G01X1484008Y1065276D02*
X1485846Y1066323D01*
G01X1493260Y1068465D02*
X1495098Y1069512D01*
G01X1496960Y1068465D02*
X1498799Y1069512D01*
G01X1491409Y1071654D02*
X1493247Y1072701D01*
G01X1485858Y1087599D02*
X1487696Y1088646D01*
G01X1484008Y1084410D02*
X1485846Y1085457D01*
G01X1496960Y1087599D02*
X1498799Y1088646D01*
G01X1493260Y1087599D02*
X1495098Y1088646D01*
G01X1484008Y1103544D02*
X1485846Y1104591D01*
G01X1491409Y1090788D02*
X1493247Y1091835D01*
G01X1485858Y1106733D02*
X1487696Y1107780D01*
G01X1496960Y1106733D02*
X1498799Y1107780D01*
G01X1493260Y1106733D02*
X1495098Y1107780D01*
G01X1491409Y1109922D02*
X1493247Y1110969D01*
G01X1485858Y1125867D02*
X1487696Y1126914D01*
G01X1484008Y1122678D02*
X1485846Y1123725D01*
G01X1496960Y1125867D02*
X1498799Y1126914D01*
G01X1493260Y1125867D02*
X1495098Y1126914D01*
G01X1491409Y1129056D02*
X1493247Y1130102D01*
G01X1485858Y1145000D02*
X1487696Y1146047D01*
G01X1484008Y1141811D02*
X1485846Y1142858D01*
G01X1496960Y1145000D02*
X1498799Y1146047D01*
G01X1493260Y1145000D02*
X1495098Y1146047D01*
G01X1491409Y1148189D02*
X1493247Y1149236D01*
G01X1491698Y1505295D02*
X1490633Y1506360D01*
Y1509130D01*
X1491798Y1510295D01*
G01X1488298Y1505295D02*
X1489363Y1506360D01*
Y1509130D01*
X1488198Y1510295D01*
G01X1498398Y1495595D02*
X1497333Y1496660D01*
Y1499430D01*
X1498498Y1500595D01*
G01X1494998Y1495595D02*
X1496063Y1496660D01*
Y1499430D01*
X1494898Y1500595D01*
G01X1484233Y1640286D02*
X1485398Y1639121D01*
Y1626445D01*
X1484333Y1625380D01*
G01X1496293Y1640286D02*
X1497458Y1639121D01*
Y1626445D01*
X1496393Y1625380D01*
G01X1487833Y1640286D02*
X1486668Y1639121D01*
Y1626445D01*
X1487733Y1625380D01*
G01X1484233Y1642386D02*
X1485398Y1643551D01*
Y1656227D01*
X1484333Y1657292D01*
G01X1496293Y1642386D02*
X1497458Y1643551D01*
Y1656227D01*
X1496393Y1657292D01*
G01X1487833Y1642386D02*
X1486668Y1643551D01*
Y1656227D01*
X1487733Y1657292D01*
G01X1510583Y880670D02*
X1512421Y879623D01*
G01X1512433Y877481D02*
X1514271Y876434D01*
G01X1508732Y896615D02*
X1510570Y895568D01*
G01X1505031Y896615D02*
X1506869Y895568D01*
G01X1510583Y893426D02*
X1512421Y892379D01*
G01X1503181Y899804D02*
X1505019Y898757D01*
G01X1508732Y915748D02*
X1510570Y914701D01*
G01X1505031Y915748D02*
X1506869Y914701D01*
G01X1510583Y912559D02*
X1512421Y911512D01*
G01X1503181Y918937D02*
X1505019Y917890D01*
G01X1508732Y934882D02*
X1510570Y933835D01*
G01X1505031Y934882D02*
X1506869Y933835D01*
G01X1510583Y931693D02*
X1512421Y930646D01*
G01X1503181Y938071D02*
X1505019Y937024D01*
G01X1508732Y954016D02*
X1510570Y952969D01*
G01X1505031Y954016D02*
X1506869Y952969D01*
G01X1510583Y950827D02*
X1512421Y949780D01*
G01X1510583Y969961D02*
X1512421Y968914D01*
G01X1503181Y957205D02*
X1505019Y956158D01*
G01X1508732Y973150D02*
X1510570Y972103D01*
G01X1505031Y973150D02*
X1506869Y972103D01*
G01X1503181Y976339D02*
X1505019Y975292D01*
G01X1504362Y1068465D02*
X1506200Y1069512D01*
G01X1511764Y1068465D02*
X1513602Y1069512D01*
G01X1506212Y1071654D02*
X1508050Y1072701D01*
G01X1509913Y1065276D02*
X1511751Y1066323D01*
G01X1498811Y1065276D02*
X1500649Y1066323D01*
G01X1511764Y1087599D02*
X1513602Y1088646D01*
G01X1504362Y1087599D02*
X1506200Y1088646D01*
G01X1509913Y1084410D02*
X1511751Y1085457D01*
G01X1498811Y1084410D02*
X1500649Y1085457D01*
G01X1509913Y1103544D02*
X1511751Y1104591D01*
G01X1506212Y1090788D02*
X1508050Y1091835D01*
G01X1498811Y1103544D02*
X1500649Y1104591D01*
G01X1511764Y1106733D02*
X1513602Y1107780D01*
G01X1504362Y1106733D02*
X1506200Y1107780D01*
G01X1506212Y1109922D02*
X1508050Y1110969D01*
G01X1511764Y1125867D02*
X1513602Y1126914D01*
G01X1504362Y1125867D02*
X1506200Y1126914D01*
G01X1509913Y1122678D02*
X1511751Y1123725D01*
G01X1506212Y1129056D02*
X1508050Y1130102D01*
G01X1498811Y1122678D02*
X1500649Y1123725D01*
G01X1511764Y1145000D02*
X1513602Y1146047D01*
G01X1504362Y1145000D02*
X1506200Y1146047D01*
G01X1509913Y1141811D02*
X1511751Y1142858D01*
G01X1506212Y1148189D02*
X1508050Y1149236D01*
G01X1498811Y1141811D02*
X1500649Y1142858D01*
G01X1505098Y1485895D02*
X1504033Y1486960D01*
Y1489730D01*
X1505198Y1490895D01*
G01X1501698Y1485895D02*
X1502763Y1486960D01*
Y1489730D01*
X1501598Y1490895D01*
G01X1508353Y1640286D02*
X1509518Y1639121D01*
Y1626445D01*
X1508453Y1625380D01*
G01X1499893Y1640286D02*
X1498728Y1639121D01*
Y1626445D01*
X1499793Y1625380D01*
G01X1511953Y1640286D02*
X1510788Y1639121D01*
Y1626445D01*
X1511853Y1625380D01*
G01X1508353Y1642386D02*
X1509518Y1643551D01*
Y1656227D01*
X1508453Y1657292D01*
G01X1499893Y1642386D02*
X1498728Y1643551D01*
Y1656227D01*
X1499793Y1657292D01*
G01X1511953Y1642386D02*
X1510788Y1643551D01*
Y1656227D01*
X1511853Y1657292D01*
G01X1533454Y88146D02*
X1534809Y86791D01*
Y77770D01*
X1525785Y68746D01*
Y51462D01*
X1531555Y45692D01*
Y29689D01*
X1537069Y24175D01*
X1541991D01*
X1544520Y26704D01*
Y29805D01*
X1545066Y30351D01*
Y32756D01*
G01X1542704D02*
Y30351D01*
X1543250Y29805D01*
Y27231D01*
X1541464Y25445D01*
X1537596D01*
X1536036Y27005D01*
Y28066D01*
X1534960Y29142D01*
X1533899D01*
X1532825Y30216D01*
Y31736D01*
X1533575Y32486D01*
Y34006D01*
X1532825Y34756D01*
Y36276D01*
X1533575Y37026D01*
Y38546D01*
X1532825Y39296D01*
Y41679D01*
X1533575Y42429D01*
Y43949D01*
X1532825Y44699D01*
Y46219D01*
X1531751Y47293D01*
Y48354D01*
X1530675Y49430D01*
X1529614D01*
X1527055Y51989D01*
Y53509D01*
X1527805Y54259D01*
Y55779D01*
X1527055Y56529D01*
Y58049D01*
X1527805Y58799D01*
Y60319D01*
X1527055Y61069D01*
Y68219D01*
X1536079Y77243D01*
Y86771D01*
X1537454Y88146D01*
G01X1525386Y874292D02*
X1527224Y873245D01*
G01X1514283Y874292D02*
X1516121Y873245D01*
G01X1517984Y874292D02*
X1519822Y873245D01*
G01X1521685Y880670D02*
X1523523Y879623D01*
G01X1523535Y877481D02*
X1525373Y876434D01*
G01X1523535Y896615D02*
X1525373Y895568D01*
G01X1516134Y896615D02*
X1517972Y895568D01*
G01X1521685Y893426D02*
X1523523Y892379D01*
G01X1517984Y899804D02*
X1519822Y898757D01*
G01X1523535Y915748D02*
X1525373Y914701D01*
G01X1516134Y915748D02*
X1517972Y914701D01*
G01X1521685Y912559D02*
X1523523Y911512D01*
G01X1517984Y918937D02*
X1519822Y917890D01*
G01X1523535Y934882D02*
X1525373Y933835D01*
G01X1516134Y934882D02*
X1517972Y933835D01*
G01X1521685Y931693D02*
X1523523Y930646D01*
G01X1517984Y938071D02*
X1519822Y937024D01*
G01X1523535Y954016D02*
X1525373Y952969D01*
G01X1516134Y954016D02*
X1517972Y952969D01*
G01X1521685Y950827D02*
X1523523Y949780D01*
G01X1521685Y969961D02*
X1523523Y968914D01*
G01X1517984Y957205D02*
X1519822Y956158D01*
G01X1523535Y973150D02*
X1525373Y972103D01*
G01X1516134Y973150D02*
X1517972Y972103D01*
G01X1517984Y976339D02*
X1519822Y975292D01*
G01X1519165Y1068465D02*
X1521003Y1069512D01*
G01X1522866Y1068465D02*
X1524704Y1069512D01*
G01X1517315Y1071654D02*
X1519153Y1072701D01*
G01X1524716Y1065276D02*
X1526554Y1066323D01*
G01X1522866Y1087599D02*
X1524704Y1088646D01*
G01X1519165Y1087599D02*
X1521003Y1088646D01*
G01X1524716Y1084410D02*
X1526554Y1085457D01*
G01X1524716Y1103544D02*
X1526554Y1104591D01*
G01X1517315Y1090788D02*
X1519153Y1091835D01*
G01X1522866Y1106733D02*
X1524704Y1107780D01*
G01X1519165Y1106733D02*
X1521003Y1107780D01*
G01X1517315Y1109922D02*
X1519153Y1110969D01*
G01X1522866Y1125867D02*
X1524704Y1126914D01*
G01X1519165Y1125867D02*
X1521003Y1126914D01*
G01X1524716Y1122678D02*
X1526554Y1123725D01*
G01X1517315Y1129056D02*
X1519153Y1130102D01*
G01X1522866Y1145000D02*
X1524704Y1146047D01*
G01X1519165Y1145000D02*
X1521003Y1146047D01*
G01X1524716Y1141811D02*
X1526554Y1142858D01*
G01X1517315Y1148189D02*
X1519153Y1149236D01*
G01X1518498Y1505295D02*
X1517433Y1506360D01*
Y1509130D01*
X1518598Y1510295D01*
G01X1525198Y1495595D02*
X1524133Y1496660D01*
Y1499430D01*
X1525298Y1500595D01*
G01X1515098Y1505295D02*
X1516163Y1506360D01*
Y1509130D01*
X1514998Y1510295D01*
G01X1521798Y1495595D02*
X1522863Y1496660D01*
Y1499430D01*
X1521698Y1500595D01*
G01X1520413Y1640286D02*
X1521578Y1639121D01*
Y1626445D01*
X1520513Y1625380D01*
G01X1524013Y1640286D02*
X1522848Y1639121D01*
Y1626445D01*
X1523913Y1625380D01*
G01X1520413Y1642386D02*
X1521578Y1643551D01*
Y1656227D01*
X1520513Y1657292D01*
G01X1524013Y1642386D02*
X1522848Y1643551D01*
Y1656227D01*
X1523913Y1657292D01*
G01X1536566Y-23228D02*
X1539134Y-22512D01*
G01X1536566Y-25196D02*
X1539134Y-25912D01*
G01X1535462Y62337D02*
X1536631Y61168D01*
Y60523D01*
X1537210Y59126D01*
X1538302Y58034D01*
X1547686Y51763D01*
X1549593Y49856D01*
X1550337Y48062D01*
Y47322D01*
X1549791Y46776D01*
Y44370D01*
G01X1539062Y62337D02*
X1537901Y61176D01*
Y60776D01*
X1538287Y59846D01*
X1539112Y59021D01*
X1548496Y52750D01*
X1550670Y50576D01*
X1551607Y48315D01*
Y47322D01*
X1552153Y46776D01*
Y44370D01*
G01X1535462Y64437D02*
X1536624Y65599D01*
X1536631D01*
Y68275D01*
X1535566Y69340D01*
G01X1539062Y64437D02*
X1537901Y65598D01*
Y68275D01*
X1538966Y69340D01*
G01X1701661Y644554D02*
X1702976Y643239D01*
Y620052D01*
X1685789Y578558D01*
Y521731D01*
X1645606Y481548D01*
X1631137Y446617D01*
X1604378Y312087D01*
Y292511D01*
X1612572Y284317D01*
Y223742D01*
X1576917Y137664D01*
X1534819Y95566D01*
Y92661D01*
X1533454Y91296D01*
G01X1705561Y644554D02*
X1704246Y643239D01*
Y619799D01*
X1687059Y578305D01*
Y521204D01*
X1646683Y480828D01*
X1632359Y446246D01*
X1605648Y311961D01*
Y293038D01*
X1613842Y284844D01*
Y223489D01*
X1577994Y136944D01*
X1536089Y95039D01*
Y92661D01*
X1537454Y91296D01*
G01X1529086Y874292D02*
X1530924Y873245D01*
G01X1532787Y880670D02*
X1534625Y879623D01*
G01X1534638Y877481D02*
X1536476Y876434D01*
G01X1534638Y896615D02*
X1536476Y895568D01*
G01X1530937Y896615D02*
X1532775Y895568D01*
G01X1536488Y893426D02*
X1538326Y892379D01*
G01X1556105Y894387D02*
X1565957Y884531D01*
Y847947D01*
X1603225Y810679D01*
X1606447D01*
X1607007Y810119D01*
Y809340D01*
X1605049Y807382D01*
Y805546D01*
X1606348Y804247D01*
X1608184D01*
X1610141Y806204D01*
X1610922D01*
X1611482Y805644D01*
Y804865D01*
X1609579Y802962D01*
Y801126D01*
X1610878Y799827D01*
X1612714D01*
X1614616Y801729D01*
X1615397D01*
X1615957Y801169D01*
Y800390D01*
X1614283Y798716D01*
Y796942D01*
X1616544Y794681D01*
X1620260D01*
X1621299Y793642D01*
X1623496D01*
G01X1529086Y899804D02*
X1530925Y898757D01*
G01X1556149Y916458D02*
X1558837D01*
X1584167Y891128D01*
Y865492D01*
X1604189Y845470D01*
Y844686D01*
X1602291Y842788D01*
Y840954D01*
X1603594Y839651D01*
X1605428D01*
X1607326Y841549D01*
X1608110D01*
X1608664Y840995D01*
Y840211D01*
X1606766Y838313D01*
Y836479D01*
X1608069Y835176D01*
X1609903D01*
X1611801Y837074D01*
X1612585D01*
X1613139Y836520D01*
Y835736D01*
X1611241Y833838D01*
Y832004D01*
X1612544Y830701D01*
X1614378D01*
X1616276Y832599D01*
X1617060D01*
X1618167Y831492D01*
X1620260D01*
X1621299Y830453D01*
X1623496D01*
G01X1534638Y915748D02*
X1536476Y914701D01*
G01X1530937Y915748D02*
X1532775Y914701D01*
G01X1536488Y912559D02*
X1538326Y911512D01*
G01X1529086Y918937D02*
X1530925Y917890D01*
G01X1557052Y936345D02*
X1563544D01*
X1601662Y898227D01*
Y883643D01*
X1602950Y882355D01*
X1604724D01*
X1607492Y885123D01*
X1608272D01*
X1608832Y884563D01*
Y883783D01*
X1606196Y881147D01*
Y879309D01*
X1607493Y878012D01*
X1609331D01*
X1611591Y880272D01*
X1612371D01*
X1612931Y879712D01*
Y878932D01*
X1611021Y877022D01*
Y875184D01*
X1612318Y873887D01*
X1614156D01*
X1615104Y874835D01*
X1615884D01*
X1616444Y874275D01*
Y873495D01*
X1615534Y872585D01*
Y870811D01*
X1618042Y868303D01*
X1620260D01*
X1621299Y867264D01*
X1623496D01*
G01X1534638Y934882D02*
X1536476Y933835D01*
G01X1530937Y934882D02*
X1532775Y933835D01*
G01X1536488Y931693D02*
X1538326Y930646D01*
G01X1529086Y938071D02*
X1530925Y937024D01*
G01X1557540Y956125D02*
X1573215D01*
X1592581Y936759D01*
X1596949D01*
X1608956Y924752D01*
Y923972D01*
X1605623Y920639D01*
Y918801D01*
X1606920Y917504D01*
X1608758D01*
X1611472Y920218D01*
X1612252D01*
X1612812Y919658D01*
Y918878D01*
X1610098Y916164D01*
Y914326D01*
X1619310Y905114D01*
X1620260D01*
X1621299Y904075D01*
X1623496D01*
G01X1534638Y954016D02*
X1536476Y952969D01*
G01X1530937Y954016D02*
X1532775Y952969D01*
G01X1536488Y950827D02*
X1538326Y949780D01*
G01X1536488Y969961D02*
X1538326Y968914D01*
G01X1529086Y957205D02*
X1530925Y956158D01*
G01X1556519Y973700D02*
X1591437D01*
X1603002Y962135D01*
Y959649D01*
X1601931Y958578D01*
Y956744D01*
X1603234Y955441D01*
X1605068D01*
X1606139Y956512D01*
X1606923D01*
X1607477Y955958D01*
Y955174D01*
X1606406Y954103D01*
Y952269D01*
X1607709Y950966D01*
X1609543D01*
X1610614Y952037D01*
X1611398D01*
X1611952Y951483D01*
Y950699D01*
X1610881Y949628D01*
Y947794D01*
X1612184Y946491D01*
X1614018D01*
X1615089Y947562D01*
X1615873D01*
X1616637Y946798D01*
Y943478D01*
X1618190Y941925D01*
X1620260D01*
X1621299Y940886D01*
X1623496D01*
G01X1534638Y973150D02*
X1536476Y972103D01*
G01X1530937Y973150D02*
X1532775Y972103D01*
G01X1529086Y976339D02*
X1530925Y975292D01*
G01X1530268Y1068465D02*
X1532106Y1069512D01*
G01X1537669Y1068465D02*
X1539507Y1069512D01*
G01X1532118Y1071654D02*
X1533956Y1072701D01*
G01X1535819Y1065276D02*
X1537657Y1066323D01*
G01X1537669Y1087599D02*
X1539507Y1088646D01*
G01X1530268Y1087599D02*
X1532106Y1088646D01*
G01X1535819Y1084410D02*
X1537657Y1085457D01*
G01X1535819Y1103544D02*
X1537657Y1104591D01*
G01X1532118Y1090788D02*
X1533956Y1091835D01*
G01X1537669Y1106733D02*
X1539507Y1107780D01*
G01X1530268Y1106733D02*
X1532106Y1107780D01*
G01X1532118Y1109922D02*
X1533956Y1110969D01*
G01X1537669Y1125867D02*
X1539507Y1126914D01*
G01X1530268Y1125867D02*
X1532106Y1126914D01*
G01X1535819Y1122678D02*
X1537657Y1123725D01*
G01X1532118Y1129056D02*
X1533956Y1130102D01*
G01X1537669Y1145000D02*
X1539507Y1146047D01*
G01X1530268Y1145000D02*
X1532106Y1146047D01*
G01X1535819Y1141811D02*
X1537657Y1142858D01*
G01X1532118Y1148189D02*
X1533956Y1149236D01*
G01X1531898Y1485895D02*
X1530833Y1486960D01*
Y1489730D01*
X1531998Y1490895D01*
G01X1528498Y1485895D02*
X1529563Y1486960D01*
Y1489730D01*
X1528398Y1490895D01*
G01X1541798D02*
X1542963Y1489730D01*
Y1486960D01*
X1541898Y1485895D01*
G01X1532473Y1640286D02*
X1533638Y1639121D01*
Y1626445D01*
X1532573Y1625380D01*
G01X1536073Y1640286D02*
X1534908Y1639121D01*
Y1626445D01*
X1535973Y1625380D01*
G01X1532473Y1642386D02*
X1533638Y1643551D01*
Y1656227D01*
X1532573Y1657292D01*
G01X1536073Y1642386D02*
X1534908Y1643551D01*
Y1656227D01*
X1535973Y1657292D01*
G01X1552153Y32756D02*
Y30351D01*
X1551607Y29805D01*
Y27544D01*
X1552674Y26477D01*
G01X1556877Y32756D02*
Y30351D01*
X1557423Y29805D01*
Y20585D01*
X1556379Y19541D01*
G01X1549791Y32756D02*
Y30351D01*
X1550337Y29805D01*
Y27540D01*
X1549274Y26477D01*
G01X1546462Y68337D02*
X1547631Y67168D01*
Y65800D01*
X1548535Y63616D01*
X1556487Y51716D01*
X1557423Y48632D01*
Y47322D01*
X1556877Y46776D01*
Y44370D01*
G01X1550062Y68337D02*
X1548901Y67176D01*
Y66053D01*
X1549661Y64217D01*
X1557648Y52265D01*
X1558693Y48821D01*
Y47322D01*
X1559240Y46775D01*
Y44370D01*
G01X1557462Y64437D02*
X1557469D01*
X1558631Y65599D01*
Y68275D01*
X1557566Y69340D01*
G01X1546462Y70437D02*
X1547631Y71606D01*
Y74274D01*
X1546562Y75343D01*
G01X1550062Y70437D02*
X1548901Y71598D01*
Y74282D01*
X1549962Y75343D01*
G01X1557462Y62337D02*
X1557463D01*
X1558631Y61169D01*
Y60220D01*
X1558901Y59566D01*
X1562253Y54549D01*
X1563549Y51807D01*
X1564510Y48642D01*
Y47322D01*
X1563964Y46776D01*
Y44370D01*
G01X1557569Y890204D02*
X1564237Y883535D01*
Y847319D01*
X1596767Y814789D01*
Y810795D01*
X1597884Y809678D01*
X1598818D01*
X1599901Y808595D01*
Y807661D01*
X1600982Y806580D01*
X1601916D01*
X1602999Y805497D01*
Y804563D01*
X1616628Y790934D01*
X1619070D01*
X1620105Y791969D01*
G01X1556670Y889305D02*
X1562967Y883008D01*
Y846792D01*
X1595497Y814262D01*
Y810268D01*
X1616101Y789664D01*
X1619064D01*
X1620105Y788623D01*
G01X1557004Y895285D02*
X1567227Y885057D01*
Y848474D01*
X1600654Y815047D01*
X1601588D01*
X1602671Y813964D01*
Y813030D01*
X1603752Y811949D01*
X1606974D01*
X1608277Y810646D01*
Y808813D01*
X1606319Y806855D01*
Y806073D01*
X1606875Y805517D01*
X1607657D01*
X1609614Y807474D01*
X1611449D01*
X1612752Y806171D01*
Y804338D01*
X1610849Y802435D01*
Y801653D01*
X1611405Y801097D01*
X1612187D01*
X1614089Y802999D01*
X1615924D01*
X1617227Y801696D01*
Y799863D01*
X1615553Y798189D01*
Y797469D01*
X1617071Y795951D01*
X1620264D01*
X1621302Y796989D01*
X1621303Y796988D01*
X1623496D01*
G01X1557752Y913988D02*
X1558904D01*
X1582507Y890385D01*
Y864803D01*
X1586982Y860328D01*
Y858000D01*
X1587687Y857295D01*
X1590015D01*
X1591457Y855853D01*
Y853525D01*
X1592162Y852820D01*
X1594490D01*
X1595932Y851378D01*
Y849050D01*
X1596637Y848345D01*
X1598965D01*
X1600631Y846679D01*
Y840215D01*
X1612981Y827865D01*
X1614810D01*
X1615470Y828525D01*
X1617000D01*
X1617660Y827865D01*
X1619190D01*
X1620105Y828780D01*
G01X1557752Y912718D02*
X1558377D01*
X1581237Y889858D01*
Y864276D01*
X1585712Y859801D01*
Y857473D01*
X1587160Y856025D01*
X1589488D01*
X1590187Y855326D01*
Y852998D01*
X1591635Y851550D01*
X1593963D01*
X1594662Y850851D01*
Y848523D01*
X1596110Y847075D01*
X1598438D01*
X1599361Y846152D01*
Y839688D01*
X1612454Y826595D01*
X1618944D01*
X1620105Y825434D01*
G01X1556149Y917728D02*
X1559364D01*
X1585437Y891655D01*
Y866019D01*
X1605459Y845997D01*
Y844159D01*
X1603561Y842261D01*
Y841481D01*
X1604121Y840921D01*
X1604901D01*
X1606799Y842819D01*
X1608637D01*
X1609934Y841522D01*
Y839684D01*
X1608036Y837786D01*
Y837006D01*
X1608596Y836446D01*
X1609376D01*
X1611274Y838344D01*
X1613112D01*
X1614409Y837047D01*
Y835209D01*
X1612511Y833311D01*
Y832531D01*
X1613071Y831971D01*
X1613851D01*
X1615749Y833869D01*
X1617587D01*
X1618694Y832762D01*
X1620264D01*
X1621302Y833800D01*
X1621303Y833799D01*
X1623496D01*
G01X1556844Y934625D02*
X1562899D01*
X1600002Y897522D01*
Y882834D01*
X1601419Y881417D01*
Y879473D01*
X1602386Y878506D01*
X1604330D01*
X1605894Y876942D01*
Y875298D01*
X1607161Y874031D01*
X1608805D01*
X1610369Y872467D01*
Y870813D01*
X1611626Y869556D01*
X1613280D01*
X1614844Y867992D01*
Y865908D01*
X1616196Y864556D01*
X1619070D01*
X1620105Y865591D01*
G01X1556844Y933355D02*
X1562372D01*
X1598732Y896995D01*
Y882307D01*
X1600149Y880890D01*
Y878946D01*
X1601859Y877236D01*
X1603803D01*
X1604624Y876415D01*
Y874771D01*
X1606634Y872761D01*
X1608278D01*
X1609099Y871940D01*
Y870286D01*
X1611099Y868286D01*
X1612753D01*
X1613574Y867465D01*
Y865381D01*
X1615669Y863286D01*
X1619064D01*
X1620105Y862245D01*
G01X1557052Y937615D02*
X1564071D01*
X1602932Y898754D01*
Y884170D01*
X1603477Y883625D01*
X1604197D01*
X1606965Y886393D01*
X1608799D01*
X1610102Y885090D01*
Y883256D01*
X1607466Y880620D01*
Y879836D01*
X1608020Y879282D01*
X1608804D01*
X1611064Y881542D01*
X1612898D01*
X1614201Y880239D01*
Y878405D01*
X1612291Y876495D01*
Y875711D01*
X1612845Y875157D01*
X1613629D01*
X1614577Y876105D01*
X1616411D01*
X1617714Y874802D01*
Y872968D01*
X1616804Y872058D01*
Y871338D01*
X1618569Y869573D01*
X1620264D01*
X1621302Y870611D01*
X1621303Y870610D01*
X1623496D01*
G01X1557342Y954106D02*
X1572886D01*
X1591893Y935099D01*
X1596087D01*
X1603807Y927379D01*
Y918179D01*
X1617777Y904209D01*
Y901916D01*
X1618326Y901367D01*
X1619070D01*
X1620105Y902402D01*
G01X1557342Y952836D02*
X1572359D01*
X1591366Y933829D01*
X1595560D01*
X1602537Y926852D01*
Y917652D01*
X1616507Y903682D01*
Y901389D01*
X1617799Y900097D01*
X1619064D01*
X1620105Y899056D01*
G01X1556532Y970668D02*
X1590323D01*
X1599001Y961990D01*
Y955454D01*
X1617547Y936908D01*
X1619064D01*
X1620105Y935867D01*
G01X1557540Y957395D02*
X1573742D01*
X1593108Y938029D01*
X1597476D01*
X1610226Y925279D01*
Y923445D01*
X1606893Y920112D01*
Y919328D01*
X1607447Y918774D01*
X1608231D01*
X1610945Y921488D01*
X1612779D01*
X1614082Y920185D01*
Y918351D01*
X1611368Y915637D01*
Y914853D01*
X1619837Y906384D01*
X1620264D01*
X1621302Y907422D01*
X1623496D01*
G01X1556532Y971938D02*
X1590850D01*
X1600271Y962517D01*
Y955981D01*
X1618074Y938178D01*
X1619070D01*
X1620105Y939213D01*
G01X1556519Y974970D02*
X1591964D01*
X1604272Y962662D01*
Y959122D01*
X1603201Y958051D01*
Y957271D01*
X1603761Y956711D01*
X1604541D01*
X1605612Y957782D01*
X1607450D01*
X1608747Y956485D01*
Y954647D01*
X1607676Y953576D01*
Y952796D01*
X1608236Y952236D01*
X1609016D01*
X1610087Y953307D01*
X1611925D01*
X1613222Y952010D01*
Y950172D01*
X1612151Y949101D01*
Y948321D01*
X1612711Y947761D01*
X1613491D01*
X1614562Y948832D01*
X1616400D01*
X1617907Y947325D01*
Y944005D01*
X1618717Y943195D01*
X1620264D01*
X1621302Y944233D01*
X1623496D01*
G01X1558501Y1068476D02*
X1596719D01*
X1597690Y1069447D01*
X1598474D01*
X1599445Y1068476D01*
X1601279D01*
X1602582Y1069779D01*
Y1071613D01*
X1600929Y1073266D01*
Y1074050D01*
X1601483Y1074604D01*
X1602267D01*
X1604339Y1072532D01*
X1606173D01*
X1607476Y1073835D01*
Y1075669D01*
X1605372Y1077773D01*
Y1078493D01*
X1606516Y1079637D01*
X1608836D01*
X1610288Y1081089D01*
Y1083409D01*
X1610991Y1084112D01*
X1613311D01*
X1614763Y1085564D01*
Y1087884D01*
X1616048Y1089169D01*
X1620260D01*
X1621299Y1088130D01*
X1623496D01*
G01X1557120Y1066816D02*
X1604248D01*
X1609136Y1071704D01*
Y1077416D01*
X1617142Y1085422D01*
X1619070D01*
X1620105Y1086457D01*
G01X1558501Y1069746D02*
X1596192D01*
X1597163Y1070717D01*
X1599001D01*
X1599972Y1069746D01*
X1600752D01*
X1601312Y1070306D01*
Y1071086D01*
X1599659Y1072739D01*
Y1074577D01*
X1600956Y1075874D01*
X1602794D01*
X1604866Y1073802D01*
X1605646D01*
X1606206Y1074362D01*
Y1075142D01*
X1604102Y1077246D01*
Y1079020D01*
X1605989Y1080907D01*
X1608309D01*
X1609018Y1081616D01*
Y1083936D01*
X1610464Y1085382D01*
X1612784D01*
X1613493Y1086091D01*
Y1088411D01*
X1615521Y1090439D01*
X1620264D01*
X1621302Y1091477D01*
X1623496D01*
G01X1557120Y1065546D02*
X1604775D01*
X1610406Y1071177D01*
Y1076889D01*
X1617669Y1084152D01*
X1619064D01*
X1620105Y1083111D01*
G01X1558501Y1086548D02*
X1585432D01*
X1611208Y1112324D01*
Y1113106D01*
X1610240Y1114075D01*
Y1115909D01*
X1611544Y1117213D01*
X1613376Y1117212D01*
X1614345Y1116243D01*
X1615127D01*
X1616357Y1117473D01*
Y1120980D01*
X1617610Y1122233D01*
X1619070D01*
X1620105Y1123268D01*
G01X1558501Y1088243D02*
X1584660D01*
X1594638Y1098221D01*
Y1099997D01*
X1593609Y1101026D01*
Y1101809D01*
X1594165Y1102365D01*
X1594947D01*
X1595948Y1101365D01*
X1597782D01*
X1599086Y1102669D01*
X1599085Y1104501D01*
X1598084Y1105502D01*
Y1106284D01*
X1598640Y1106840D01*
X1599422D01*
X1600423Y1105840D01*
X1602257D01*
X1603561Y1107144D01*
X1603560Y1108976D01*
X1602559Y1109977D01*
Y1110759D01*
X1603115Y1111315D01*
X1603897D01*
X1604898Y1110315D01*
X1606732D01*
X1608036Y1111619D01*
X1608035Y1113451D01*
X1607034Y1114452D01*
Y1115234D01*
X1617780Y1125980D01*
X1620260D01*
X1621299Y1124941D01*
X1623496D01*
G01X1558501Y1085278D02*
X1585959D01*
X1612478Y1111797D01*
Y1113632D01*
X1611510Y1114601D01*
Y1115382D01*
X1612070Y1115942D01*
X1612849Y1115941D01*
X1613818Y1114973D01*
X1615654D01*
X1617627Y1116946D01*
Y1120453D01*
X1618137Y1120963D01*
X1619064D01*
X1620105Y1119922D01*
G01X1558501Y1089513D02*
X1584133D01*
X1593368Y1098748D01*
Y1099470D01*
X1592339Y1100499D01*
Y1102336D01*
X1593638Y1103635D01*
X1595473D01*
X1596474Y1102635D01*
X1597255D01*
X1597815Y1103195D01*
X1597814Y1103974D01*
X1596814Y1104975D01*
Y1106811D01*
X1598113Y1108110D01*
X1599948D01*
X1600949Y1107110D01*
X1601730D01*
X1602290Y1107670D01*
X1602289Y1108449D01*
X1601289Y1109450D01*
Y1111286D01*
X1602588Y1112585D01*
X1604423D01*
X1605424Y1111585D01*
X1606205D01*
X1606765Y1112145D01*
X1606764Y1112924D01*
X1605764Y1113925D01*
Y1115761D01*
X1617253Y1127250D01*
X1620264D01*
X1621302Y1128288D01*
X1623496D01*
G01X1558501Y1104511D02*
X1569633D01*
X1607480Y1142358D01*
Y1143318D01*
X1605252Y1145546D01*
Y1147384D01*
X1606549Y1148681D01*
X1608387D01*
X1610615Y1146453D01*
X1611395D01*
X1611955Y1147013D01*
Y1147793D01*
X1609727Y1150021D01*
Y1151859D01*
X1616912Y1159044D01*
X1619070D01*
X1620105Y1160079D01*
G01X1558501Y1103241D02*
X1570160D01*
X1608750Y1141831D01*
Y1143845D01*
X1606522Y1146073D01*
Y1146857D01*
X1607076Y1147411D01*
X1607860D01*
X1610088Y1145183D01*
X1611922D01*
X1613225Y1146486D01*
Y1148320D01*
X1610997Y1150548D01*
Y1151332D01*
X1617439Y1157774D01*
X1619064D01*
X1620105Y1156733D01*
G01X1558501Y1106656D02*
X1569430D01*
X1603592Y1140818D01*
Y1148072D01*
X1604832Y1149312D01*
Y1151150D01*
X1603229Y1152753D01*
Y1153533D01*
X1603789Y1154093D01*
X1604569D01*
X1606172Y1152490D01*
X1608010D01*
X1609307Y1153787D01*
Y1155625D01*
X1607704Y1157228D01*
Y1158008D01*
X1608264Y1158568D01*
X1609044D01*
X1610647Y1156965D01*
X1612485D01*
X1613782Y1158262D01*
Y1160100D01*
X1612179Y1161703D01*
Y1162483D01*
X1612739Y1163043D01*
X1613519D01*
X1615122Y1161440D01*
X1616960D01*
X1618311Y1162791D01*
X1620260D01*
X1621299Y1161752D01*
X1623496D01*
G01X1558501Y1107926D02*
X1568903D01*
X1602322Y1141345D01*
Y1148599D01*
X1603562Y1149839D01*
Y1150623D01*
X1601959Y1152226D01*
Y1154060D01*
X1603262Y1155363D01*
X1605096D01*
X1606699Y1153760D01*
X1607483D01*
X1608037Y1154314D01*
Y1155098D01*
X1606434Y1156701D01*
Y1158535D01*
X1607737Y1159838D01*
X1609571D01*
X1611174Y1158235D01*
X1611958D01*
X1612512Y1158789D01*
Y1159573D01*
X1610909Y1161176D01*
Y1163010D01*
X1612212Y1164313D01*
X1614046D01*
X1615649Y1162710D01*
X1616433D01*
X1617784Y1164061D01*
X1620264D01*
X1621302Y1165099D01*
X1623496D01*
G01X1558501Y1124718D02*
X1564880D01*
X1582178Y1142016D01*
Y1159660D01*
X1609074Y1186556D01*
Y1187292D01*
X1608309Y1188057D01*
Y1189895D01*
X1609606Y1191192D01*
X1611444D01*
X1612209Y1190427D01*
X1612989D01*
X1613549Y1190987D01*
Y1191767D01*
X1612784Y1192532D01*
Y1194370D01*
X1614269Y1195855D01*
X1619070D01*
X1620105Y1196890D01*
G01X1558501Y1126405D02*
X1564172D01*
X1580518Y1142751D01*
Y1164452D01*
X1583348Y1167282D01*
X1584132D01*
X1584734Y1166680D01*
X1586568Y1166681D01*
X1587872Y1167985D01*
X1587871Y1169817D01*
X1587268Y1170420D01*
Y1171202D01*
X1587823Y1171757D01*
X1588607D01*
X1589209Y1171155D01*
X1591043Y1171156D01*
X1592347Y1172460D01*
X1592346Y1174292D01*
X1591743Y1174895D01*
Y1175677D01*
X1592298Y1176232D01*
X1593082D01*
X1593684Y1175630D01*
X1595518Y1175631D01*
X1596822Y1176935D01*
X1596821Y1178767D01*
X1596218Y1179370D01*
Y1180152D01*
X1596773Y1180707D01*
X1597557D01*
X1598159Y1180105D01*
X1599993Y1180106D01*
X1601297Y1181410D01*
X1601296Y1183242D01*
X1600693Y1183845D01*
Y1184627D01*
X1601248Y1185182D01*
X1602032D01*
X1602634Y1184580D01*
X1604468Y1184581D01*
X1605772Y1185885D01*
X1605771Y1187717D01*
X1605168Y1188320D01*
Y1189102D01*
X1615668Y1199602D01*
X1620260D01*
X1621299Y1198563D01*
X1623496D01*
G01X1558501Y1123448D02*
X1565407D01*
X1583448Y1141489D01*
Y1159133D01*
X1610344Y1186029D01*
Y1187819D01*
X1609579Y1188584D01*
Y1189368D01*
X1610133Y1189922D01*
X1610917D01*
X1611682Y1189157D01*
X1613516D01*
X1614819Y1190460D01*
Y1192294D01*
X1614054Y1193059D01*
Y1193843D01*
X1614796Y1194585D01*
X1619064D01*
X1620105Y1193544D01*
G01X1558501Y1127675D02*
X1563645D01*
X1579248Y1143278D01*
Y1164979D01*
X1582821Y1168552D01*
X1584659D01*
X1585260Y1167951D01*
X1586041Y1167952D01*
X1586601Y1168511D01*
X1586600Y1169290D01*
X1585998Y1169893D01*
Y1171729D01*
X1587296Y1173027D01*
X1589134D01*
X1589735Y1172426D01*
X1590516Y1172427D01*
X1591076Y1172986D01*
X1591075Y1173765D01*
X1590473Y1174368D01*
Y1176204D01*
X1591771Y1177502D01*
X1593609D01*
X1594210Y1176901D01*
X1594991Y1176902D01*
X1595551Y1177461D01*
X1595550Y1178240D01*
X1594948Y1178843D01*
Y1180679D01*
X1596246Y1181977D01*
X1598084D01*
X1598685Y1181376D01*
X1599466Y1181377D01*
X1600026Y1181936D01*
X1600025Y1182715D01*
X1599423Y1183318D01*
Y1185154D01*
X1600721Y1186452D01*
X1602559D01*
X1603160Y1185851D01*
X1603941Y1185852D01*
X1604501Y1186411D01*
X1604500Y1187190D01*
X1603898Y1187793D01*
Y1189629D01*
X1615141Y1200872D01*
X1620264D01*
X1621302Y1201910D01*
X1623496D01*
G01X1558013Y1144518D02*
X1559720D01*
X1564887Y1149685D01*
Y1175957D01*
X1611998Y1223068D01*
Y1223847D01*
X1610930Y1224915D01*
Y1226751D01*
X1612229Y1228050D01*
X1614064D01*
X1615132Y1226983D01*
X1615913D01*
X1616473Y1227543D01*
Y1228322D01*
X1615405Y1229390D01*
Y1231226D01*
X1616845Y1232666D01*
X1619070D01*
X1620105Y1233701D01*
G01X1557812Y1146209D02*
X1559057D01*
X1563197Y1150349D01*
Y1176690D01*
X1595772Y1209265D01*
Y1211042D01*
X1594713Y1212101D01*
Y1212883D01*
X1595269Y1213439D01*
X1596051D01*
X1597082Y1212409D01*
X1598916D01*
X1600220Y1213713D01*
X1600219Y1215545D01*
X1599188Y1216576D01*
Y1217358D01*
X1599744Y1217914D01*
X1600526D01*
X1601557Y1216884D01*
X1603391D01*
X1604695Y1218188D01*
X1604694Y1220020D01*
X1603663Y1221051D01*
Y1221833D01*
X1604219Y1222389D01*
X1605001D01*
X1605402Y1221988D01*
X1606032Y1221359D01*
X1607866D01*
X1609170Y1222663D01*
X1609169Y1224495D01*
X1608138Y1225526D01*
Y1226308D01*
X1618243Y1236413D01*
X1620260D01*
X1621299Y1235374D01*
X1623496D01*
G01X1558013Y1143248D02*
X1560247D01*
X1566157Y1149158D01*
Y1175430D01*
X1613268Y1222541D01*
Y1224374D01*
X1612200Y1225442D01*
Y1226224D01*
X1612756Y1226780D01*
X1613538D01*
X1614606Y1225713D01*
X1616440D01*
X1617743Y1227016D01*
Y1228849D01*
X1616675Y1229917D01*
Y1230699D01*
X1617372Y1231396D01*
X1619064D01*
X1620105Y1230355D01*
G01X1557812Y1147479D02*
X1558530D01*
X1561927Y1150876D01*
Y1177217D01*
X1594502Y1209792D01*
Y1210515D01*
X1593443Y1211574D01*
Y1213410D01*
X1594742Y1214709D01*
X1596577D01*
X1597608Y1213679D01*
X1598389D01*
X1598949Y1214239D01*
X1598948Y1215018D01*
X1597918Y1216049D01*
Y1217885D01*
X1599217Y1219184D01*
X1601052D01*
X1602083Y1218154D01*
X1602864D01*
X1603424Y1218714D01*
X1603423Y1219493D01*
X1602393Y1220524D01*
Y1222360D01*
X1603692Y1223659D01*
X1605527D01*
X1606558Y1222629D01*
X1607339D01*
X1607899Y1223189D01*
X1607898Y1223968D01*
X1606868Y1224999D01*
Y1226835D01*
X1617716Y1237683D01*
X1620264D01*
X1621302Y1238721D01*
X1623496D01*
G01X1545398Y1490895D02*
X1544233Y1489730D01*
Y1486960D01*
X1545298Y1485895D01*
G01X1552668Y1513682D02*
X1551603Y1514747D01*
X1548833D01*
X1547668Y1513582D01*
G01X1552668Y1517082D02*
X1551603Y1516017D01*
X1548833D01*
X1547668Y1517182D01*
G01X1552668Y1530482D02*
X1551603Y1529417D01*
X1548833D01*
X1547668Y1530582D01*
G01X1552668Y1527082D02*
X1551603Y1528147D01*
X1548833D01*
X1547668Y1526982D01*
G01X1544533Y1640286D02*
X1545698Y1639121D01*
Y1626445D01*
X1544633Y1625380D01*
G01X1556593Y1640286D02*
X1557758Y1639121D01*
Y1626445D01*
X1556693Y1625380D01*
G01X1548133Y1640286D02*
X1546968Y1639121D01*
Y1626445D01*
X1548033Y1625380D01*
G01X1544533Y1642386D02*
X1545698Y1643551D01*
Y1656227D01*
X1544633Y1657292D01*
G01X1556593Y1642386D02*
X1557758Y1643551D01*
Y1656227D01*
X1556693Y1657292D01*
G01X1548133Y1642386D02*
X1546968Y1643551D01*
Y1656227D01*
X1548033Y1657292D01*
G01X1566326Y32756D02*
Y30351D01*
X1565780Y29805D01*
Y27544D01*
X1566847Y26477D01*
G01X1559779Y19541D02*
X1558693Y20627D01*
Y29805D01*
X1559240Y30352D01*
Y32756D01*
G01X1570552Y19541D02*
X1571597Y20586D01*
Y29805D01*
X1571051Y30351D01*
Y32756D01*
G01X1563964D02*
Y30351D01*
X1564510Y29805D01*
Y27540D01*
X1563447Y26477D01*
G01X1568462Y68337D02*
X1568463D01*
X1569631Y67169D01*
Y65861D01*
X1571597Y55975D01*
Y47322D01*
X1571051Y46776D01*
Y44370D01*
G01X1561062Y62337D02*
Y62330D01*
X1559901Y61169D01*
Y60472D01*
X1560027Y60167D01*
X1563361Y55177D01*
X1564738Y52266D01*
X1565780Y48831D01*
Y47322D01*
X1566326Y46776D01*
Y44370D01*
G01X1572062Y68337D02*
X1570901Y67176D01*
Y65987D01*
X1572867Y56101D01*
Y47322D01*
X1573413Y46776D01*
Y44370D01*
G01X1568462Y70437D02*
X1568469D01*
X1569631Y71599D01*
Y74275D01*
X1568566Y75340D01*
G01X1572062Y70437D02*
X1570901Y71598D01*
Y74275D01*
X1571966Y75340D01*
G01X1561062Y64437D02*
X1559901Y65598D01*
Y68275D01*
X1560966Y69340D01*
G01X1572860Y1495595D02*
X1571795Y1496660D01*
Y1499430D01*
X1572960Y1500595D01*
G01X1569460Y1495595D02*
X1570525Y1496660D01*
Y1499430D01*
X1569360Y1500595D01*
G01X1563222Y1516590D02*
X1564287Y1515525D01*
X1567057D01*
X1568222Y1516690D01*
G01X1563222Y1513190D02*
X1564287Y1514255D01*
X1567057D01*
X1568222Y1513090D01*
G01X1563222Y1534990D02*
X1564287Y1536055D01*
X1567057D01*
X1568222Y1534890D01*
G01X1563222Y1538390D02*
X1564287Y1537325D01*
X1567057D01*
X1568222Y1538490D01*
G01X1568592Y1556431D02*
X1569554Y1557393D01*
X1570580D01*
X1571542Y1556431D01*
G01D02*
X1572459Y1557348D01*
X1574527D01*
X1575744Y1558565D01*
X1578078D01*
G01X1568592Y1559631D02*
X1569560Y1558663D01*
X1570574D01*
X1571542Y1559631D01*
G01D02*
X1572555Y1558618D01*
X1574000D01*
X1575217Y1559835D01*
X1578153D01*
G01X1562640Y1556331D02*
X1563705Y1557396D01*
X1565527D01*
X1566492Y1556431D01*
G01X1562640Y1559731D02*
X1563705Y1558666D01*
X1565527D01*
X1566492Y1559631D01*
G01X1568653Y1640286D02*
X1569818Y1639121D01*
Y1626445D01*
X1568753Y1625380D01*
G01X1560193Y1640286D02*
X1559028Y1639121D01*
Y1626445D01*
X1560093Y1625380D01*
G01X1572253Y1640286D02*
X1571088Y1639121D01*
Y1626445D01*
X1572153Y1625380D01*
G01X1568653Y1642386D02*
X1569818Y1643551D01*
Y1656227D01*
X1568753Y1657292D01*
G01X1560193Y1642386D02*
X1559028Y1643551D01*
Y1656227D01*
X1560093Y1657292D01*
G01X1572253Y1642386D02*
X1571088Y1643551D01*
Y1656227D01*
X1572153Y1657292D01*
G01X1588125Y19541D02*
X1587040Y20626D01*
Y29805D01*
X1587587Y30352D01*
X1587586Y30353D01*
Y32756D01*
G01X1580499D02*
Y30351D01*
X1579953Y29805D01*
Y27544D01*
X1581020Y26477D01*
G01X1573952Y19541D02*
X1572867Y20626D01*
Y29805D01*
X1573414Y30352D01*
X1573413Y30353D01*
Y32756D01*
G01X1584725Y19541D02*
X1585770Y20586D01*
Y29805D01*
X1585224Y30351D01*
Y32756D01*
G01X1578137D02*
Y30351D01*
X1578683Y29805D01*
Y27540D01*
X1577620Y26477D01*
G01X1590462Y68337D02*
X1591627Y67172D01*
Y66240D01*
X1591182Y64138D01*
X1588720Y58578D01*
X1585770Y48820D01*
Y47322D01*
X1585224Y46776D01*
Y44370D01*
G01X1579462Y62337D02*
X1580627Y61172D01*
Y58789D01*
X1578683Y49014D01*
Y47322D01*
X1578137Y46776D01*
Y44370D01*
G01X1583062Y62337D02*
X1581897Y61172D01*
Y58663D01*
X1579953Y48887D01*
Y47322D01*
X1580499Y46776D01*
Y44370D01*
G01X1594062Y68337D02*
X1592897Y67172D01*
Y66107D01*
X1592397Y63745D01*
X1589914Y58135D01*
X1587040Y48632D01*
Y47322D01*
X1587586Y46776D01*
Y44370D01*
G01X1579462Y64437D02*
X1579469D01*
X1580631Y65599D01*
Y68275D01*
X1579566Y69340D01*
G01X1583062Y64437D02*
X1581901Y65598D01*
Y68275D01*
X1582966Y69340D01*
G01X1579560Y1485895D02*
X1578495Y1486960D01*
Y1489730D01*
X1579660Y1490895D01*
G01X1576160Y1485895D02*
X1577225Y1486960D01*
Y1489730D01*
X1576060Y1490895D01*
G01X1580713Y1640286D02*
X1581878Y1639121D01*
Y1626445D01*
X1580813Y1625380D01*
G01X1584313Y1640286D02*
X1583148Y1639121D01*
Y1626445D01*
X1584213Y1625380D01*
G01X1580713Y1642386D02*
X1581878Y1643551D01*
Y1656227D01*
X1580813Y1657292D01*
G01X1584313Y1642386D02*
X1583148Y1643551D01*
Y1656227D01*
X1584213Y1657292D01*
G01X1602299Y19541D02*
X1601217Y20623D01*
Y29809D01*
X1601759Y30351D01*
Y32756D01*
G01X1594673D02*
Y30351D01*
X1594127Y29805D01*
Y27544D01*
X1595194Y26477D01*
G01X1598899Y19541D02*
X1599947Y20589D01*
Y29801D01*
X1599397Y30351D01*
Y32756D01*
G01X1592311D02*
Y30351D01*
X1592857Y29805D01*
Y27540D01*
X1591794Y26477D01*
G01X1612462Y68337D02*
X1613631Y67168D01*
Y66307D01*
X1613459Y65741D01*
X1611069Y62162D01*
X1607276Y57535D01*
X1600991Y51242D01*
X1599943Y48708D01*
Y47322D01*
X1599397Y46776D01*
Y44370D01*
G01X1601462Y62337D02*
X1602627Y61172D01*
Y60617D01*
X1602372Y60003D01*
X1594331Y51964D01*
X1593824Y51204D01*
X1592857Y48870D01*
Y47322D01*
X1592311Y46776D01*
Y44370D01*
G01X1616062Y68337D02*
X1614901Y67176D01*
Y66118D01*
X1614620Y65192D01*
X1612091Y61405D01*
X1608219Y56682D01*
X1602068Y50523D01*
X1601213Y48455D01*
Y47322D01*
X1601759Y46776D01*
Y44370D01*
G01X1605062Y62337D02*
X1603897Y61172D01*
Y60364D01*
X1603449Y59283D01*
X1595318Y51153D01*
X1594950Y50602D01*
X1594127Y48617D01*
Y47322D01*
X1594673Y46776D01*
Y44370D01*
G01X1590462Y70437D02*
X1590469D01*
X1591631Y71599D01*
Y74275D01*
X1590566Y75340D01*
G01X1601462Y64437D02*
X1602627Y65602D01*
Y68278D01*
X1601562Y69343D01*
G01X1594062Y70437D02*
X1592901Y71598D01*
Y74275D01*
X1593966Y75340D01*
G01X1592960Y1505295D02*
X1591895Y1506360D01*
Y1509130D01*
X1593060Y1510295D01*
G01X1599660Y1495595D02*
X1598595Y1496660D01*
Y1499430D01*
X1599760Y1500595D01*
G01X1589560Y1505295D02*
X1590625Y1506360D01*
Y1509130D01*
X1589460Y1510295D01*
G01X1596260Y1495595D02*
X1597325Y1496660D01*
Y1499430D01*
X1596160Y1500595D01*
G01X1592773Y1640286D02*
X1593938Y1639121D01*
Y1626445D01*
X1592873Y1625380D01*
G01X1596373Y1640286D02*
X1595208Y1639121D01*
Y1626445D01*
X1596273Y1625380D01*
G01X1592773Y1642386D02*
X1593938Y1643551D01*
Y1656227D01*
X1592873Y1657292D01*
G01X1596373Y1642386D02*
X1595208Y1643551D01*
Y1656227D01*
X1596273Y1657292D01*
G01X1612462Y70437D02*
X1613631Y71606D01*
Y74275D01*
X1612566Y75340D01*
G01X1616062Y70437D02*
X1614901Y71598D01*
Y74275D01*
X1615966Y75340D01*
G01X1605062Y64437D02*
X1603897Y65602D01*
Y68278D01*
X1604962Y69343D01*
G01X1606360Y1485895D02*
X1605295Y1486960D01*
Y1489730D01*
X1606460Y1490895D01*
G01X1602960Y1485895D02*
X1604025Y1486960D01*
Y1489730D01*
X1602860Y1490895D01*
G01X1616360Y1505295D02*
X1617425Y1506360D01*
Y1509130D01*
X1616260Y1510295D01*
G01X1604833Y1640286D02*
X1605998Y1639121D01*
Y1626445D01*
X1604933Y1625380D01*
G01X1616893Y1640286D02*
X1618058Y1639121D01*
Y1626445D01*
X1616993Y1625380D01*
G01X1608433Y1640286D02*
X1607268Y1639121D01*
Y1626445D01*
X1608333Y1625380D01*
G01X1604833Y1642386D02*
X1605998Y1643551D01*
Y1656227D01*
X1604933Y1657292D01*
G01X1616893Y1642386D02*
X1618058Y1643551D01*
Y1656227D01*
X1616993Y1657292D01*
G01X1608333D02*
X1607268Y1656227D01*
Y1643551D01*
X1608433Y1642386D01*
G01X1630539Y32756D02*
Y30351D01*
X1629993Y29805D01*
Y27544D01*
X1631060Y26477D01*
G01X1628177Y32756D02*
Y30351D01*
X1628723Y29805D01*
Y27540D01*
X1627660Y26477D01*
G01X1623462Y62337D02*
X1623463D01*
X1624631Y61169D01*
Y59313D01*
X1624897Y57973D01*
X1628723Y48738D01*
Y47322D01*
X1628177Y46776D01*
Y44370D01*
G01X1627062Y62337D02*
Y62330D01*
X1625901Y61169D01*
Y59439D01*
X1626119Y58344D01*
X1629993Y48991D01*
Y47322D01*
X1630539Y46776D01*
Y44370D01*
G01X1623462Y64437D02*
X1624631Y65606D01*
Y68274D01*
X1623562Y69343D01*
G01X1627062Y64437D02*
X1625901Y65598D01*
Y68282D01*
X1626962Y69343D01*
G01X1633160Y1485895D02*
X1632095Y1486960D01*
Y1489730D01*
X1633260Y1490895D01*
G01X1629760Y1485895D02*
X1630825Y1486960D01*
Y1489730D01*
X1629660Y1490895D01*
G01X1619760Y1505295D02*
X1618695Y1506360D01*
Y1509130D01*
X1619860Y1510295D01*
G01X1626460Y1495595D02*
X1625395Y1496660D01*
Y1499430D01*
X1626560Y1500595D01*
G01X1623060Y1495595D02*
X1624125Y1496660D01*
Y1499430D01*
X1622960Y1500595D01*
G01X1628953Y1640286D02*
X1630118Y1639121D01*
Y1626445D01*
X1629053Y1625380D01*
G01X1620493Y1640286D02*
X1619328Y1639121D01*
Y1626445D01*
X1620393Y1625380D01*
G01X1632553Y1640286D02*
X1631388Y1639121D01*
Y1626445D01*
X1632453Y1625380D01*
G01X1628953Y1642386D02*
X1630118Y1643551D01*
Y1656227D01*
X1629053Y1657292D01*
G01X1620493Y1642386D02*
X1619328Y1643551D01*
Y1656227D01*
X1620393Y1657292D01*
G01X1632553Y1642386D02*
X1631388Y1643551D01*
Y1656227D01*
X1632453Y1657292D01*
G01X1644712Y32756D02*
Y30351D01*
X1644166Y29805D01*
Y27544D01*
X1645233Y26477D01*
G01X1638165Y19541D02*
X1637079Y20627D01*
Y29805D01*
X1637625Y30351D01*
Y32756D01*
G01X1642350D02*
Y30351D01*
X1642896Y29805D01*
Y27540D01*
X1641833Y26477D01*
G01X1634765Y19541D02*
X1635809Y20585D01*
Y29805D01*
X1635263Y30351D01*
Y32756D01*
G01X1646666Y62337D02*
X1646667D01*
X1647835Y61169D01*
Y60475D01*
X1647329Y58809D01*
X1644533Y53578D01*
X1642896Y49625D01*
Y47322D01*
X1642350Y46776D01*
Y44370D01*
G01X1635666Y68337D02*
X1635667D01*
X1636835Y67169D01*
Y62571D01*
X1635809Y52151D01*
Y47322D01*
X1635263Y46776D01*
Y44370D01*
G01X1650266Y62337D02*
Y62330D01*
X1649105Y61169D01*
Y60286D01*
X1648509Y58320D01*
X1645683Y53034D01*
X1644166Y49372D01*
Y47322D01*
X1644712Y46776D01*
Y44370D01*
G01X1639266Y68337D02*
Y68330D01*
X1638105Y67169D01*
Y62508D01*
X1637079Y52088D01*
Y47322D01*
X1637625Y46776D01*
Y44370D01*
G01X1646666Y64437D02*
X1646673D01*
X1647835Y65599D01*
Y68275D01*
X1646770Y69340D01*
G01X1635666Y70437D02*
X1635673D01*
X1636835Y71599D01*
Y74275D01*
X1635770Y75340D01*
G01X1639266Y70437D02*
X1638105Y71598D01*
Y74275D01*
X1639170Y75340D01*
G01X1646560Y1505295D02*
X1645495Y1506360D01*
Y1509130D01*
X1646660Y1510295D01*
G01X1643160Y1505295D02*
X1644225Y1506360D01*
Y1509130D01*
X1643060Y1510295D01*
G01X1641013Y1640286D02*
X1642178Y1639121D01*
Y1626445D01*
X1641113Y1625380D01*
G01X1644613Y1640286D02*
X1643448Y1639121D01*
Y1626445D01*
X1644513Y1625380D01*
G01X1641013Y1642386D02*
X1642178Y1643551D01*
Y1656227D01*
X1641113Y1657292D01*
G01X1644613Y1642386D02*
X1643448Y1643551D01*
Y1656227D01*
X1644513Y1657292D01*
G01X1652338Y19541D02*
X1651253Y20626D01*
Y29805D01*
X1651800Y30352D01*
X1651799Y30353D01*
Y32756D01*
G01X1648938Y19541D02*
X1649983Y20586D01*
Y29805D01*
X1649437Y30351D01*
Y32756D01*
G01X1657666Y68337D02*
X1657667D01*
X1658835Y67169D01*
Y66078D01*
X1650647Y51627D01*
X1649983Y49106D01*
Y47322D01*
X1649437Y46776D01*
Y44370D01*
G01X1661266Y68337D02*
Y68330D01*
X1660105Y67169D01*
Y65743D01*
X1651834Y51144D01*
X1651253Y48941D01*
Y47322D01*
X1651799Y46776D01*
Y44370D01*
G01X1657666Y70437D02*
X1658831Y71602D01*
Y74278D01*
X1657766Y75343D01*
G01X1661266Y70437D02*
X1661265D01*
X1660101Y71601D01*
Y74278D01*
X1661166Y75343D01*
G01X1650266Y64437D02*
X1649105Y65598D01*
Y68275D01*
X1650170Y69340D01*
G01X1659960Y1485895D02*
X1658895Y1486960D01*
Y1489730D01*
X1660060Y1490895D01*
G01X1656560Y1485895D02*
X1657625Y1486960D01*
Y1489730D01*
X1656460Y1490895D01*
G01X1653260Y1495595D02*
X1652195Y1496660D01*
Y1499430D01*
X1653360Y1500595D01*
G01X1649860Y1495595D02*
X1650925Y1496660D01*
Y1499430D01*
X1649760Y1500595D01*
G01X1674673Y32756D02*
Y30351D01*
X1674127Y29805D01*
Y27544D01*
X1675194Y26477D01*
G01X1672311Y32756D02*
Y30351D01*
X1672857Y29805D01*
Y27540D01*
X1671794Y26477D01*
G01X1668666Y62337D02*
X1669835Y61168D01*
Y58139D01*
X1670022Y57193D01*
X1672252Y51809D01*
X1672857Y48771D01*
Y47322D01*
X1672311Y46776D01*
Y44370D01*
G01X1672266Y62337D02*
X1671105Y61176D01*
Y58264D01*
X1671244Y57564D01*
X1673474Y52180D01*
X1674127Y48897D01*
Y47322D01*
X1674673Y46776D01*
Y44370D01*
G01X1668666Y64437D02*
X1669835Y65606D01*
Y68275D01*
X1668770Y69340D01*
G01X1672266Y64437D02*
X1671105Y65598D01*
Y68275D01*
X1672170Y69340D01*
G01X1673360Y1485895D02*
X1672295Y1486960D01*
Y1489730D01*
X1673460Y1490895D01*
G01X1669960Y1485895D02*
X1671025Y1486960D01*
Y1489730D01*
X1669860Y1490895D01*
G01X1680730Y1517082D02*
X1679665Y1516017D01*
X1676895D01*
X1675730Y1517182D01*
G01X1680730Y1513682D02*
X1679665Y1514747D01*
X1676895D01*
X1675730Y1513582D01*
G01X1680730Y1530482D02*
X1679665Y1529417D01*
X1676895D01*
X1675730Y1530582D01*
G01X1680730Y1527082D02*
X1679665Y1528147D01*
X1676895D01*
X1675730Y1526982D01*
G01X1688846Y32756D02*
Y30351D01*
X1688300Y29805D01*
Y27544D01*
X1689367Y26477D01*
G01X1682299Y19541D02*
X1681213Y20627D01*
Y29805D01*
X1681760Y30352D01*
X1681759Y30353D01*
Y32756D01*
G01X1686484D02*
Y30351D01*
X1687030Y29805D01*
Y27540D01*
X1685967Y26477D01*
G01X1678899Y19541D02*
X1679943Y20585D01*
Y29805D01*
X1679397Y30351D01*
Y32756D01*
G01X1690800Y62337D02*
X1691969Y61168D01*
Y60422D01*
X1687175Y48885D01*
X1687030Y48161D01*
Y47322D01*
X1686484Y46776D01*
Y44370D01*
G01X1679800Y68337D02*
X1680969Y67168D01*
Y64198D01*
X1679943Y53778D01*
Y47322D01*
X1679397Y46776D01*
Y44370D01*
G01X1694400Y62337D02*
X1693239Y61176D01*
Y60168D01*
X1688396Y48513D01*
X1688300Y48035D01*
Y47322D01*
X1688846Y46776D01*
Y44370D01*
G01X1683400Y68337D02*
X1682239Y67176D01*
Y64135D01*
X1681213Y53715D01*
Y47322D01*
X1681759Y46776D01*
Y44370D01*
G01X1690800Y64437D02*
X1691965Y65602D01*
Y68278D01*
X1690900Y69343D01*
G01X1679800Y70437D02*
X1680969Y71606D01*
Y74275D01*
X1679904Y75340D01*
G01X1683400Y70437D02*
X1682239Y71598D01*
Y74275D01*
X1683304Y75340D01*
G01X1696472Y19541D02*
X1695387Y20626D01*
Y29805D01*
X1695934Y30352D01*
X1695933Y30353D01*
Y32756D01*
G01X1693072Y19541D02*
X1694117Y20586D01*
Y29805D01*
X1693570Y30352D01*
Y32756D01*
G01X1703583Y26505D02*
X1702439Y27649D01*
Y30018D01*
X1703019Y30598D01*
Y32756D01*
G01X1700183Y26505D02*
X1701169Y27491D01*
Y30020D01*
X1700657Y30532D01*
Y32756D01*
G01X1701800Y68337D02*
X1702965Y67172D01*
Y66200D01*
X1702721Y65226D01*
X1695682Y52060D01*
X1694116Y48279D01*
Y47322D01*
X1693570Y46776D01*
Y44370D01*
G01X1705400Y68337D02*
X1704235Y67172D01*
Y66043D01*
X1703915Y64765D01*
X1696832Y51516D01*
X1695386Y48026D01*
Y47322D01*
X1695933Y46775D01*
Y44370D01*
G01X1703536Y50649D02*
X1702473Y49586D01*
Y47182D01*
X1703019Y46636D01*
Y44370D01*
G01X1700657D02*
Y46512D01*
X1701203Y47058D01*
Y49582D01*
X1700136Y50649D01*
G01X1701800Y70437D02*
X1702969Y71606D01*
Y74275D01*
X1701904Y75340D01*
G01X1705400Y70437D02*
X1704239Y71598D01*
Y74275D01*
X1705304Y75340D01*
G01X1694400Y64437D02*
X1693235Y65602D01*
Y68278D01*
X1694300Y69343D01*
G01X1732125Y-23228D02*
X1729557Y-22512D01*
G01X1732125Y-25196D02*
X1729557Y-25912D01*
G01X1758118Y32756D02*
Y30338D01*
X1757572Y29792D01*
Y27543D01*
X1758638Y26477D01*
G01X1755755Y32756D02*
Y30343D01*
X1756302Y29796D01*
Y27541D01*
X1755238Y26477D01*
G01X1758635Y50649D02*
X1757572Y49586D01*
Y47187D01*
X1758118Y46641D01*
Y44370D01*
G01X1755755D02*
Y46616D01*
X1756302Y47163D01*
Y49582D01*
X1755235Y50649D01*
G01X2047419Y-29669D02*
X2051284D01*
X2051782Y-29171D01*
Y562033D01*
X2051284Y562531D01*
X2047419D01*
G01X2057419D02*
X2053562D01*
X2053052Y562021D01*
Y-29159D01*
X2053562Y-29669D01*
X2057419D01*
G54D331*
G01X382797Y1580912D02*
Y1577324D01*
X383673Y1576448D01*
G01X393322Y1573347D02*
X392472Y1574197D01*
X388222D01*
X388056Y1574363D01*
X384173D01*
X383673Y1574863D01*
Y1576448D01*
G01X387805Y1604802D02*
X384457Y1601454D01*
Y1593936D01*
G01X381607Y1590393D02*
Y1589938D01*
X382797Y1588748D01*
Y1587526D01*
G01X384457Y1591836D02*
X383692Y1591071D01*
X382285D01*
X381607Y1590393D01*
G01X450749Y1571104D02*
X445118D01*
X444790Y1571432D01*
X443976Y1573396D01*
X440846Y1576526D01*
G01X446653Y1573264D02*
X446713Y1573204D01*
X450749D01*
G01X444128Y1600200D02*
X446218Y1598110D01*
Y1590517D01*
G01X454288Y1583440D02*
Y1585083D01*
X452704Y1586667D01*
X451492D01*
X447642Y1590517D01*
X446218D01*
G54D160*
X366588Y288429D03*
X773766Y275881D03*
G54D22*
X18848Y516951D03*
X33001Y401000D03*
X48678Y1519335D03*
X38149Y1594396D03*
Y1607896D03*
Y1598896D03*
Y1603396D03*
Y1612896D03*
Y1617396D03*
X44443Y1668587D03*
Y1663587D03*
X52143Y1681489D03*
X45143Y1681645D03*
X66741Y268223D03*
X57123Y423746D03*
X67149Y1630396D03*
X59143Y1682016D03*
X74267Y145191D03*
X74270Y149191D03*
Y153191D03*
X81890Y382219D03*
Y391391D03*
Y395865D03*
X73516Y1434000D03*
X79149Y1611896D03*
Y1625396D03*
Y1620896D03*
Y1616396D03*
X70683Y1634905D03*
X89017Y140950D03*
X96574Y1353216D03*
X87016Y1417000D03*
Y1412500D03*
Y1408000D03*
Y1421500D03*
X96016Y1426000D03*
Y1430500D03*
Y1440000D03*
Y1435500D03*
X87016D03*
X84421Y1519335D03*
X85712Y1549369D03*
X83212Y1544869D03*
X92283Y1716241D03*
X85436Y1706511D03*
X85273Y1716331D03*
X104637Y1554069D03*
X104002Y1671361D03*
Y1667361D03*
Y1679564D03*
Y1675564D03*
X107516Y1712450D03*
X123369Y1661087D03*
X141508Y521997D03*
Y530997D03*
Y534997D03*
X129174Y1353216D03*
X141016Y1417500D03*
X136936Y1701011D03*
X136834Y1705166D03*
X132783Y1718241D03*
X139783Y1726241D03*
Y1722241D03*
X151716Y438810D03*
X149763Y668361D03*
X145016Y1421500D03*
Y1425500D03*
X155831Y1726500D03*
X168366Y395040D03*
X166382Y684799D03*
Y680799D03*
X161874Y1353216D03*
X172016Y1711000D03*
Y1725000D03*
X174616Y416600D03*
X178496Y438270D03*
X176516Y672500D03*
Y676500D03*
X192936Y140962D03*
X195652Y165325D03*
X194774Y1353216D03*
X199016Y1707000D03*
X197795Y1723000D03*
X222368Y144710D03*
X230536Y159071D03*
X227574Y1353216D03*
X242236Y75862D03*
X234216Y142062D03*
X232759Y715823D03*
X255916Y58400D03*
Y54400D03*
X254816Y73400D03*
X255916Y62400D03*
X257813Y87543D03*
X247313Y115743D03*
X260859Y583999D03*
X261174Y1307070D03*
X275472Y78461D03*
X267069Y151203D03*
Y147203D03*
X267119Y137302D03*
X270016Y211000D03*
X262016Y217500D03*
X278972Y74536D03*
X283816Y136962D03*
X277016Y215000D03*
X283807Y577698D03*
X280657Y574022D03*
X276942Y570398D03*
X283807Y581298D03*
X284483Y1342705D03*
X298182Y67128D03*
X302173Y91767D03*
X295943Y85983D03*
Y82483D03*
X294070Y1307042D03*
X317115Y95852D03*
X317119Y99837D03*
X314355Y227851D03*
Y231851D03*
X310516Y241000D03*
X309016Y263000D03*
X326162Y147120D03*
Y152120D03*
Y156120D03*
Y160120D03*
X326974Y1306985D03*
X343186Y229180D03*
X345673Y586415D03*
X338755Y702203D03*
X352449Y219343D03*
X362924Y294030D03*
X353673Y582415D03*
Y578415D03*
X356073Y590415D03*
Y586415D03*
X359774Y1307185D03*
X376011Y149077D03*
X370979Y163173D03*
X374041Y235455D03*
X374071Y239615D03*
X371815Y701935D03*
X381104Y287370D03*
X387673Y565915D03*
X387473Y571115D03*
X392356Y1326516D03*
X394121Y1611022D03*
Y1607022D03*
Y1603022D03*
Y1599022D03*
X405657Y144300D03*
X402309Y157034D03*
Y152278D03*
X401516Y304000D03*
X399887Y555915D03*
Y561415D03*
X409016Y1641000D03*
X406016Y1649500D03*
X419516Y54762D03*
X413217Y99148D03*
X414456Y226323D03*
Y230323D03*
Y240501D03*
X415231Y254165D03*
Y270165D03*
Y262165D03*
X415682Y1032304D03*
X419516Y1639000D03*
Y1634000D03*
X414016Y1649500D03*
Y1653500D03*
X431267Y1285694D03*
Y1289694D03*
X451315Y206620D03*
Y210620D03*
X451368Y283318D03*
X465515Y210620D03*
Y206620D03*
X465912Y222764D03*
Y235764D03*
Y243764D03*
X462672Y1013604D03*
Y1009864D03*
Y1006123D03*
Y1017344D03*
Y1024824D03*
Y1028564D03*
Y1021084D03*
Y1032304D03*
X465016Y1655500D03*
Y1672000D03*
X465516Y1701000D03*
Y1733500D03*
X480316Y288469D03*
X476321Y309809D03*
X472516Y1668000D03*
Y1659500D03*
Y1676000D03*
Y1697000D03*
Y1710500D03*
Y1733500D03*
X485899Y60105D03*
X486059Y55095D03*
X485789Y64965D03*
X490013Y167625D03*
X489198Y201516D03*
Y197516D03*
X497748D03*
X494550Y233000D03*
Y243178D03*
X501292Y209285D03*
Y213285D03*
Y220166D03*
X511239Y280721D03*
X541712Y190256D03*
Y199256D03*
X543504Y222441D03*
Y235560D03*
Y226441D03*
X538658Y292268D03*
X544253Y659489D03*
X551352Y156667D03*
X551454Y239566D03*
X553189Y403586D03*
X546016Y459000D03*
X559016Y473500D03*
X574519Y164356D03*
Y169415D03*
X567316Y297469D03*
X563321Y318809D03*
X572016Y454500D03*
X578040Y257171D03*
X579976Y366827D03*
X583139Y415846D03*
Y427949D03*
X583158Y431976D03*
X587687Y1266668D03*
Y1262668D03*
X600285Y145640D03*
Y149640D03*
X602794Y157640D03*
X600285Y153640D03*
X591045Y213277D03*
X598239Y289721D03*
X593516Y445500D03*
Y449500D03*
X597014Y464349D03*
X590519Y474353D03*
X600287Y1270598D03*
Y1278598D03*
Y1274598D03*
X613298Y179720D03*
X605909Y260010D03*
X615976Y366827D03*
X615516Y418000D03*
X615407Y426901D03*
X628016Y427000D03*
X629519Y437881D03*
X630175Y461441D03*
X629925Y468856D03*
X619329Y1371182D03*
X619354Y1382864D03*
Y1378964D03*
X619329Y1375082D03*
X619293Y1390732D03*
X646237Y184862D03*
X634625Y230975D03*
Y226975D03*
X648676Y307089D03*
X642596Y401580D03*
X642540Y405449D03*
X647016Y418500D03*
X643016Y433862D03*
X647016Y422500D03*
X643016Y437862D03*
Y442362D03*
Y453862D03*
Y449862D03*
X643140Y461853D03*
X643027Y457746D03*
X643157Y469863D03*
X643016Y488000D03*
X647016Y519500D03*
X659516Y390000D03*
X656516Y429862D03*
Y425862D03*
Y433862D03*
Y453862D03*
Y469862D03*
Y473862D03*
X655738Y1363394D03*
X655770Y1367283D03*
X652716Y1687400D03*
X653316Y1708184D03*
X662516Y1712084D03*
X653316Y1702400D03*
X664739Y363261D03*
X672516Y417862D03*
Y413362D03*
Y433862D03*
Y429862D03*
Y425862D03*
Y421862D03*
Y442362D03*
Y449862D03*
X672548Y486942D03*
X672805Y495084D03*
X665516Y533500D03*
X671116Y1312502D03*
X677821Y1635842D03*
Y1647842D03*
X690736Y76962D03*
X690969Y91668D03*
X680469Y119868D03*
X704130Y1371225D03*
X702126Y1564523D03*
X702016Y1556500D03*
X702126Y1576523D03*
Y1572523D03*
Y1568523D03*
Y1584523D03*
X702016Y1596500D03*
X702126Y1588523D03*
Y1592523D03*
X702016Y1604500D03*
X699244Y1623062D03*
X696855Y1681996D03*
X710237Y221862D03*
X713537Y1403571D03*
X717266Y1566333D03*
X730009Y86998D03*
X730519Y105468D03*
Y101968D03*
X738249Y111252D03*
X736912Y1371325D03*
X724266Y1566333D03*
X725377Y1610743D03*
X725266Y1606733D03*
X751649Y115288D03*
X751651Y119172D03*
X745761Y137864D03*
X748251Y161463D03*
X748516Y175500D03*
X746319Y1403671D03*
X752126Y1580023D03*
X754570Y228201D03*
X756782Y269322D03*
Y265322D03*
X763153Y1570633D03*
X763166Y1574733D03*
Y1578733D03*
Y1587733D03*
X774936Y163254D03*
X773043Y303410D03*
X772958Y308755D03*
X779016Y367500D03*
X776168Y415344D03*
X775168Y431344D03*
Y427344D03*
Y423344D03*
Y447344D03*
Y443344D03*
Y439344D03*
Y435344D03*
Y451344D03*
X788282Y274822D03*
X786143Y303410D03*
X786058Y308755D03*
X789516Y403000D03*
Y399000D03*
X789618Y419344D03*
X789516Y411500D03*
X789618Y431344D03*
Y427344D03*
Y423344D03*
X789668Y435344D03*
X789618Y443344D03*
X789668Y447344D03*
X805516Y392500D03*
X812516D03*
X806551Y427344D03*
X806525Y435628D03*
X805425Y439628D03*
X806449Y459344D03*
Y455344D03*
X806516Y508000D03*
X804666Y1570633D03*
Y1578633D03*
Y1594633D03*
Y1582633D03*
Y1602633D03*
X820016Y409500D03*
X827016D03*
X820935Y427344D03*
Y431344D03*
Y443552D03*
X821062Y439279D03*
X820935Y435628D03*
Y449802D03*
Y459344D03*
X837342Y90451D03*
X839236Y129362D03*
Y135862D03*
X837074Y435552D03*
Y439552D03*
Y443552D03*
Y459578D03*
Y455578D03*
Y463578D03*
X835516Y475000D03*
X848737Y135862D03*
Y129362D03*
X856319Y265057D03*
X856829Y283527D03*
Y280027D03*
X848516Y381000D03*
Y385000D03*
X852716Y401280D03*
X852778Y524413D03*
X846666Y1570633D03*
Y1578633D03*
Y1594633D03*
Y1582633D03*
Y1602633D03*
X871236Y171362D03*
Y176862D03*
X865409Y223763D03*
X858108Y240441D03*
X865409Y227763D03*
X864559Y289311D03*
X859016Y391500D03*
X881241Y192055D03*
X877959Y293347D03*
X877982Y297365D03*
X878016Y301500D03*
X877516Y326000D03*
X902467Y597449D03*
X902316Y602182D03*
X894139Y1137843D03*
X894546Y1149069D03*
Y1153497D03*
X899410Y1159831D03*
X888666Y1570633D03*
Y1578633D03*
Y1594633D03*
Y1582633D03*
Y1602633D03*
X906688Y582412D03*
X903647Y611358D03*
X906688Y625912D03*
X906564Y1161169D03*
X926540Y570703D03*
X930666Y1590233D03*
X941461Y185052D03*
Y189052D03*
X945097Y590417D03*
X941164Y1137843D03*
X941571Y1149069D03*
Y1153497D03*
X946435Y1159831D03*
X961641Y202096D03*
X953589Y1161169D03*
X965141Y198171D03*
X991516Y152299D03*
X982440Y175483D03*
X984971Y264781D03*
Y275443D03*
X977241Y1055484D03*
X998516Y152299D03*
X994428Y217233D03*
X992900Y473675D03*
Y479175D03*
X996572Y521014D03*
Y516014D03*
Y526074D03*
Y531074D03*
X1009892Y175278D03*
Y171278D03*
X1013836Y194499D03*
X1021485Y378764D03*
Y383764D03*
Y388764D03*
X1021516Y402000D03*
X1021485Y393764D03*
X1014073Y425902D03*
X1011280Y460155D03*
Y456155D03*
Y452155D03*
Y464155D03*
Y468155D03*
Y476155D03*
Y472155D03*
Y493655D03*
Y488642D03*
Y480155D03*
X1012302Y550074D03*
Y545074D03*
X1027920Y287311D03*
Y298311D03*
X1028516Y566000D03*
X1043761Y406586D03*
X1039770Y516014D03*
Y521074D03*
Y526074D03*
Y534074D03*
X1042516Y538000D03*
X1041770Y544574D03*
Y549574D03*
X1041847Y553641D03*
X1065810Y475525D03*
X1065780Y483655D03*
Y487655D03*
X1068597Y369792D03*
X1074810Y471500D03*
Y467000D03*
X1074726Y483782D03*
Y487782D03*
X1068312Y1353197D03*
X1087027Y373187D03*
X1081751Y387226D03*
Y379226D03*
Y383226D03*
Y391226D03*
X1090454Y472105D03*
X1091630Y1687229D03*
Y1691229D03*
X1098964Y447355D03*
Y463355D03*
Y459355D03*
Y455355D03*
Y451355D03*
Y467355D03*
Y475355D03*
Y484391D03*
Y489391D03*
X1100912Y1353197D03*
X1099016Y1642500D03*
X1099580Y1696029D03*
X1108380Y1711244D03*
X1133612Y1353197D03*
X1159027Y73939D03*
X1169722Y442341D03*
Y447841D03*
Y464341D03*
Y453341D03*
Y458841D03*
Y469841D03*
Y481691D03*
X1166512Y1353197D03*
X1160291Y1454234D03*
X1178703Y61515D03*
Y57015D03*
X1178723Y52815D03*
X1185103Y99694D03*
X1185208Y574322D03*
X1192218Y177187D03*
Y173187D03*
X1188443Y432202D03*
Y448202D03*
Y440202D03*
Y460202D03*
X1188563Y470392D03*
X1188503Y465272D03*
X1199628Y582443D03*
Y587443D03*
X1199312Y1353197D03*
X1188016Y1401000D03*
Y1396500D03*
Y1405500D03*
Y1410000D03*
X1197016Y1414500D03*
Y1419000D03*
Y1428500D03*
Y1433000D03*
X1188016Y1437500D03*
X1189553Y1693850D03*
X1196553D03*
X1192703Y1689850D03*
X1199993Y1731803D03*
X1202528Y164987D03*
Y160987D03*
Y185187D03*
X1204895Y1693859D03*
X1211895D03*
X1208045Y1689859D03*
X1241709Y128239D03*
Y132739D03*
Y123739D03*
Y137239D03*
X1231209Y145239D03*
X1236970Y427255D03*
Y431255D03*
Y439255D03*
Y435255D03*
X1237303Y1307051D03*
X1240016Y1406500D03*
X1258963Y459182D03*
X1259033Y454372D03*
X1250078Y453182D03*
Y458182D03*
X1245516Y1410500D03*
Y1414500D03*
X1272627Y154030D03*
X1262715Y395125D03*
X1262718Y399125D03*
X1263016Y765000D03*
X1270199Y1307023D03*
X1260612Y1342686D03*
X1277465Y390884D03*
X1295209Y141739D03*
Y137739D03*
X1296123Y162051D03*
Y166051D03*
Y171551D03*
Y184051D03*
X1299167Y527418D03*
X1297248Y541634D03*
X1300782Y552813D03*
X1304239Y560209D03*
X1291850Y592871D03*
X1303103Y1306966D03*
X1316357Y567148D03*
X1309203Y565771D03*
X1318454Y1408282D03*
X1343312Y678393D03*
X1335903Y1307166D03*
X1378231Y236594D03*
Y241594D03*
Y246594D03*
Y251594D03*
X1368485Y1326497D03*
X1391824Y1032303D03*
X1382009Y1670391D03*
X1389009Y1674391D03*
X1384561Y1700038D03*
X1388691Y1695238D03*
X1384561Y1712038D03*
Y1708038D03*
X1387120Y1728318D03*
X1407706Y1285765D03*
Y1289765D03*
X1398149Y1622167D03*
X1405149Y1626167D03*
X1404831Y1646967D03*
X1423813Y1609904D03*
Y1623366D03*
X1418831Y1646967D03*
X1432198Y117664D03*
X1438814Y1013603D03*
Y1009863D03*
Y1006122D03*
Y1017343D03*
Y1028563D03*
Y1021083D03*
Y1024823D03*
Y1032303D03*
X1432825Y1613904D03*
X1433013Y1623504D03*
X1428902Y1647087D03*
X1462773Y537827D03*
X1466773Y580977D03*
Y572977D03*
Y568977D03*
Y576977D03*
X1458773D03*
X1482025Y702203D03*
X1510773Y547977D03*
Y551977D03*
X1500773Y556477D03*
X1500873Y561677D03*
X1510773Y563977D03*
X1514458Y130813D03*
X1519035Y209250D03*
Y213250D03*
Y221250D03*
Y225250D03*
Y231250D03*
Y238017D03*
Y249250D03*
Y244250D03*
Y253250D03*
X1515107Y702203D03*
X1539030Y288816D03*
X1539033Y292816D03*
Y296816D03*
X1553780Y284575D03*
X1547153Y1262314D03*
X1547193Y1270188D03*
Y1274188D03*
X1558064Y1302609D03*
X1570808Y1271378D03*
X1587819Y225250D03*
Y214250D03*
Y229250D03*
Y234250D03*
Y239250D03*
Y244250D03*
X1582193Y1278988D03*
X1575221Y1275454D03*
X1582193Y1292988D03*
X1581788Y1298278D03*
X1574923Y1288958D03*
X1598815Y536344D03*
Y531226D03*
X1588693Y1278988D03*
X1610581Y538723D03*
X1610464Y554664D03*
X1610527Y559092D03*
X1622425Y290742D03*
Y294742D03*
Y298742D03*
Y302742D03*
X1622482Y566803D03*
X1629744Y1432248D03*
X1629719Y1424466D03*
Y1428366D03*
X1629744Y1436148D03*
X1629683Y1448016D03*
X1635516Y381500D03*
X1644626Y414202D03*
X1634849Y1311874D03*
X1646693Y1440488D03*
X1656664Y692328D03*
X1651863Y1370514D03*
X1661270Y1402860D03*
X1666326Y1416678D03*
X1692520Y401485D03*
X1687149Y424694D03*
X1684645Y1370614D03*
X1684824Y1696427D03*
X1694052Y1402960D03*
X1722434Y116867D03*
X1715043Y424340D03*
Y420340D03*
X1732381Y53651D03*
Y57651D03*
X1733134Y89827D03*
X1723350Y656238D03*
X1735961Y1552371D03*
X1726979Y1681465D03*
Y1676965D03*
X1740325Y89264D03*
X1743825Y85339D03*
X1751103Y364048D03*
Y368048D03*
X1751236Y377452D03*
Y382952D03*
X1739593Y668216D03*
Y664216D03*
X1760554Y68637D03*
X1761064Y87107D03*
Y83607D03*
X1764943Y368148D03*
X1764736Y372452D03*
X1764943Y364148D03*
X1764939Y1635686D03*
X1768794Y92891D03*
X1778591Y186911D03*
Y194399D03*
X1781020Y182463D03*
X1778647Y197899D03*
X1771704Y1552371D03*
X1772995Y1582405D03*
X1770495Y1577905D03*
X1767979Y1661465D03*
Y1657465D03*
X1782194Y96927D03*
X1782152Y100939D03*
X1789906Y156834D03*
Y161834D03*
X1791920Y1587105D03*
X1822096Y151834D03*
X1823172Y388051D03*
X1822815Y427432D03*
X1822808Y431678D03*
X1844807Y165834D03*
X1844777Y170287D03*
G54D13*
X27559Y87795D03*
X40708Y631889D03*
Y1368908D03*
X51180Y1714961D03*
X117933Y605376D03*
X373622Y87795D03*
X395671Y1714960D03*
X661024Y631890D03*
X707677Y1714960D03*
X763602Y605413D03*
X800787Y87795D03*
X931693Y757874D03*
X931692Y1072835D03*
X931693Y1387795D03*
X1045866Y87795D03*
X1094076Y605378D03*
X1155709Y1714961D03*
X1271260Y631890D03*
X1461806Y1714961D03*
X1499606Y87795D03*
X1739745Y605411D03*
X1806298Y1714961D03*
X1829921Y87795D03*
X1816772Y631889D03*
Y1368897D03*
G36*
G01X253476Y197836D02*
G02Y172636I0J-12600D01*
G01X250331D01*
Y176926D01*
X253476D01*
G03Y193546I0J8310D01*
G01X247176D01*
G03Y176926I0J-8310D01*
G01X250321D01*
Y172636D01*
X247176D01*
G02Y197836I0J12600D01*
G01X253476D01*
G37*
G36*
G01X371587D02*
G02Y172636I0J-12600D01*
G01X368442D01*
Y176926D01*
X371587D01*
G03Y193546I0J8310D01*
G01X365287D01*
G03Y176926I0J-8310D01*
G01X368432D01*
Y172636D01*
X365287D01*
G02Y197836I0J12600D01*
G01X371587D01*
G37*
G54D304*
X1418249Y244450D03*
X1421989D03*
G54D31*
X47300Y277798D03*
Y280357D03*
Y282916D03*
X47260Y308541D03*
Y311100D03*
Y313659D03*
X54780Y282916D03*
Y280357D03*
Y277798D03*
X54740Y313659D03*
Y311100D03*
Y308541D03*
X384155Y152818D03*
Y157936D03*
X391635D03*
Y155377D03*
Y152818D03*
X603245Y401728D03*
Y404287D03*
Y406846D03*
X610725Y401728D03*
Y406846D03*
X1005169Y295634D03*
Y293075D03*
Y290516D03*
X997689D03*
Y293075D03*
Y295634D03*
X1810280Y146716D03*
X1802800D03*
Y149275D03*
X1810280Y151834D03*
X1802800D03*
X1805069Y366053D03*
Y368612D03*
Y371171D03*
X1805629Y385293D03*
Y387852D03*
Y390411D03*
X1805648Y418775D03*
X1798168D03*
X1805659Y410615D03*
Y408056D03*
Y405497D03*
X1798179D03*
Y408056D03*
Y410615D03*
X1805648Y423893D03*
Y421334D03*
X1798168D03*
Y423893D03*
X1812549Y371171D03*
Y366053D03*
X1813109Y385293D03*
Y390411D03*
G54D151*
X329219Y220874D03*
Y239378D03*
X649319Y219363D03*
Y237867D03*
X791526Y128244D03*
Y146748D03*
X882183Y216681D03*
Y235185D03*
G54D40*
X50773Y753020D03*
G54D214*
X600647Y772929D03*
G54D223*
X667552Y149803D03*
Y151771D03*
Y153740D03*
Y155708D03*
Y165551D03*
Y167519D03*
Y169488D03*
Y171456D03*
Y173425D03*
Y175393D03*
Y177362D03*
Y179330D03*
Y181299D03*
Y183268D03*
Y185236D03*
Y187204D03*
Y189173D03*
Y191142D03*
Y193110D03*
Y195079D03*
Y197047D03*
Y199016D03*
Y200984D03*
Y202953D03*
Y204921D03*
Y206890D03*
Y208858D03*
Y210827D03*
Y212795D03*
Y214764D03*
Y216732D03*
Y218701D03*
Y220669D03*
X697277Y148819D03*
Y150787D03*
Y152756D03*
Y154724D03*
Y156693D03*
Y166535D03*
Y168504D03*
Y170472D03*
Y172441D03*
Y174409D03*
Y176378D03*
Y178346D03*
Y180315D03*
Y182283D03*
Y184252D03*
Y186220D03*
Y188189D03*
Y190157D03*
Y192126D03*
Y194094D03*
Y196063D03*
Y198031D03*
Y200000D03*
Y201968D03*
Y203937D03*
Y205905D03*
Y207874D03*
Y209842D03*
Y211811D03*
Y213779D03*
Y215748D03*
Y217716D03*
Y219685D03*
Y221653D03*
G54D313*
X1669100Y121762D03*
Y126762D03*
Y131762D03*
Y136762D03*
Y141762D03*
Y146762D03*
Y151762D03*
Y156762D03*
Y161762D03*
Y166762D03*
X1699100Y121762D03*
Y126762D03*
Y131762D03*
Y136762D03*
Y141762D03*
Y146762D03*
Y151762D03*
Y156762D03*
Y161762D03*
Y166762D03*
G54D322*
X1790355Y189682D03*
X1804135D03*
G54D205*
X514635Y212498D03*
G54D241*
X771220Y1482049D03*
G54D250*
X791280Y1297982D03*
Y1321012D03*
G54D106*
X168071Y1411468D03*
Y1432728D03*
X300044Y1387041D03*
Y1408301D03*
X328994Y1376650D03*
Y1397910D03*
G54D232*
X722356Y1573552D03*
X718813D03*
X720585D03*
Y1591170D03*
X722356D03*
X718813D03*
X736530Y1573552D03*
X734758D03*
X732986D03*
X731215D03*
X729443D03*
X727671D03*
X724128D03*
X725900D03*
Y1591170D03*
X727671D03*
X729443D03*
X731215D03*
X732986D03*
X734758D03*
X736530D03*
X724128D03*
X740073Y1573552D03*
X738301D03*
Y1591170D03*
X740073D03*
G54D115*
X195345Y1407483D03*
Y1427365D03*
X347380Y616161D03*
Y636043D03*
X356251Y1369970D03*
Y1389852D03*
X466581Y573882D03*
Y593764D03*
X1133565Y1409036D03*
Y1428918D03*
X1345073Y1391844D03*
Y1411726D03*
X1454057Y619617D03*
Y639499D03*
G54D142*
X283817Y585179D03*
G54D133*
X270291Y589457D03*
G54D341*
G01X11782Y171901D02*
Y167036D01*
G01X18691Y172073D02*
Y167208D01*
G01X8879Y180928D02*
X11782Y178025D01*
Y175051D01*
G01X23031Y197224D02*
Y184661D01*
X18691Y180321D01*
G01D02*
Y175223D01*
G01X23031Y202224D02*
X17164D01*
X16338Y201398D01*
Y188387D01*
X8879Y180928D01*
G01X23031Y207224D02*
X20011D01*
X8013Y219222D01*
G01X14517Y223688D02*
Y227410D01*
X17280Y230173D01*
X17363D01*
G01X23031Y212224D02*
X18175D01*
X14517Y215882D01*
Y223688D01*
G01X8013Y219222D02*
X8576Y219785D01*
Y228250D01*
X10543Y230217D01*
G01X17363Y233323D02*
X19107D01*
X22409Y230021D01*
G01X10543Y233367D02*
X14330Y237154D01*
X19684D01*
G01X14092Y298207D02*
X16264D01*
X28496Y310439D01*
X37463D01*
X39940Y312916D01*
G01X14092Y295452D02*
X16009D01*
X25910Y305353D01*
X37495D01*
X39940Y307798D01*
G01X38944Y303000D02*
X37673Y304271D01*
X28575D01*
X17196Y292892D01*
X14092D01*
G01X34387Y517025D02*
X31807Y519605D01*
X24561D01*
X21907Y516951D01*
G01X20587Y537355D02*
Y536840D01*
X23977Y533450D01*
X30167D01*
X30562Y533055D01*
G01X150318Y210383D02*
X148364D01*
X133804Y224943D01*
Y342843D01*
X140315Y349354D01*
X194623D01*
X201079Y355810D01*
Y487186D01*
X231601Y517708D01*
Y524026D01*
X222322Y533305D01*
X170563D01*
X137955Y565913D01*
X96738D01*
X63222Y599429D01*
Y680997D01*
X23939Y720280D01*
Y1318073D01*
X14534Y1327478D01*
Y1447963D01*
X17479Y1450908D01*
X103433D01*
X109041Y1456516D01*
Y1467644D01*
X111631Y1470234D01*
X121812D01*
X125796Y1468584D01*
X132356Y1464201D01*
X152845D01*
X163148Y1474504D01*
G01X28068Y292892D02*
X26013D01*
X24765Y291644D01*
Y288304D01*
X32776Y280293D01*
X37445D01*
X39940Y277798D01*
G01X34180Y293407D02*
X32135Y295452D01*
X28068D01*
G01X34925Y288500D02*
Y292662D01*
X34180Y293407D01*
G01X28068Y290137D02*
X32705Y285500D01*
X39440D01*
X39940Y285000D01*
Y282916D01*
G01X39008Y363337D02*
X35740D01*
G01X31099Y387783D02*
X32490Y386392D01*
X34860D01*
X36595Y388127D01*
G01D02*
X38405D01*
X39230Y387302D01*
X40940D01*
G01X40800Y400962D02*
X36098D01*
X36060Y401000D01*
G01X39320Y392269D02*
X36597D01*
X36524Y392196D01*
G01X24997Y395067D02*
X28482Y391582D01*
X33460D01*
X34074Y392196D01*
X36524D01*
G01X34387Y517025D02*
X37276Y519914D01*
X39163D01*
G01X41010Y534105D02*
X36637D01*
X36372Y534370D01*
G01Y531220D02*
X36092D01*
X32847Y534465D01*
G01D02*
X31972D01*
X30562Y533055D01*
G01X32774Y528945D02*
X34962Y526757D01*
G01D02*
Y525621D01*
X35566Y525017D01*
X36581D01*
G01D02*
X38275D01*
X39967Y526709D01*
G01X26887Y528693D02*
X27045Y528851D01*
X32680D01*
X32774Y528945D01*
G01X611896Y535178D02*
X562517D01*
X529065Y501726D01*
X518588D01*
X463550Y446688D01*
X390593D01*
X349148Y488133D01*
Y498570D01*
X307414Y540304D01*
X175361D01*
X141915Y573750D01*
X99464D01*
X70847Y602367D01*
Y682695D01*
X30689Y722853D01*
Y794571D01*
X53099Y816981D01*
Y1252743D01*
X62679Y1262323D01*
X245158D01*
X285866Y1221615D01*
X293463D01*
X304238Y1210840D01*
Y1199261D01*
X308194Y1189710D01*
X314519Y1183385D01*
X335344D01*
X341954Y1189995D01*
Y1218017D01*
X358045Y1234108D01*
X396227D01*
X424954Y1262835D01*
Y1266214D01*
X424024Y1267144D01*
G01X642310Y535773D02*
X619258D01*
X615863Y532378D01*
X562967D01*
X530527Y499938D01*
X518590D01*
X462975Y444323D01*
X390364D01*
X347768Y486919D01*
Y497590D01*
X306444Y538914D01*
X173809D01*
X140481Y572242D01*
X99304D01*
X69497Y602049D01*
Y682219D01*
X29498Y722218D01*
Y795524D01*
X51459Y817485D01*
Y1287792D01*
X53343Y1289676D01*
X55099D01*
G01X278547Y523041D02*
X266962Y534626D01*
X171111D01*
X138395Y567342D01*
X97454D01*
X64812Y599984D01*
Y680992D01*
X25090Y720714D01*
Y1270322D01*
X53444Y1298676D01*
X55099D01*
G01X639757Y533440D02*
X619537D01*
X616530Y530433D01*
X565554D01*
X533278Y498157D01*
X519019D01*
X463961Y443099D01*
X389322D01*
X345969Y486452D01*
Y497255D01*
X305620Y537604D01*
X172737D01*
X139581Y570760D01*
X98960D01*
X67739Y601981D01*
Y682083D01*
X28148Y721674D01*
Y796158D01*
X50306Y818316D01*
Y1290074D01*
X52908Y1292676D01*
X55099D01*
G01X646151Y535227D02*
X644355D01*
X640086Y530958D01*
X620000D01*
X613970Y524928D01*
X564568D01*
X535907Y496267D01*
X519200D01*
X463856Y440923D01*
X388999D01*
X344238Y485684D01*
Y496099D01*
X304282Y536055D01*
X171985D01*
X138755Y569285D01*
X98212D01*
X66297Y601200D01*
Y681516D01*
X26639Y721174D01*
Y796874D01*
X48281Y818516D01*
Y1290656D01*
X53301Y1295676D01*
X55043D01*
G01X424024Y1272144D02*
X424087D01*
X427931Y1268300D01*
Y1262018D01*
X397781Y1231868D01*
X359175D01*
X344394Y1217087D01*
Y1206577D01*
X344414Y1206557D01*
Y1188699D01*
X336640Y1180925D01*
X313499D01*
X305624Y1188800D01*
X301778Y1198086D01*
Y1209820D01*
X292443Y1219155D01*
X284846D01*
X244138Y1259863D01*
X63699D01*
X55509Y1251673D01*
Y815419D01*
X33568Y793478D01*
Y723308D01*
X73706Y683170D01*
Y603424D01*
X100428Y576702D01*
X142969D01*
X176746Y542925D01*
X308487D01*
X351742Y499670D01*
Y489387D01*
X391259Y449870D01*
X463110D01*
X517545Y504305D01*
X526612D01*
X562385Y540078D01*
X649592D01*
G01X57752Y808020D02*
X52676D01*
X36711Y792055D01*
Y724184D01*
X74610Y686285D01*
X113042D01*
G01X424024Y1274644D02*
X424087D01*
X429979Y1268752D01*
Y1261743D01*
X398684Y1230448D01*
X359764D01*
X345834Y1216518D01*
Y1187668D01*
X337671Y1179505D01*
X312910D01*
X303454Y1188961D01*
X298908Y1199937D01*
Y1210681D01*
X291854Y1217735D01*
X284257D01*
X243549Y1258443D01*
X64288D01*
X57018Y1251173D01*
Y814705D01*
X34988Y792675D01*
Y723897D01*
X75135Y683750D01*
Y604004D01*
X101017Y578122D01*
X143694D01*
X177422Y544394D01*
X309027D01*
X353248Y500173D01*
Y490204D01*
X392162Y451290D01*
X462521D01*
X516956Y505725D01*
X526023D01*
X562876Y542578D01*
X654170D01*
X655967Y544375D01*
G01X611896Y538178D02*
X563142D01*
X527961Y502997D01*
X518070D01*
X463394Y448321D01*
X390677D01*
X350319Y488679D01*
Y499220D01*
X307885Y541654D01*
X176192D01*
X142739Y575107D01*
X100170D01*
X72356Y602921D01*
Y682855D01*
X32119Y723092D01*
Y794132D01*
X54318Y816331D01*
Y1252181D01*
X63201Y1261064D01*
X244636D01*
X285344Y1220356D01*
X292941D01*
X302979Y1210318D01*
Y1198861D01*
X307021Y1189102D01*
X313997Y1182126D01*
X335808D01*
X343213Y1189531D01*
Y1217563D01*
X358638Y1232988D01*
X396994D01*
X426696Y1262690D01*
Y1267035D01*
X424087Y1269644D01*
X424024D01*
G01X47300Y282916D02*
X42449D01*
G01D02*
X39940D01*
G01X47300Y277798D02*
X42449D01*
G01D02*
X39940D01*
G01X44692Y292892D02*
X41492D01*
G01X44692Y298207D02*
X41492D01*
G01X44692Y295452D02*
X47892D01*
G01X38075Y288500D02*
X40500D01*
G01D02*
X42500Y286500D01*
X63500D01*
X64425Y287425D01*
Y290000D01*
G01X50925Y303500D02*
Y296075D01*
X54108Y292892D01*
X55254D01*
G01X42449Y312916D02*
X39940D01*
G01X47260Y313659D02*
X43192D01*
X42449Y312916D01*
G01X39940Y307798D02*
X42449D01*
G01D02*
X44797D01*
X45540Y308541D01*
X47260D01*
G01X43925Y303500D02*
X39444D01*
X38944Y303000D01*
G01X47075Y303500D02*
X50925D01*
G01X192592Y353072D02*
X43131D01*
X39021Y357182D01*
Y363324D01*
X39008Y363337D01*
G01X50200Y375262D02*
X51114Y374348D01*
Y366487D01*
G01X46834D02*
X42809D01*
G01X39008D02*
X42809D01*
G01X51114D02*
X46834D01*
G01X39600Y378562D02*
X40400Y379362D01*
X48999D01*
X49468Y379831D01*
Y380803D01*
G01X44700Y375262D02*
X47300Y377862D01*
X49800D01*
X51437Y379499D01*
Y380803D01*
G01X53406D02*
Y378468D01*
X50200Y375262D01*
G01X40940Y387302D02*
X43939Y390301D01*
X45876D01*
G01X43814Y408139D02*
X44200Y407753D01*
Y406862D01*
X47000Y404062D01*
X49600D01*
X51437Y402225D01*
Y399799D01*
G01X38800Y406562D02*
X40424D01*
X44893Y402093D01*
X48784D01*
X49468Y401409D01*
Y399799D01*
G01X45876Y396207D02*
X45056D01*
X40800Y400463D01*
Y400962D01*
G01X45876Y392269D02*
X39320D01*
G01X48502Y507847D02*
X47902Y508447D01*
Y512585D01*
G01X48502Y504697D02*
Y501553D01*
X61371Y488684D01*
X141642D01*
G01X50380Y520331D02*
Y515063D01*
X47902Y512585D01*
G01X45951Y526729D02*
X44449D01*
X39163Y521443D01*
Y519914D01*
G01X45951Y532634D02*
X45385D01*
X43914Y534105D01*
X41010D01*
G01X45951Y530666D02*
X45667Y530950D01*
X40960D01*
X39967Y529957D01*
Y526709D01*
G01X50380Y535095D02*
Y540686D01*
X49039Y542027D01*
G01X53299Y546720D02*
X48661D01*
X48626Y546685D01*
G01D02*
Y543361D01*
X49039Y542948D01*
Y542027D01*
G01X50773Y754595D02*
Y756955D01*
X45610Y762118D01*
X40373D01*
G01X50773Y775855D02*
Y770855D01*
X49300Y769382D01*
X41423D01*
X40373Y768332D01*
G01X47502Y1663587D02*
Y1662087D01*
X47002Y1661587D01*
X40502D01*
X38502Y1663587D01*
G01X57966Y1664896D02*
X52236D01*
X50927Y1663587D01*
G01D02*
X47502D01*
G01X38502Y1668587D02*
X40502Y1670587D01*
X47002D01*
X47502Y1670087D01*
Y1668587D01*
G01D02*
X50927D01*
G01D02*
X52650Y1666864D01*
X57966D01*
G01X45052Y1681645D02*
Y1684283D01*
G01X48202Y1681645D02*
Y1679016D01*
X49069Y1678149D01*
G01D02*
X52713D01*
X56019Y1674843D01*
X59694D01*
X60525Y1674012D01*
Y1673360D01*
G01X65933Y32756D02*
Y28406D01*
G01Y44370D02*
Y48720D01*
G01X55301Y53544D02*
X57158D01*
X62336Y48366D01*
Y40714D01*
X64749Y38301D01*
X68312D01*
X70657Y40646D01*
Y44370D01*
G01X59406Y57055D02*
Y53595D01*
X63985Y49016D01*
Y41350D01*
X64911Y40424D01*
X67094D01*
X68295Y41625D01*
Y44370D01*
G01X59650Y268223D02*
X57588D01*
X54969Y270842D01*
Y273271D01*
X56279Y274581D01*
X58004D01*
X59780Y276357D01*
G01X62800Y268223D02*
X66650D01*
G01D02*
Y265316D01*
G01X62930Y276357D02*
Y272357D01*
G01D02*
X106259D01*
X132096Y298194D01*
Y342380D01*
X139950Y350234D01*
X194258D01*
X200199Y356175D01*
Y491359D01*
X223687Y514847D01*
Y522453D01*
G01X54780Y277798D02*
X58339D01*
X59780Y276357D01*
G01X54780Y277798D02*
X52717D01*
X52217Y278298D01*
Y282416D01*
X52717Y282916D01*
X54780D01*
G01D02*
X56624D01*
X58946Y285238D01*
X68050D01*
X69800Y286988D01*
Y303700D01*
X67500Y306000D01*
X64000D01*
G01X58668Y295452D02*
X62218D01*
X62567Y295103D01*
G01X64425Y290000D02*
X64288Y290137D01*
X58668D01*
G01X55254Y292892D02*
X58668D01*
G01X64000Y306000D02*
X59001D01*
X56460Y308541D01*
X54740D01*
G01Y313659D02*
X53000D01*
X52500Y313159D01*
Y308850D01*
X52816Y308534D01*
X54733D01*
X54740Y308541D01*
G01X63350Y371362D02*
Y366566D01*
X63429Y366487D01*
G01X59311Y380803D02*
Y377099D01*
X63350Y373060D01*
Y371362D01*
G01X57342Y375262D02*
Y371019D01*
X59322Y369039D01*
Y366487D01*
G01X55374Y380803D02*
Y378036D01*
X53500Y376162D01*
Y371362D01*
G01D02*
X55190Y369672D01*
Y366487D01*
G01X64872Y388333D02*
X69071D01*
X71136Y390398D01*
G01X57342Y380803D02*
Y375262D01*
G01X64872Y386364D02*
X76600D01*
G01X70500Y381562D02*
X67667Y384395D01*
X64872D01*
G01X71480Y399442D02*
Y396052D01*
X67697Y392269D01*
X64872D01*
G01X76200Y395865D02*
X73263D01*
X67699Y390301D01*
X64872D01*
G01X53658Y512639D02*
X53902Y512395D01*
Y508560D01*
X53002Y507660D01*
X52902D01*
G01X64442Y504390D02*
X61522D01*
X61402Y504510D01*
G01D02*
X58402D01*
G01X64442Y504390D02*
X111426D01*
X121652Y514616D01*
X213350D01*
X217687Y518953D01*
Y522453D01*
G01X58254Y514975D02*
Y509464D01*
X58402Y509316D01*
Y507660D01*
G01X141642Y494147D02*
X63265D01*
X52902Y504510D01*
G01X52349Y520331D02*
Y513948D01*
X53658Y512639D01*
G01X58254Y520331D02*
Y514975D01*
G01Y535095D02*
Y540392D01*
X59849Y541987D01*
G01X52349Y535095D02*
Y539977D01*
X54399Y542027D01*
G01X63148Y549835D02*
X78999D01*
X99350Y529484D01*
X123811D01*
G01X63148Y549835D02*
Y579297D01*
X56627Y585818D01*
G01X63148Y546685D02*
X59849Y543386D01*
Y541987D01*
G01X58365Y546685D02*
Y545993D01*
X54399Y542027D01*
G01X69323Y766871D02*
X65188D01*
X63229Y768830D01*
X61940D01*
X61620Y768510D01*
G01X69323Y763525D02*
X62697D01*
X60042Y766180D01*
X56440D01*
G01X72260Y1418669D02*
Y1416407D01*
X70068Y1414215D01*
X67464D01*
X66250Y1413001D01*
Y1412899D01*
G01D02*
Y1412407D01*
X66896Y1411761D01*
X71909D01*
X72378Y1412230D01*
G01X63633Y1593471D02*
X66854Y1596692D01*
Y1597165D01*
G01X65279Y1605956D02*
Y1602794D01*
X63730Y1601245D01*
Y1597720D01*
X61675Y1595665D01*
X60827D01*
X58633Y1593471D01*
G01Y1590321D02*
Y1587481D01*
G01X63633Y1590321D02*
Y1587481D01*
G01X62493Y1658400D02*
Y1656653D01*
X62152Y1656312D01*
Y1653448D01*
G01X55427Y1649962D02*
X59427D01*
G01X62152Y1653448D02*
Y1651387D01*
X59427Y1649962D01*
G01X68427D02*
X64427D01*
G01X60525Y1658400D02*
Y1657231D01*
X56821Y1653527D01*
G01X66127Y1681812D02*
X70127D01*
G01X64462Y1673360D02*
Y1678404D01*
G01D02*
X66127Y1680069D01*
Y1681812D01*
G01X59052Y1682016D02*
X55729D01*
X55202Y1681489D01*
G01D02*
Y1679408D01*
X56694Y1677916D01*
G01D02*
X58740D01*
X62493Y1674163D01*
Y1673360D01*
G01X66430D02*
Y1674556D01*
X70237Y1678363D01*
G01X77329Y149191D02*
X78993D01*
X80991Y151189D01*
G01X74179Y149191D02*
X71659D01*
G01X74176Y145191D02*
Y149188D01*
X74179Y149191D01*
G01X85942Y157775D02*
X84379D01*
X82796Y156192D01*
X80979D01*
G01D02*
X78976D01*
X77977Y157191D01*
X77329D01*
G01D02*
Y153191D01*
G01X85942Y159744D02*
X84403D01*
X82953Y161194D01*
X80965D01*
G01D02*
X80962Y161191D01*
X77329D01*
G01Y165191D02*
Y161191D01*
G01X80991Y151189D02*
X82132Y152330D01*
Y153594D01*
X84345Y155807D01*
X85942D01*
G01X74179Y153191D02*
X71778D01*
X71775Y153194D01*
G01X79729Y289822D02*
X86034Y283517D01*
X113711D01*
X120016Y289822D01*
G01X79729Y310256D02*
X86034Y303951D01*
X113711D01*
X120016Y310256D01*
G01X76600Y386364D02*
X81661D01*
X81799Y386502D01*
G01Y382219D02*
X80556Y383462D01*
X76100D01*
X74200Y381562D01*
X70500D01*
G01X81799Y395865D02*
X76200D01*
G01X71136Y390398D02*
X72129Y391391D01*
X81799D01*
G01X80378Y1409080D02*
Y1406676D01*
G01Y1412230D02*
X76378D01*
G01D02*
X72378D01*
G01X86925Y1435500D02*
X87623Y1434802D01*
Y1431310D01*
X84471Y1428158D01*
X81800D01*
X81052Y1427410D01*
G01X76000Y1427331D02*
X71009D01*
X68392Y1429948D01*
Y1432013D01*
G01D02*
Y1433000D01*
X69178Y1433786D01*
X73211D01*
X73425Y1434000D01*
G01X77000Y1447437D02*
Y1443690D01*
X76203Y1442893D01*
X73820D01*
G01X73425Y1434000D02*
Y1439398D01*
X73260Y1439563D01*
G01X72660Y1590321D02*
Y1587365D01*
G01X66854Y1605956D02*
Y1597165D01*
G01X78406Y1607782D02*
X82606D01*
G01X70567Y1625603D02*
Y1623284D01*
X69775Y1622492D01*
G01X73399Y1653408D02*
X70367Y1656440D01*
Y1658400D01*
G01X73427Y1649962D02*
Y1653380D01*
X73399Y1653408D01*
G01X73427Y1649962D02*
X77427D01*
G01X68399Y1653382D02*
Y1658400D01*
G01X68427Y1649962D02*
Y1653354D01*
X68399Y1653382D01*
G01X79117Y1666864D02*
X72926D01*
G01Y1664896D02*
X77493D01*
X79251Y1663138D01*
X83908D01*
G01X83867Y1667127D02*
X81690D01*
X81427Y1666864D01*
X79117D01*
G01X70367Y1673360D02*
Y1674119D01*
X71038Y1674790D01*
X79105D01*
X82630Y1678315D01*
G01X78127Y1681812D02*
X82127D01*
G01X68399Y1673360D02*
Y1674110D01*
X70231Y1675942D01*
X74001D01*
X76468Y1678409D01*
G01D02*
X78127Y1680068D01*
Y1681812D01*
G01X70237Y1678363D02*
X70678D01*
X74127Y1681812D01*
G01X90470Y151279D02*
Y147692D01*
X89009Y146231D01*
G01X94010Y146250D02*
X92438Y147822D01*
Y151279D01*
G01X98892Y147345D02*
X97543Y148694D01*
X96421D01*
X94407Y150708D01*
Y151279D01*
G01X92076Y140950D02*
X92197Y141071D01*
Y143853D01*
G01X87137Y143663D02*
Y142739D01*
X88926Y140950D01*
G01X88501Y151279D02*
Y149449D01*
X86634Y147582D01*
Y144166D01*
X87137Y143663D01*
G01X82026Y140950D02*
Y143491D01*
G01X84009Y146557D02*
Y152740D01*
X85107Y153838D01*
X85942D01*
G01X85176Y140950D02*
Y142142D01*
X84009Y143309D01*
Y146557D01*
G01X92438Y162303D02*
Y165422D01*
X94291Y167275D01*
G01X90470Y162303D02*
Y166127D01*
X89290Y167307D01*
G01X84377Y166361D02*
X85811D01*
X88501Y163671D01*
Y162303D01*
G01X105975Y207241D02*
X93775D01*
G01X105975Y202241D02*
X93775D01*
G01X105975Y197241D02*
X93775D01*
G01X105975Y212241D02*
X93775D01*
G01X81799Y382219D02*
X81816Y382202D01*
Y376026D01*
G01X85465Y766871D02*
X90015D01*
G01X99024D02*
X94474D01*
G01X99024Y763525D02*
X94474D01*
G01X85465Y770218D02*
X90015D01*
G01X95925Y1417000D02*
X93000D01*
G01D02*
X90075D01*
G01X95925Y1408000D02*
X93000D01*
G01D02*
X90075D01*
G01X95925Y1412500D02*
X93069D01*
G01X90075D02*
X93069D01*
G01X95925Y1421500D02*
X93000D01*
G01D02*
X90075D01*
G01X86925Y1440000D02*
Y1435500D01*
G01X90075Y1440000D02*
X92344Y1442269D01*
X103315D01*
X106572Y1439012D01*
X108681D01*
G01X95925Y1444500D02*
X93000D01*
G01D02*
X90075D01*
G01X86925D02*
X84500D01*
G01X90075Y1448500D02*
X93000D01*
G01D02*
X95925D01*
G01X86925D02*
X84500D01*
G01X83908Y1663138D02*
Y1667086D01*
X83867Y1667127D01*
G01X86127Y1681812D02*
X90127D01*
G01X82630Y1678315D02*
X86127Y1681812D01*
G01X85345Y1698511D02*
X82500D01*
G01X96101Y1696469D02*
Y1699117D01*
X98370Y1701386D01*
X102529D01*
G01X92500Y1698875D02*
X94906Y1696469D01*
X96101D01*
G01X88495Y1698511D02*
X88859Y1698875D01*
X92500D01*
G01X82500Y1706511D02*
X85345D01*
G01X88495Y1702511D02*
X92014D01*
X92500Y1702025D01*
G01X88495Y1706511D02*
Y1702511D01*
G01X92500Y1702025D02*
X93072D01*
X96555Y1705508D01*
G01D02*
X98117Y1703946D01*
X102529D01*
G01X85182Y1716331D02*
X82000D01*
G01X85182Y1724331D02*
X82000D01*
G01X88332Y1716331D02*
Y1720331D01*
G01D02*
X89501D01*
X90426Y1721256D01*
X92257D01*
G01X102583Y1720997D02*
X99343D01*
X98087Y1719741D01*
X95400D01*
G01D02*
X93772D01*
X92257Y1721256D01*
G01X88332Y1724331D02*
X88407Y1724406D01*
X92257D01*
G01X95460Y1725241D02*
X97947D01*
X99631Y1723557D01*
X102583D01*
G01X92257Y1724406D02*
X93092Y1725241D01*
X95460D01*
G01X99729Y289822D02*
X115016D01*
G01X99729Y310256D02*
X115016D01*
G01X99075Y1408000D02*
X100999D01*
X102376Y1409377D01*
G01D02*
X104840Y1411841D01*
Y1417850D01*
X107100Y1420110D01*
Y1424200D01*
X107739Y1424839D01*
X108681D01*
G01X99075Y1412500D02*
X102035Y1415460D01*
X102054D01*
X102548Y1415954D01*
G01D02*
X102979Y1416385D01*
Y1418595D01*
X105287Y1420903D01*
Y1424187D01*
X107513Y1426413D01*
X108681D01*
G01X99075Y1417000D02*
X103401Y1421326D01*
Y1424501D01*
X106888Y1427988D01*
X108681D01*
G01X99075Y1426000D02*
X100243D01*
X102076Y1427833D01*
G01D02*
X102592D01*
X105897Y1431138D01*
X108681D01*
G01X99075Y1421500D02*
X101088Y1423513D01*
Y1423933D01*
X106718Y1429563D01*
X108681D01*
G01X101500Y1436000D02*
X101000Y1435500D01*
X99075D01*
G01X101500Y1436000D02*
X103950D01*
G01D02*
X105075D01*
X105213Y1435862D01*
X108681D01*
G01X101637Y1432938D02*
X102986Y1434287D01*
X108681D01*
G01X99075Y1440000D02*
X102398D01*
G01D02*
X104961Y1437437D01*
X108681D01*
G01Y1440587D02*
X107159D01*
X103246Y1444500D01*
X102160D01*
G01D02*
X99075D01*
G01Y1448500D02*
Y1447342D01*
X100669Y1445748D01*
X104413D01*
X108000Y1442161D01*
X108681D01*
G01X107061Y1667361D02*
Y1671361D01*
G01Y1667361D02*
X112976D01*
X115928Y1670313D01*
G01X107061Y1675564D02*
Y1679564D01*
G01D02*
X110677D01*
X115928Y1674313D01*
G01X110575Y1712450D02*
X114425D01*
G01X107500Y1707450D02*
X106555Y1706505D01*
X102529D01*
G01X107425Y1712450D02*
Y1707525D01*
X107500Y1707450D01*
G01X120016Y289822D02*
Y294622D01*
G01X115016Y289822D02*
Y294622D01*
G01X120016Y310256D02*
Y315056D01*
G01X115016Y310256D02*
Y315056D01*
G01X115166Y766871D02*
X119321D01*
X119616Y767166D01*
G01X128724Y766871D02*
X124174D01*
G01X128724Y763525D02*
X124174D01*
G01X115166Y770218D02*
X119716D01*
G01X126000Y1414000D02*
X123937Y1416063D01*
Y1422181D01*
G01X370369Y1661817D02*
X357651D01*
X331087Y1635253D01*
X212089D01*
X208108Y1631272D01*
X177649D01*
X169800Y1639121D01*
X160012D01*
X140351Y1619460D01*
X121705D01*
G01X372449Y1680520D02*
X329942Y1638013D01*
X210944D01*
X206963Y1634032D01*
X178794D01*
X170945Y1641881D01*
X158867D01*
X141527Y1624541D01*
X114618D01*
G01X372395Y1677449D02*
X371274D01*
X330498Y1636673D01*
X211500D01*
X207519Y1632692D01*
X178238D01*
X170389Y1640541D01*
X159423D01*
X140648Y1621766D01*
X117655D01*
G01X120353Y1655843D02*
X126927D01*
X128633Y1657549D01*
G01X112353Y1652162D02*
X116353D01*
G01X120353D02*
X116353D01*
G01X120353D02*
Y1655843D01*
G01X124353Y1652162D02*
X128353D01*
G01X115928Y1670313D02*
X116398Y1669843D01*
X119927D01*
G01X129932Y1671300D02*
X121384D01*
X119927Y1669843D01*
G01Y1674843D02*
X116458D01*
X115928Y1674313D01*
G01X129932Y1672874D02*
X121896D01*
X119927Y1674843D01*
G01X131703Y1680945D02*
Y1682237D01*
X128727Y1685213D01*
X124983D01*
G01D02*
X123353Y1686843D01*
G01X119353Y1690391D02*
X123353D01*
G01X115353D02*
X119353D01*
G01X123353Y1686843D02*
Y1690391D01*
G01X127710Y1700166D02*
X124598D01*
X123378Y1701386D01*
X120107D01*
G01X127290Y1705666D02*
X124654D01*
X122934Y1703946D01*
X120107D01*
G01X114425Y1712450D02*
Y1714036D01*
X116500Y1716111D01*
X121731D01*
X123392Y1714450D01*
X134500D01*
X135722Y1715672D01*
G01X120161Y1720997D02*
X124767D01*
X125465Y1721695D01*
X127168D01*
G01X120161Y1723557D02*
X124583D01*
X127767Y1726741D01*
X129020D01*
G01X125183Y1716741D02*
X125067D01*
X123370Y1718438D01*
X120161D01*
G01X132692Y1718241D02*
X131192Y1716741D01*
X125183D01*
G01X130811Y524366D02*
X134248D01*
X136617Y521997D01*
G01D02*
X141417D01*
G01X130811Y526925D02*
X136545D01*
X136617Y526997D01*
G01D02*
X141417D01*
G01X150185Y674136D02*
X145328Y669279D01*
X141637D01*
X140471Y670445D01*
G01X131752Y671290D02*
Y668506D01*
G01X138052Y675290D02*
Y671290D01*
G01X134902D02*
Y668506D01*
G01X150185Y680042D02*
X149530D01*
X146543Y683029D01*
X140600D01*
G01X131752Y683290D02*
Y686074D01*
G01X143649Y672383D02*
X142147D01*
X139240Y675290D01*
X138052D01*
G01Y683290D02*
Y679290D01*
G01X143949Y677610D02*
X142363Y679196D01*
X138146D01*
X138052Y679290D01*
G01X134902Y683290D02*
Y686074D01*
G01X131319Y1432713D02*
X135287D01*
X136000Y1432000D01*
G01X144925Y1425500D02*
X143778Y1426647D01*
X140853D01*
X137500Y1430000D01*
X135500D01*
X134362Y1431138D01*
X131319D01*
G01X133278Y1656694D02*
X132353Y1655769D01*
G01Y1652162D02*
Y1655769D01*
G01X128353Y1652162D02*
X132353D01*
G01X144253Y1655843D02*
X137597D01*
G01D02*
X136428Y1657012D01*
Y1663229D01*
G01X140353Y1652162D02*
X144253D01*
G01X136353D02*
X140353D01*
G01X128633Y1657549D02*
X131703Y1660619D01*
Y1663229D01*
G01X133278Y1656694D02*
Y1663229D01*
G01X138003D02*
Y1661267D01*
X140927Y1658343D01*
X146252D01*
G01X138003Y1680945D02*
Y1682920D01*
X142426Y1687343D01*
X148427D01*
G01X132427Y1686343D02*
Y1684194D01*
X133278Y1683343D01*
G01Y1680945D02*
Y1683343D01*
G01X137427Y1686343D02*
X136428Y1685344D01*
Y1680945D01*
G01X144985Y1671863D02*
X142235D01*
X141672Y1671300D01*
X139774D01*
G01X135353Y1690512D02*
X131353D01*
G01D02*
X127353D01*
G01X132427Y1686343D02*
X135353Y1689269D01*
Y1690512D01*
G01X143353D02*
X139353D01*
G01D02*
Y1688269D01*
X137427Y1686343D01*
G01X132420Y1701436D02*
Y1701267D01*
X131319Y1700166D01*
X127710D01*
G01X143000Y1709166D02*
X139893D01*
G01X139995Y1701011D02*
X143000D01*
G01X132420Y1704586D02*
X130664D01*
X129584Y1705666D01*
X127290D01*
G01X136743Y1705166D02*
X135818Y1704241D01*
X132765D01*
X132420Y1704586D01*
G01X136743Y1709166D02*
Y1705166D01*
G01X136845Y1701011D02*
X136420Y1701436D01*
X132420D01*
G01X135722Y1715672D02*
X135842Y1715792D01*
Y1718241D01*
G01X139692Y1722241D02*
X138767Y1723166D01*
X132767D01*
G01X139692Y1718241D02*
Y1722241D01*
G01X127168Y1721695D02*
X128639Y1723166D01*
X132767D01*
G01X129020Y1726741D02*
X131342D01*
X131767Y1726316D01*
X132767D01*
G01X139692Y1726241D02*
X139617Y1726316D01*
X132767D01*
G01X149043Y32756D02*
Y29384D01*
X147920Y28261D01*
G01X149043Y44370D02*
Y48457D01*
X148780Y48720D01*
G01X150318Y221533D02*
X149231Y222620D01*
Y224204D01*
G01X150318Y227088D02*
X149231Y226001D01*
Y224204D01*
G01X150318Y213533D02*
X148739D01*
X148228Y214044D01*
Y216118D01*
G01X150318Y218383D02*
X148729D01*
X148228Y217882D01*
Y216118D01*
G01X144567Y521997D02*
X146982D01*
G01X229687Y522453D02*
X219860Y532280D01*
X151508D01*
X148791Y534997D01*
X144567D01*
G01X141417D02*
Y530997D01*
G01D02*
Y526997D01*
G01X155225Y674136D02*
X155825D01*
X159098Y670863D01*
X163372D01*
G01X155225Y676105D02*
X158037D01*
X159287Y674855D01*
X159513D01*
G01X155225Y678073D02*
X161236D01*
X162482Y679319D01*
G01X155225Y680042D02*
X157321D01*
X161735Y684456D01*
G01X150185Y676105D02*
X148866D01*
X145144Y672383D01*
X143649D01*
G01X150185Y678073D02*
X146979D01*
X145993Y679059D01*
X145398D01*
X143949Y677610D01*
G01X144866Y766871D02*
X149416D01*
G01X158425D02*
X153875D01*
G01X158425Y763525D02*
X153875D01*
G01X144866Y770218D02*
X149416D01*
G01X148075Y1421500D02*
X150432D01*
X153184Y1424252D01*
Y1432406D01*
X156174Y1435396D01*
G01X144925Y1421500D02*
Y1425500D01*
G01X162112Y1450019D02*
X154671D01*
G01X154305Y1453101D02*
X164805D01*
X170058Y1447848D01*
X381390D01*
X463361Y1365877D01*
Y1286586D01*
X401688Y1224913D01*
X366274D01*
X351413Y1210052D01*
G01X152339Y1655756D02*
X152353Y1655742D01*
Y1652162D01*
G01X148353D02*
X152353D01*
G01X146252Y1658343D02*
X149752D01*
X152339Y1655756D01*
G01X144253Y1652162D02*
Y1655843D01*
G01X149778Y1670087D02*
X146761D01*
X144985Y1671863D01*
G01X159427Y1693662D02*
X155353D01*
G01D02*
X151353D01*
G01Y1686843D02*
X148927D01*
X148427Y1687343D01*
G01X151353Y1686843D02*
Y1690512D01*
G01X147253D02*
X143353D01*
G01X154740Y1710575D02*
X158740D01*
G01X152605Y1715941D02*
X155260D01*
G01X149900D02*
X152605D01*
G01X149900Y1719791D02*
Y1715941D01*
G01X142842Y1718241D02*
X146000D01*
G01X146483Y1725636D02*
X145878Y1726241D01*
X142842D01*
G01X155260Y1721059D02*
Y1723682D01*
G01X169575Y670500D02*
Y671668D01*
X170166Y672259D01*
X175128D01*
X175369Y672500D01*
X176425D01*
G01X166425Y670500D02*
X163735D01*
X163372Y670863D01*
G01X169575Y676500D02*
Y675174D01*
X170268Y674481D01*
X174406D01*
X176425Y676500D01*
G01X166425D02*
X164780Y674855D01*
X159513D01*
G01X162482Y679319D02*
Y679528D01*
X163753Y680799D01*
X166291D01*
G01X161735Y684456D02*
X162078Y684799D01*
X166291D01*
G01X349938Y1214563D02*
X362058Y1226683D01*
X400953D01*
X461471Y1287201D01*
Y1365094D01*
X380571Y1445994D01*
X169393D01*
X165368Y1450019D01*
X162112D01*
G01X313574Y1157757D02*
Y1161827D01*
X312511Y1162890D01*
X311596D01*
X309908Y1164578D01*
Y1167042D01*
X318421Y1175555D01*
X338625D01*
X352055Y1188985D01*
Y1206160D01*
X347868Y1210347D01*
Y1216048D01*
X360273Y1228453D01*
X399863D01*
X459701Y1288291D01*
Y1364360D01*
X379954Y1444107D01*
X168724D01*
X165098Y1447733D01*
X156477D01*
G01X167850Y1491010D02*
X171380D01*
X172180Y1490210D01*
G01X165750Y1491010D02*
X163460D01*
G01X167740Y1494340D02*
X170860D01*
X172070Y1495550D01*
G01X165640Y1494340D02*
X163320D01*
G01X166388Y1518040D02*
X169288D01*
G01X166388D02*
Y1518987D01*
X165669Y1519706D01*
X164351D01*
X161305Y1520968D01*
X157923D01*
G01X169288Y1518040D02*
Y1516839D01*
X169897Y1516230D01*
X174648D01*
X175423Y1517005D01*
Y1519121D01*
X176109Y1519807D01*
X179457D01*
G01X169288Y1514420D02*
X166180D01*
G01X179457Y1517445D02*
X178703D01*
X176061Y1514803D01*
Y1514248D01*
X174423Y1512610D01*
X169908D01*
X169288Y1513230D01*
Y1514420D01*
G01X165388Y1510800D02*
X169288D01*
G01X165388D02*
Y1511135D01*
X162209Y1514314D01*
X161162D01*
G01X169288Y1510800D02*
Y1509522D01*
X170119Y1508691D01*
X173954D01*
X177072Y1511809D01*
Y1514568D01*
X178768Y1516264D01*
X181503D01*
G01X179457Y1531618D02*
X177517D01*
X174135Y1535000D01*
X167900D01*
G01D02*
X166437Y1536463D01*
X163576D01*
X162550Y1537489D01*
Y1538000D01*
G01X181503Y1530437D02*
X175891D01*
X175142Y1531186D01*
X169086D01*
X167900Y1530000D01*
G01X164650Y1534800D02*
X166555Y1532895D01*
Y1531345D01*
X167900Y1530000D01*
G01X162550Y1531600D02*
Y1534800D01*
G01X159000Y1530550D02*
X160388D01*
X161438Y1531600D01*
X162550D01*
G01X159000Y1530550D02*
Y1525480D01*
G01X162550Y1542500D02*
Y1543222D01*
X163298Y1543970D01*
X166661D01*
X167900Y1542731D01*
Y1540000D01*
G01X159000Y1541350D02*
X161400D01*
X162550Y1542500D01*
G01X181503Y1532799D02*
X178141D01*
X174643Y1536297D01*
X171603D01*
X167900Y1540000D01*
G01X159000Y1538050D02*
X162500D01*
X162550Y1538000D01*
G01X159427Y1693662D02*
Y1696652D01*
G01X158740Y1710575D02*
X162740D01*
G01Y1715941D02*
Y1713172D01*
G01D02*
Y1710575D01*
G01Y1707425D02*
Y1704885D01*
G01X165890Y1726500D02*
X167752D01*
X171945Y1730693D01*
G01X162740Y1726500D02*
X158890D01*
G01X162740Y1721059D02*
Y1723886D01*
G01D02*
Y1726500D01*
G01X178169Y154740D02*
Y158493D01*
X178799Y159123D01*
X181025D01*
G01X176425Y672500D02*
Y671215D01*
X178050Y669590D01*
X184456D01*
X186421Y671555D01*
G01X172725Y670500D02*
Y667898D01*
G01X317944Y877482D02*
Y870384D01*
X340739Y847589D01*
Y829245D01*
X328932Y817438D01*
X327844Y816987D01*
X293998D01*
X285650Y808639D01*
X280880Y806662D01*
X274008Y799790D01*
Y797637D01*
X271682Y795311D01*
X267586D01*
X249907Y777632D01*
Y770623D01*
X252610Y767920D01*
Y759622D01*
X241877Y748889D01*
X227937D01*
X214643Y735595D01*
Y713978D01*
X186537Y685872D01*
Y679027D01*
X185170Y677660D01*
X184700D01*
G01D02*
X183209D01*
X181369Y679500D01*
X177823D01*
X176425Y678102D01*
Y676500D01*
G01X172725D02*
Y679230D01*
G01X174567Y766871D02*
X179117D01*
G01X188126D02*
X183576D01*
G01X188126Y763525D02*
X183576D01*
G01X174567Y770218D02*
X179117D01*
G01X181503Y1520988D02*
X178111D01*
X177487Y1521612D01*
G01X177086Y1518121D02*
X178081D01*
X178586Y1518626D01*
X181503D01*
G01X178745Y1513218D02*
X180819D01*
X181503Y1513902D01*
G01Y1535162D02*
X178069D01*
X177533Y1535698D01*
G01X179457Y1536343D02*
X177902Y1537898D01*
X177533D01*
G01X181886Y1655566D02*
X182736D01*
X183974Y1656804D01*
G01X181886Y1652366D02*
X182313D01*
X183920Y1653973D01*
G01X181886Y1649166D02*
X182217D01*
X184139Y1651088D01*
G01X181886Y1658766D02*
X182668Y1659548D01*
X183986D01*
G01D02*
X185604D01*
X186386Y1658766D01*
G01X185760Y1710463D02*
X181760D01*
G01X185760D02*
X189760D01*
G01X178385Y1715441D02*
X181760D01*
G01X175075Y1715000D02*
X175516Y1715441D01*
X178385D01*
G01X175075Y1715000D02*
Y1711000D01*
G01X178376Y1720559D02*
X181760D01*
G01X175075Y1721000D02*
X175516Y1720559D01*
X178376D01*
G01X175075Y1721000D02*
Y1725000D01*
G01X185760Y1725801D02*
X181760D01*
G01X185760D02*
X189760D01*
G01X195979Y98067D02*
X208179D01*
G01X195979Y101217D02*
Y106017D01*
G01Y120502D02*
Y125562D01*
G01X232529Y114830D02*
X231697Y115662D01*
X227438D01*
X225674Y117426D01*
X194779D01*
X193420Y116067D01*
Y113022D01*
G01X195979Y106017D02*
X194174D01*
X190861Y109330D01*
Y113022D01*
G01X197645Y133762D02*
X195145Y136262D01*
X192845D01*
G01X195979Y125562D02*
X197645Y127228D01*
Y130612D01*
G01X192845Y140962D02*
Y136262D01*
G01Y144962D02*
Y140962D01*
G01Y144962D02*
X190500D01*
X190000Y144462D01*
Y143000D01*
G01X195995Y140962D02*
X202038D01*
X204088Y138912D01*
G01X197075Y149000D02*
X195075Y151000D01*
X186831D01*
G01X197075Y149000D02*
Y152200D01*
X197375Y152500D01*
G01X198711Y165325D02*
X204900D01*
X206310Y166735D01*
X234628D01*
G01X202776Y152500D02*
X197375D01*
G01X197575Y156500D02*
X197835Y156240D01*
X202776D01*
G01X197575Y160432D02*
Y158285D01*
X197484Y158194D01*
Y156591D01*
X197575Y156500D01*
G01X195561Y165325D02*
Y162446D01*
X197575Y160432D01*
G01X186421Y671555D02*
X191486Y676620D01*
Y684775D01*
X216763Y710052D01*
Y734716D01*
X228790Y746743D01*
X242730D01*
X254860Y758873D01*
Y768800D01*
X252071Y771589D01*
Y776797D01*
X268382Y793108D01*
X272478D01*
X276151Y796781D01*
Y798934D01*
X282082Y804865D01*
X286852Y806842D01*
X294877Y814867D01*
X328718D01*
X329814Y815321D01*
X342859Y828366D01*
Y848468D01*
X319795Y871532D01*
Y874293D01*
G01X189240Y1715441D02*
X189760Y1714921D01*
Y1713061D01*
G01D02*
Y1710463D01*
G01Y1707313D02*
Y1707584D01*
X191945Y1709769D01*
X193274D01*
G01X198760Y1712441D02*
X196763Y1710444D01*
G01X189760Y1725801D02*
Y1723041D01*
G01D02*
X189740D01*
X189240Y1722541D01*
Y1720559D01*
G01X189760Y1728951D02*
Y1731564D01*
G01X203655Y1723000D02*
X200854D01*
G01X198760Y1717559D02*
Y1719991D01*
G01X208179Y98067D02*
X235186D01*
G01X208179Y101217D02*
Y106017D01*
G01D02*
X206374D01*
X203061Y109330D01*
Y113022D01*
G01X208179Y120502D02*
X214900D01*
G01D02*
X220745D01*
X220905Y120662D01*
G01X235186Y112022D02*
X227968D01*
X224184Y115806D01*
X206634D01*
X205620Y114792D01*
Y113022D01*
G01X212224Y148760D02*
X218402D01*
G01X204268Y766871D02*
X208818D01*
G01X217827D02*
X212772D01*
G01X217827Y763525D02*
X213277D01*
G01X204268Y770218D02*
X208818D01*
G01X211862Y1701100D02*
X214722Y1703960D01*
Y1719680D01*
X211402Y1723000D01*
X209390D01*
G01X202075Y1707000D02*
X205925D01*
G01X203510Y1712441D02*
X206240D01*
G01X202075Y1707000D02*
Y1711006D01*
X203510Y1712441D01*
G01X209075Y1707000D02*
X210672Y1705403D01*
X212365D01*
G01X206240Y1717559D02*
Y1723000D01*
G01D02*
X203655D01*
G01X220905Y124662D02*
Y120662D01*
G01X224055D02*
X230588D01*
X235460Y115790D01*
G01X234331Y103286D02*
Y108211D01*
X238000Y111880D01*
Y117500D01*
X230610Y124890D01*
Y128270D01*
X222277Y136603D01*
Y144710D01*
G01X229516Y151984D02*
Y149984D01*
X231500Y148000D01*
X234000D01*
G01X222277Y148750D02*
X219763D01*
X219753Y148760D01*
X218402D01*
G01X225427Y148750D02*
Y144710D01*
G01Y148750D02*
Y150963D01*
X225090Y151300D01*
Y153395D01*
G01X225427Y144710D02*
Y143638D01*
X231870Y137195D01*
X233284D01*
G01X229516Y155134D02*
X229528Y155146D01*
X233595D01*
G01X225090Y156545D02*
X228105D01*
X229516Y155134D01*
G01X248350Y165700D02*
X243530Y170520D01*
X237670D01*
X224445Y183745D01*
Y206820D01*
G01X227595D02*
X231670D01*
X233785Y208935D01*
G01X300295Y885160D02*
Y843887D01*
X253336Y796928D01*
Y795021D01*
X240246Y781931D01*
G01X300645Y889589D02*
X297615Y886559D01*
Y845073D01*
X241166Y788624D01*
X237578D01*
G01X300451Y901406D02*
X299651D01*
X288845Y890600D01*
Y854424D01*
X269774Y835353D01*
Y832136D01*
X242994Y805356D01*
X238860D01*
G01X300389Y908936D02*
X298931D01*
X283025Y893030D01*
Y856852D01*
X244915Y818742D01*
X238860D01*
G01X299435Y904706D02*
X299151D01*
X286165Y891720D01*
Y855536D01*
X250762Y820133D01*
Y816916D01*
X244902Y811056D01*
X244308D01*
X243982Y811382D01*
X243388D01*
X242871Y810865D01*
Y810271D01*
X243197Y809945D01*
Y809351D01*
X242548Y808702D01*
X238860D01*
G01X300869Y911806D02*
X298009D01*
X280345Y894142D01*
Y862836D01*
X277116Y855043D01*
X254159Y832086D01*
X251492Y830304D01*
X239737Y825435D01*
X237578D01*
G01X299329Y922066D02*
X295683D01*
X271575Y897958D01*
Y866362D01*
X256158Y850945D01*
X252759D01*
X243981Y842167D01*
X242721D01*
X242301Y841747D01*
Y839519D01*
X241881Y839099D01*
X241150D01*
X240730Y839519D01*
Y841747D01*
X240310Y842167D01*
X238860D01*
G01X299459Y925526D02*
X295351D01*
X268895Y899070D01*
Y870874D01*
X245832Y847811D01*
X245238D01*
X244850Y848199D01*
X244256D01*
X243739Y847682D01*
Y847088D01*
X244127Y846700D01*
Y846106D01*
X243534Y845513D01*
X238860D01*
G01X298999Y929016D02*
X294399D01*
X265755Y900372D01*
Y872241D01*
X249067Y855553D01*
X238860D01*
G01X298959Y931836D02*
X293427D01*
X263075Y901484D01*
Y874675D01*
X254144Y865744D01*
X245696Y862246D01*
X237578D01*
G01X299089Y942226D02*
X291231D01*
X254305Y905300D01*
Y889845D01*
X243438Y878978D01*
X242267D01*
X241807Y878518D01*
Y877616D01*
X241347Y877156D01*
X240696D01*
X240236Y877616D01*
Y878518D01*
X239776Y878978D01*
X238860D01*
G01X299079Y944916D02*
X290129D01*
X251625Y906412D01*
Y895089D01*
X243719Y887183D01*
X243125D01*
X241889Y888419D01*
X241295D01*
X240778Y887902D01*
Y887308D01*
X242014Y886072D01*
Y885478D01*
X241497Y884961D01*
X240903D01*
X239667Y886197D01*
X239073D01*
X238556Y885680D01*
Y885086D01*
X239792Y883850D01*
Y883256D01*
X238860Y882324D01*
G01X299099Y948066D02*
X288837D01*
X248485Y907714D01*
Y901112D01*
X241774Y894401D01*
Y892698D01*
X241440Y892364D01*
X238860D01*
G01X300296Y950789D02*
X287316D01*
X245805Y909278D01*
Y906138D01*
X238724Y899057D01*
X237578D01*
G01X299149Y959806D02*
X277726D01*
X251130Y933210D01*
Y932616D01*
X251594Y932152D01*
Y931558D01*
X251077Y931041D01*
X250483D01*
X250019Y931505D01*
X249425D01*
X248908Y930988D01*
Y930394D01*
X249372Y929930D01*
Y929336D01*
X248855Y928819D01*
X248261D01*
X247797Y929283D01*
X247203D01*
X246686Y928766D01*
Y928172D01*
X247150Y927708D01*
Y927114D01*
X246633Y926597D01*
X246039D01*
X245575Y927061D01*
X244981D01*
X244295Y926375D01*
Y924234D01*
X241249Y921188D01*
Y917526D01*
X239512Y915789D01*
X238860D01*
G01X300799Y962496D02*
X276623D01*
X257779Y943652D01*
X255017D01*
X242889Y931524D01*
Y928762D01*
X238569Y924442D01*
Y920304D01*
X238060Y919795D01*
G01X300009Y965706D02*
X272629D01*
X258278Y951355D01*
X257684D01*
X257425Y951614D01*
X256831Y951613D01*
X256314Y951096D01*
Y950502D01*
X256573Y950243D01*
X256574Y949651D01*
X239749Y932826D01*
Y930064D01*
X238860Y929175D01*
G01X300969Y968856D02*
X270315D01*
X255636Y954177D01*
X253876D01*
X246030Y946331D01*
Y943169D01*
X238729Y935868D01*
X237578D01*
G01X299139Y979746D02*
X294255D01*
X293285Y978776D01*
X256628D01*
X253563Y975711D01*
Y972969D01*
X251617Y971023D01*
X251023D01*
X250158Y971888D01*
X249564D01*
X249047Y971371D01*
Y970777D01*
X249912Y969912D01*
Y969318D01*
X242925Y962331D01*
Y956665D01*
X238860Y952600D01*
G01X302349Y985166D02*
X299860Y985165D01*
X299356Y985669D01*
X292595D01*
X291865Y984939D01*
X251506D01*
X246865Y980298D01*
Y977963D01*
X244095Y975193D01*
Y970490D01*
X237985Y964380D01*
Y963299D01*
G01X228860Y962286D02*
X227540Y960966D01*
G01X306842Y985907D02*
X305463Y987286D01*
X291813D01*
X290806Y986279D01*
X250950D01*
X245525Y980854D01*
Y978519D01*
X242755Y975749D01*
Y971201D01*
X238860Y967306D01*
G01X300429Y982516D02*
X293233D01*
X292173Y981456D01*
X264718D01*
X261765Y982679D01*
X252443D01*
X249125Y979361D01*
Y977026D01*
X246355Y974256D01*
Y969553D01*
X240245Y963443D01*
Y958363D01*
X238518Y956636D01*
G01X299174Y998501D02*
X298179Y999496D01*
X292441D01*
X285774Y992829D01*
X248587D01*
X239245Y983487D01*
Y981139D01*
X238242Y980136D01*
G01X300224Y1001251D02*
X299299Y1002176D01*
X291329D01*
X284662Y995509D01*
X244595D01*
X239254Y990168D01*
Y987769D01*
X238209Y986724D01*
G01X301919Y993976D02*
X300889Y992946D01*
X289683D01*
X286616Y989879D01*
X249430D01*
X241925Y982374D01*
Y980013D01*
X239155Y977243D01*
Y973909D01*
G01X297653Y1007712D02*
X293073D01*
X283550Y998189D01*
X266187D01*
X263427Y1000949D01*
X245856D01*
X238324Y993417D01*
G01X299599Y1033007D02*
X286270D01*
X283609Y1035668D01*
X266939D01*
X260839Y1029568D01*
X238860D01*
G01X299599Y1035764D02*
X287305D01*
X284721Y1038348D01*
X265789D01*
X263702Y1036261D01*
X238860D01*
G01X299599Y1038444D02*
X288417D01*
X285833Y1041028D01*
X253290D01*
X251364Y1042954D01*
X238860D01*
G01X301969Y1048666D02*
X299617D01*
X297564Y1046613D01*
X257168D01*
X250092Y1053689D01*
X240999D01*
X239595Y1055093D01*
Y1058951D01*
X238860Y1059686D01*
G01X301069Y1041486D02*
X289167D01*
X286945Y1043708D01*
X256277D01*
X251177Y1048808D01*
X239698D01*
X238860Y1049646D01*
G01X299550Y1061436D02*
X297082D01*
X292125Y1056479D01*
X256898D01*
X255708Y1057669D01*
X255707Y1058263D01*
X256176Y1058732D01*
Y1059326D01*
X255658Y1059844D01*
X255066Y1059843D01*
X254597Y1059374D01*
X254003D01*
X253486Y1059891D01*
X253485Y1060485D01*
X253954Y1060954D01*
Y1061548D01*
X253436Y1062066D01*
X252844Y1062065D01*
X252375Y1061596D01*
X251781D01*
X243371Y1070006D01*
X241830D01*
X241296Y1070540D01*
Y1071134D01*
X242016Y1071854D01*
Y1072448D01*
X241499Y1072965D01*
X240905D01*
X240185Y1072245D01*
X239591D01*
X238764Y1073072D01*
G01X298768Y1064116D02*
X295970D01*
X291013Y1059159D01*
X261400D01*
X240793Y1079766D01*
X239078D01*
G01X299038Y1073186D02*
X273371D01*
X272951Y1072766D01*
Y1071559D01*
X272531Y1071139D01*
X271800D01*
X271380Y1071559D01*
Y1072766D01*
X270960Y1073186D01*
X270229D01*
X269809Y1072766D01*
Y1071559D01*
X269389Y1071139D01*
X268658D01*
X268238Y1071559D01*
Y1072766D01*
X267818Y1073186D01*
X263915D01*
X240604Y1096497D01*
X239078D01*
G01X299089Y1076236D02*
X266353D01*
X239399Y1103190D01*
X239078D01*
G01X299059Y1079566D02*
X269775D01*
X239458Y1109883D01*
X239078D01*
G01X300727Y1082246D02*
X272653D01*
X241715Y1113184D01*
X241121Y1113185D01*
X240568Y1112632D01*
X239974D01*
X239456Y1113150D01*
X239457Y1113742D01*
X240010Y1114295D01*
Y1114889D01*
X239032Y1115867D01*
G01X299860Y1092124D02*
X280185D01*
X246978Y1125331D01*
Y1126287D01*
X239957Y1133308D01*
X239078D01*
G01X299079Y1099311D02*
X283194D01*
X249608Y1132897D01*
Y1139981D01*
X242084Y1147505D01*
X239590D01*
G01X299059Y1096082D02*
X281981D01*
X238722Y1139341D01*
G01X300200Y1101991D02*
X284306D01*
X252288Y1134009D01*
Y1140823D01*
X253190Y1141725D01*
Y1144635D01*
X246609Y1151216D01*
X244902D01*
X243871Y1150185D01*
X240761D01*
X238428Y1152518D01*
G01X299264Y1110964D02*
X289923D01*
X262982Y1137905D01*
Y1151947D01*
X246077Y1168852D01*
X240127D01*
X239078Y1169901D01*
G01X298859Y1115536D02*
X289143D01*
X265662Y1139017D01*
Y1153093D01*
X244994Y1173761D01*
X239078Y1176212D01*
G01X299059Y1118711D02*
X290410D01*
X268833Y1140288D01*
Y1156968D01*
X242296Y1183505D01*
X239078D01*
G01X299284Y1121391D02*
X291522D01*
X271513Y1141400D01*
Y1160076D01*
X243962Y1187627D01*
X243368D01*
X241940Y1186199D01*
X241348Y1186198D01*
X240830Y1186716D01*
Y1187310D01*
X242258Y1188738D01*
X242257Y1189332D01*
X241391Y1190198D01*
X239078D01*
G01X299059Y1130566D02*
X295021D01*
X280388Y1145199D01*
Y1169453D01*
X246791Y1203050D01*
X245038Y1203047D01*
X244638Y1203447D01*
Y1204041D01*
X244914Y1204317D01*
Y1204911D01*
X244397Y1205428D01*
X243803D01*
X243527Y1205152D01*
X242933D01*
X241982Y1206103D01*
Y1207649D01*
X241562Y1208069D01*
X240831D01*
X240411Y1207649D01*
Y1207350D01*
X239991Y1206930D01*
X239079D01*
X239078Y1206931D01*
G01X299159Y1133766D02*
X295613D01*
X283068Y1146311D01*
Y1171751D01*
X241196Y1213623D01*
X239078D01*
G01X299159Y1136966D02*
X297159D01*
X286208Y1147917D01*
Y1174253D01*
X255506Y1204955D01*
Y1209399D01*
X244589Y1220316D01*
X239078D01*
G01X299159Y1140166D02*
X297959D01*
X288888Y1149237D01*
Y1175365D01*
X267522Y1196731D01*
Y1201175D01*
X256305Y1212392D01*
Y1213498D01*
X255747Y1214056D01*
X254641D01*
X254083Y1214614D01*
Y1215720D01*
X253525Y1216278D01*
X252419D01*
X251861Y1216836D01*
Y1217942D01*
X251303Y1218500D01*
X250197D01*
X249639Y1219058D01*
Y1220164D01*
X249081Y1220722D01*
X247975D01*
X247417Y1221280D01*
Y1222386D01*
X246859Y1222944D01*
X245753D01*
X245195Y1223502D01*
Y1224608D01*
X244637Y1225166D01*
X243531D01*
X241688Y1227009D01*
X239078D01*
G01X299069Y1152776D02*
Y1184174D01*
X255577Y1227666D01*
Y1228316D01*
X256583Y1229322D01*
Y1229972D01*
X256122Y1230433D01*
X255472D01*
X254466Y1229427D01*
X253816D01*
X253153Y1230090D01*
Y1234534D01*
X243946Y1243741D01*
X239078D01*
G01X301859Y1155428D02*
Y1184732D01*
X300510Y1187988D01*
X298403Y1193076D01*
X275795Y1215684D01*
X275145D01*
X274608Y1215147D01*
X273958D01*
X273497Y1215608D01*
Y1216258D01*
X274034Y1216795D01*
Y1217445D01*
X273573Y1217906D01*
X272923D01*
X272386Y1217369D01*
X271736D01*
X271275Y1217830D01*
Y1218480D01*
X271812Y1219017D01*
Y1219667D01*
X271351Y1220128D01*
X270701D01*
X270164Y1219591D01*
X269514D01*
X269053Y1220052D01*
Y1220702D01*
X269590Y1221239D01*
Y1221889D01*
X241045Y1250434D01*
X239078D01*
G01X238059Y32756D02*
Y26235D01*
G01X233335Y32756D02*
Y17665D01*
G01X235697Y32756D02*
Y21585D01*
G01X240421Y32756D02*
Y21210D01*
X241306Y20325D01*
G01X245146Y32756D02*
Y28065D01*
X246356Y26855D01*
G01X242783Y32756D02*
Y26617D01*
X246506Y22894D01*
Y20365D01*
G01X233335Y44370D02*
Y57341D01*
G01X245146Y44370D02*
Y51547D01*
X249909Y56310D01*
Y58971D01*
G01X242783Y44370D02*
Y50701D01*
X245330Y53248D01*
Y56939D01*
G01X239734Y57435D02*
X241582Y55587D01*
Y52732D01*
X240516Y51666D01*
Y44465D01*
X240421Y44370D01*
G01X238059D02*
Y52608D01*
X239816Y54365D01*
G01X233335Y57341D02*
X236266Y60272D01*
Y62287D01*
G01X245330Y56939D02*
X244552D01*
X242373Y59118D01*
Y60394D01*
X244266Y62287D01*
G01X240266D02*
X239734Y61755D01*
Y57435D01*
G01X236266Y65437D02*
Y74382D01*
X237746Y75862D01*
X242145D01*
G01X235186Y98067D02*
Y84914D01*
X242145Y77955D01*
Y75862D01*
G01X244266Y65437D02*
X242920Y66783D01*
Y67915D01*
G01X242145Y71862D02*
X241033Y72974D01*
X238849D01*
X238846Y72977D01*
G01D02*
Y66857D01*
X240266Y65437D01*
G01X247487Y107835D02*
X243487D01*
G01D02*
X237932D01*
X237929Y107838D01*
G01X238297Y127118D02*
Y130097D01*
X238600Y130400D01*
G01X234125Y142062D02*
Y144041D01*
X236916Y146832D01*
G01X242215Y146879D02*
X236963D01*
X236916Y146832D01*
G01X242215Y144320D02*
X244781D01*
X245068Y144607D01*
Y146155D01*
X244344Y146879D01*
X242215D01*
G01X233595Y159071D02*
X234546D01*
X237396Y161921D01*
Y163965D01*
G01D02*
X239717Y161644D01*
Y158293D01*
X240407Y157603D01*
X242255D01*
G01X233595Y155146D02*
Y156908D01*
X233503Y157000D01*
Y158979D01*
X233595Y159071D01*
G01X245486Y159705D02*
X245621Y159570D01*
Y155882D01*
X244783Y155044D01*
X242255D01*
G01X233595Y151996D02*
X236104D01*
G01X233785Y208935D02*
X236241Y211391D01*
X240708D01*
G01X250615Y224370D02*
X248760Y222515D01*
Y218340D01*
X245600Y215180D01*
Y208120D01*
X249960Y203760D01*
X259385D01*
X263285Y207660D01*
G01X247465Y224370D02*
X245575Y222480D01*
Y217805D01*
X242901Y215131D01*
X240708D01*
G01X232981Y743983D02*
X243346D01*
X263271Y763908D01*
Y771988D01*
G01X240200Y766300D02*
X239668D01*
X239097Y766871D01*
X233969D01*
G01Y770218D02*
X238519D01*
G01X301635Y882482D02*
Y843331D01*
X268296Y809992D01*
Y809398D01*
X268972Y808722D01*
Y808128D01*
X268455Y807611D01*
X267861D01*
X267185Y808287D01*
X266591D01*
X266074Y807770D01*
Y807176D01*
X266750Y806500D01*
Y805906D01*
X266233Y805389D01*
X265639D01*
X264963Y806065D01*
X264369D01*
X263852Y805548D01*
Y804954D01*
X264528Y804278D01*
Y803684D01*
X264011Y803167D01*
X263417D01*
X262741Y803843D01*
X262147D01*
X261630Y803326D01*
Y802732D01*
X262306Y802056D01*
Y801462D01*
X261789Y800945D01*
X261195D01*
X260519Y801621D01*
X259925D01*
X259408Y801104D01*
Y800510D01*
X260084Y799834D01*
Y799240D01*
X259567Y798723D01*
X258973D01*
X258297Y799399D01*
X257703D01*
X257186Y798882D01*
Y798288D01*
X257862Y797612D01*
Y797018D01*
X257345Y796501D01*
X256751D01*
X256075Y797177D01*
X255481D01*
X254676Y796372D01*
Y793569D01*
X238018Y776911D01*
X233969D01*
G01X301702Y888669D02*
X298955Y885922D01*
Y844517D01*
X251619Y797181D01*
Y796549D01*
X251996Y796172D01*
Y795578D01*
X251479Y795061D01*
X250885D01*
X250508Y795438D01*
X249914D01*
X249397Y794921D01*
Y794327D01*
X249774Y793950D01*
Y793356D01*
X249257Y792839D01*
X248663D01*
X248286Y793216D01*
X247692D01*
X247175Y792699D01*
Y792105D01*
X247552Y791728D01*
Y791134D01*
X247035Y790617D01*
X246441D01*
X246064Y790994D01*
X245470D01*
X244953Y790477D01*
Y789883D01*
X245330Y789506D01*
Y788912D01*
X244813Y788395D01*
X244219D01*
X243842Y788772D01*
X243248D01*
X242731Y788255D01*
Y787661D01*
X243108Y787284D01*
Y786690D01*
X242591Y786173D01*
X241997D01*
X241620Y786550D01*
X241026D01*
X240509Y786033D01*
Y785439D01*
X240886Y785062D01*
Y784468D01*
X240022Y783604D01*
X233969D01*
G01X301309Y900506D02*
X300892Y900089D01*
X300336D01*
X290185Y889938D01*
Y853867D01*
X282260Y845942D01*
Y845348D01*
X282835Y844773D01*
Y844179D01*
X282318Y843662D01*
X281724D01*
X281149Y844237D01*
X280555D01*
X280038Y843720D01*
Y843126D01*
X280668Y842496D01*
Y841902D01*
X280151Y841385D01*
X279557D01*
X278927Y842015D01*
X278333D01*
X277816Y841498D01*
Y840904D01*
X278831Y839889D01*
Y839295D01*
X278314Y838778D01*
X277720D01*
X276705Y839793D01*
X276111D01*
X275594Y839276D01*
Y838682D01*
X276609Y837667D01*
Y837073D01*
X276092Y836556D01*
X275498D01*
X274483Y837571D01*
X273889D01*
X273372Y837054D01*
Y836460D01*
X274387Y835445D01*
Y834851D01*
X273870Y834334D01*
X273276D01*
X272261Y835349D01*
X271667D01*
X271151Y834833D01*
Y834238D01*
X272175Y833214D01*
Y832619D01*
X242437Y802881D01*
X241843D01*
X240718Y804006D01*
X240124D01*
X239607Y803489D01*
Y802895D01*
X240732Y801770D01*
Y801176D01*
X239892Y800336D01*
X233969D01*
G01X300033Y902987D02*
X299332D01*
X287505Y891160D01*
Y854980D01*
X267837Y835312D01*
Y834718D01*
X268433Y834122D01*
X268434Y833530D01*
X267916Y833012D01*
X267322D01*
X266726Y833608D01*
X266132Y833607D01*
X265615Y833090D01*
Y832496D01*
X266211Y831900D01*
X266212Y831308D01*
X265694Y830790D01*
X265100D01*
X264504Y831386D01*
X263910Y831385D01*
X263393Y830868D01*
Y830274D01*
X263989Y829678D01*
X263990Y829086D01*
X263472Y828568D01*
X262878D01*
X262282Y829164D01*
X261688Y829163D01*
X261171Y828646D01*
Y828052D01*
X261767Y827456D01*
X261768Y826864D01*
X261250Y826346D01*
X260656D01*
X260060Y826942D01*
X259466Y826941D01*
X258949Y826424D01*
Y825830D01*
X259545Y825234D01*
X259546Y824642D01*
X259028Y824124D01*
X258434D01*
X257838Y824720D01*
X257244Y824719D01*
X256727Y824202D01*
Y823608D01*
X257323Y823012D01*
X257324Y822420D01*
X256806Y821902D01*
X256212D01*
X255616Y822498D01*
X255022Y822497D01*
X254505Y821980D01*
Y821386D01*
X255101Y820790D01*
X255102Y820198D01*
X254584Y819680D01*
X253990D01*
X253394Y820276D01*
X252800Y820275D01*
X252102Y819577D01*
Y816360D01*
X242771Y807029D01*
X233969D01*
G01X300609Y907156D02*
X299047D01*
X284365Y892474D01*
Y856282D01*
X247954Y819871D01*
Y819277D01*
X248961Y818270D01*
X248962Y817678D01*
X248444Y817160D01*
X247850Y817159D01*
X246836Y818173D01*
X246242Y818172D01*
X245724Y817654D01*
X245725Y817062D01*
X246739Y816048D01*
X246740Y815456D01*
X246222Y814938D01*
X245628Y814937D01*
X243163Y817402D01*
X242569Y817401D01*
X242051Y816883D01*
X242052Y816291D01*
X244038Y814305D01*
X244039Y813713D01*
X243521Y813195D01*
X242927Y813194D01*
X242398Y813723D01*
X241805Y813722D01*
X233969D01*
G01X300024Y910341D02*
X298440D01*
X281685Y893586D01*
Y857652D01*
X249179Y825146D01*
X248585D01*
X246989Y826742D01*
X246395Y826741D01*
X245878Y826224D01*
Y825630D01*
X247474Y824034D01*
X247475Y823442D01*
X246957Y822924D01*
X246363D01*
X244749Y824538D01*
X244155Y824537D01*
X243638Y824020D01*
Y823426D01*
X245252Y821812D01*
X245253Y821220D01*
X244448Y820415D01*
X233969D01*
G01X299069Y920436D02*
X295949D01*
X272915Y897402D01*
Y865573D01*
X255612Y848270D01*
X255018D01*
X253834Y849454D01*
X253240D01*
X252723Y848937D01*
Y848343D01*
X253907Y847159D01*
Y846565D01*
X253390Y846048D01*
X252796D01*
X251612Y847232D01*
X251018D01*
X250501Y846715D01*
Y846121D01*
X251685Y844937D01*
Y844343D01*
X251168Y843826D01*
X250574D01*
X249390Y845010D01*
X248796D01*
X248279Y844493D01*
Y843899D01*
X249463Y842715D01*
Y842121D01*
X248946Y841604D01*
X248352D01*
X247168Y842788D01*
X246574D01*
X246057Y842271D01*
Y841677D01*
X247241Y840493D01*
Y839899D01*
X246724Y839382D01*
X246130D01*
X244946Y840566D01*
X244352D01*
X243835Y840049D01*
Y839455D01*
X245019Y838271D01*
Y837677D01*
X244489Y837147D01*
X233969D01*
G01X299029Y923836D02*
X295557D01*
X270235Y898514D01*
Y870318D01*
X267613Y867696D01*
Y867046D01*
X268467Y866192D01*
Y865542D01*
X268006Y865081D01*
X267356D01*
X266502Y865935D01*
X265852D01*
X265391Y865474D01*
Y864824D01*
X266245Y863970D01*
Y863320D01*
X265784Y862859D01*
X265134D01*
X264280Y863713D01*
X263630D01*
X263169Y863252D01*
Y862602D01*
X264023Y861748D01*
Y861098D01*
X263562Y860637D01*
X262912D01*
X262058Y861491D01*
X261408D01*
X260947Y861030D01*
Y860380D01*
X261801Y859526D01*
Y858876D01*
X261340Y858415D01*
X260690D01*
X259836Y859269D01*
X259186D01*
X258725Y858808D01*
Y858158D01*
X259579Y857304D01*
Y856654D01*
X259118Y856193D01*
X258468D01*
X257614Y857047D01*
X256964D01*
X256503Y856586D01*
Y855936D01*
X257151Y855288D01*
Y854638D01*
X256690Y854177D01*
X256040D01*
X255392Y854825D01*
X254742D01*
X254281Y854364D01*
Y853714D01*
X254599Y853396D01*
Y852746D01*
X254138Y852285D01*
X253488D01*
X253170Y852603D01*
X252520D01*
X243757Y843840D01*
X233969D01*
G01X299119Y927496D02*
X294775D01*
X267095Y899816D01*
Y871621D01*
X246007Y850533D01*
X244688D01*
X244268Y850953D01*
Y853769D01*
X243848Y854189D01*
X243117D01*
X242697Y853769D01*
Y850449D01*
X242277Y850029D01*
X241546D01*
X241126Y850449D01*
Y853769D01*
X240706Y854189D01*
X239975D01*
X239555Y853769D01*
Y850953D01*
X239135Y850533D01*
X233969D01*
G01X298969Y930486D02*
X293973D01*
X264415Y900928D01*
Y874119D01*
X247522Y857226D01*
X245799D01*
X245379Y857646D01*
Y860119D01*
X244959Y860539D01*
X244228D01*
X243808Y860119D01*
Y857646D01*
X243388Y857226D01*
X242657D01*
X242237Y857646D01*
Y860119D01*
X241817Y860539D01*
X241086D01*
X240666Y860119D01*
Y857646D01*
X240246Y857226D01*
X233969D01*
G01X298939Y940806D02*
X291707D01*
X255645Y904744D01*
Y889289D01*
X254038Y887682D01*
Y887088D01*
X255344Y885782D01*
Y885188D01*
X254827Y884671D01*
X254233D01*
X252927Y885977D01*
X252333D01*
X251816Y885460D01*
Y884866D01*
X253122Y883560D01*
Y882966D01*
X252605Y882449D01*
X252011D01*
X250705Y883755D01*
X250111D01*
X249594Y883238D01*
Y882644D01*
X250900Y881338D01*
Y880744D01*
X250383Y880227D01*
X249789D01*
X248483Y881533D01*
X247889D01*
X247372Y881016D01*
Y880422D01*
X248678Y879116D01*
Y878522D01*
X248161Y878005D01*
X247567D01*
X246261Y879311D01*
X245667D01*
X245150Y878794D01*
Y878200D01*
X246456Y876894D01*
Y876300D01*
X245939Y875783D01*
X245345D01*
X244039Y877089D01*
X243445D01*
X242928Y876572D01*
Y875978D01*
X244234Y874672D01*
Y874078D01*
X243717Y873561D01*
X243123D01*
X241817Y874867D01*
X241223D01*
X240314Y873958D01*
X233969D01*
G01X299119Y943566D02*
X290675D01*
X252965Y905856D01*
Y894482D01*
X251299Y892816D01*
Y892222D01*
X252746Y890775D01*
X252745Y890181D01*
X252228Y889664D01*
X251634D01*
X250187Y891111D01*
X249595Y891112D01*
X249077Y890594D01*
Y890000D01*
X250524Y888553D01*
X250523Y887959D01*
X250006Y887442D01*
X249412D01*
X247965Y888889D01*
X247373Y888890D01*
X246855Y888372D01*
Y887778D01*
X248302Y886331D01*
X248301Y885737D01*
X247784Y885220D01*
X247190D01*
X245743Y886667D01*
X245151Y886668D01*
X244633Y886150D01*
Y885556D01*
X246080Y884109D01*
X246079Y883515D01*
X245562Y882998D01*
X244968D01*
X243521Y884445D01*
X242929Y884446D01*
X242411Y883928D01*
Y883334D01*
X243858Y881887D01*
X243857Y881293D01*
X243340Y880776D01*
X242746D01*
X241299Y882223D01*
X240707Y882224D01*
X239134Y880651D01*
X233969D01*
G01X299099Y946716D02*
X289383D01*
X249825Y907158D01*
Y899399D01*
X249215Y898789D01*
X248092D01*
X247558Y898255D01*
X247559Y897663D01*
X249236Y895986D01*
Y895392D01*
X248719Y894875D01*
X248125Y894874D01*
X246448Y896551D01*
X245854D01*
X245336Y896033D01*
X245337Y895441D01*
X247014Y893764D01*
Y893170D01*
X246497Y892653D01*
X245903Y892652D01*
X244226Y894329D01*
X243632D01*
X243114Y893811D01*
X243115Y893219D01*
X244792Y891542D01*
Y890948D01*
X244275Y890431D01*
X243681Y890430D01*
X239733D01*
X236647Y887344D01*
X233969D01*
G01X299079Y949446D02*
X287869D01*
X247145Y908722D01*
Y904730D01*
X246435Y904020D01*
Y903159D01*
X247145Y902449D01*
Y901692D01*
X246305Y900852D01*
X245711Y900851D01*
X244382Y902180D01*
X243788D01*
X243270Y901662D01*
X243271Y901070D01*
X244600Y899741D01*
Y899147D01*
X244083Y898630D01*
X243489Y898629D01*
X242160Y899958D01*
X241566D01*
X241048Y899440D01*
X241049Y898848D01*
X242378Y897519D01*
Y896925D01*
X241387Y895934D01*
X240399D01*
X239013Y897320D01*
X238363D01*
X237689Y896646D01*
Y895786D01*
X235940Y894037D01*
X233969D01*
G01X299839Y958466D02*
X280423D01*
X278621Y956664D01*
X278027Y956663D01*
X277556Y957134D01*
X276962D01*
X276444Y956616D01*
X276445Y956024D01*
X276916Y955553D01*
Y954959D01*
X276399Y954442D01*
X275805Y954441D01*
X275334Y954912D01*
X274740D01*
X274222Y954394D01*
X274223Y953802D01*
X274694Y953331D01*
Y952737D01*
X274177Y952220D01*
X273583Y952219D01*
X273112Y952690D01*
X272518D01*
X272000Y952172D01*
X272001Y951580D01*
X272472Y951109D01*
Y950515D01*
X271955Y949998D01*
X271361Y949997D01*
X270890Y950468D01*
X270296D01*
X269778Y949950D01*
X269779Y949358D01*
X270250Y948887D01*
Y948293D01*
X269733Y947776D01*
X269139Y947775D01*
X268668Y948246D01*
X268074D01*
X267556Y947728D01*
X267557Y947136D01*
X268028Y946665D01*
Y946071D01*
X267511Y945554D01*
X266917Y945553D01*
X266446Y946024D01*
X265852D01*
X265334Y945506D01*
X265335Y944914D01*
X265806Y944443D01*
Y943849D01*
X265289Y943332D01*
X264695Y943331D01*
X264224Y943802D01*
X263630D01*
X263112Y943284D01*
X263113Y942692D01*
X263584Y942221D01*
Y941627D01*
X263067Y941110D01*
X262473Y941109D01*
X262002Y941580D01*
X261408D01*
X260890Y941062D01*
X260891Y940470D01*
X261362Y939999D01*
Y939405D01*
X260845Y938888D01*
X260251Y938887D01*
X259780Y939358D01*
X259186D01*
X258668Y938840D01*
X258669Y938248D01*
X259140Y937777D01*
Y937183D01*
X258623Y936666D01*
X258029Y936665D01*
X257558Y937136D01*
X256964D01*
X256446Y936618D01*
X256447Y936026D01*
X256918Y935555D01*
Y934961D01*
X256401Y934444D01*
X255807Y934443D01*
X255336Y934914D01*
X254742D01*
X254224Y934396D01*
X254225Y933804D01*
X254696Y933333D01*
Y932739D01*
X242589Y920632D01*
Y916936D01*
X236422Y910769D01*
X233969D01*
G01X300779Y964366D02*
X273185D01*
X272140Y963321D01*
X272139Y962727D01*
X272748Y962118D01*
Y961524D01*
X272230Y961006D01*
X271638Y961007D01*
X271029Y961616D01*
X270435D01*
X269918Y961099D01*
X269917Y960505D01*
X270526Y959896D01*
Y959302D01*
X270008Y958784D01*
X269416Y958785D01*
X268807Y959394D01*
X268213D01*
X267696Y958877D01*
X267695Y958283D01*
X268304Y957674D01*
Y957080D01*
X267786Y956562D01*
X267194Y956563D01*
X266585Y957172D01*
X265991D01*
X265474Y956655D01*
X265473Y956061D01*
X266082Y955452D01*
Y954858D01*
X265564Y954340D01*
X264972Y954341D01*
X264363Y954950D01*
X263769D01*
X263252Y954433D01*
X263251Y953839D01*
X263860Y953230D01*
Y952636D01*
X263342Y952118D01*
X262750Y952119D01*
X262141Y952728D01*
X261547D01*
X261030Y952211D01*
X261029Y951617D01*
X261638Y951008D01*
Y950414D01*
X261120Y949896D01*
X260528Y949897D01*
X259919Y950506D01*
X259325D01*
X258808Y949989D01*
X258807Y949395D01*
X259416Y948786D01*
Y948192D01*
X258898Y947674D01*
X258306Y947675D01*
X257697Y948284D01*
X257103D01*
X256586Y947767D01*
X256585Y947173D01*
X257194Y946564D01*
Y945970D01*
X256676Y945452D01*
X256084Y945453D01*
X255475Y946062D01*
X254881D01*
X241089Y932270D01*
Y929508D01*
X235736Y924155D01*
X233969D01*
G01X299099Y961146D02*
X277169D01*
X257956Y941933D01*
X257362D01*
X256984Y942311D01*
X256392Y942312D01*
X255874Y941794D01*
Y941200D01*
X256252Y940822D01*
X256251Y940228D01*
X255734Y939711D01*
X255140D01*
X254366Y940485D01*
X253774Y940486D01*
X253256Y939968D01*
Y939374D01*
X254030Y938600D01*
X254029Y938006D01*
X253512Y937489D01*
X252918D01*
X252144Y938263D01*
X251552Y938264D01*
X251034Y937746D01*
Y937152D01*
X251808Y936378D01*
X251807Y935784D01*
X251290Y935267D01*
X250696D01*
X249922Y936041D01*
X249330Y936042D01*
X248812Y935524D01*
Y934930D01*
X249586Y934156D01*
X249585Y933562D01*
X249068Y933045D01*
X248474D01*
X247700Y933819D01*
X247108Y933820D01*
X246590Y933302D01*
Y932708D01*
X247364Y931934D01*
X247363Y931340D01*
X246846Y930823D01*
X246252D01*
X245478Y931597D01*
X244886Y931598D01*
X244368Y931080D01*
Y930486D01*
X245142Y929712D01*
X245141Y929118D01*
X242079Y926056D01*
Y925462D01*
X242391Y925150D01*
X242392Y924558D01*
X241874Y924040D01*
X241280D01*
X240968Y924352D01*
X240374Y924351D01*
X239909Y923886D01*
Y918083D01*
X239288Y917462D01*
X233969D01*
G01X299199Y967306D02*
X270661D01*
X270111Y966756D01*
Y965654D01*
X269551Y965094D01*
X268449D01*
X267889Y964534D01*
Y963432D01*
X267329Y962872D01*
X266227D01*
X265667Y962312D01*
Y961210D01*
X265107Y960650D01*
X264005D01*
X263445Y960090D01*
Y958988D01*
X262885Y958428D01*
X261783D01*
X261223Y957868D01*
Y956766D01*
X260663Y956206D01*
X259561D01*
X259001Y955646D01*
Y954544D01*
X258441Y953984D01*
X257339D01*
X256192Y952837D01*
X254432D01*
X253778Y952183D01*
Y951589D01*
X254805Y950562D01*
Y949968D01*
X254288Y949451D01*
X253694D01*
X252667Y950478D01*
X252073D01*
X251556Y949961D01*
Y949367D01*
X252583Y948340D01*
Y947746D01*
X252066Y947229D01*
X251472D01*
X250445Y948256D01*
X249851D01*
X249334Y947739D01*
Y947145D01*
X250361Y946118D01*
Y945524D01*
X249844Y945007D01*
X249250D01*
X248223Y946034D01*
X247629D01*
X247370Y945775D01*
Y942387D01*
X235831Y930848D01*
X233969D01*
G01X300101Y977436D02*
X299646D01*
X298943Y978139D01*
X298075D01*
X297372Y977436D01*
X296504D01*
X295801Y978139D01*
X294933D01*
X294230Y977436D01*
X257852D01*
X257301Y976885D01*
Y976291D01*
X258982Y974610D01*
Y974016D01*
X258465Y973499D01*
X257871D01*
X256014Y975356D01*
X255420D01*
X254903Y974839D01*
Y974245D01*
X255522Y973626D01*
Y972438D01*
X256166Y971794D01*
Y971200D01*
X255649Y970683D01*
X255055D01*
X254411Y971327D01*
X253817D01*
X253300Y970810D01*
Y970216D01*
X253944Y969572D01*
Y968978D01*
X253427Y968461D01*
X252833D01*
X252189Y969105D01*
X251595D01*
X251078Y968588D01*
Y967994D01*
X251722Y967350D01*
Y966756D01*
X251205Y966239D01*
X250611D01*
X249967Y966883D01*
X249373D01*
X248856Y966366D01*
Y965772D01*
X249500Y965128D01*
Y964534D01*
X248983Y964017D01*
X248389D01*
X247745Y964661D01*
X247151D01*
X246634Y964144D01*
Y963550D01*
X247278Y962906D01*
Y962312D01*
X246761Y961795D01*
X246167D01*
X245523Y962439D01*
X244929D01*
X244265Y961775D01*
Y955793D01*
X236053Y947580D01*
X233969D01*
G01X299919Y981116D02*
X293729D01*
X292729Y980116D01*
X264451D01*
X261498Y981339D01*
X259963D01*
X259233Y980609D01*
X258392D01*
X257662Y981339D01*
X256821D01*
X256091Y980609D01*
X255250D01*
X254520Y981339D01*
X252999D01*
X252617Y980957D01*
Y980363D01*
X254171Y978809D01*
Y978215D01*
X253654Y977698D01*
X253060D01*
X251506Y979252D01*
X250912D01*
X250465Y978805D01*
Y975877D01*
X252223Y974119D01*
Y973525D01*
X251706Y973008D01*
X251112Y973007D01*
X249354Y974765D01*
X248760D01*
X247695Y973700D01*
Y968997D01*
X241585Y962887D01*
Y957782D01*
X238076Y954273D01*
X233969D01*
G01X300429Y991606D02*
X297754D01*
X297334Y991186D01*
Y990069D01*
X296914Y989649D01*
X296183D01*
X295763Y990069D01*
Y991186D01*
X295343Y991606D01*
X294612D01*
X294192Y991186D01*
Y990069D01*
X293772Y989649D01*
X293041D01*
X292621Y990069D01*
Y991186D01*
X292201Y991606D01*
X290239D01*
X287172Y988539D01*
X249986D01*
X243265Y981818D01*
Y979456D01*
X240495Y976686D01*
Y972139D01*
G01X237048Y968692D02*
X236605Y968249D01*
X234559D01*
X233969Y967659D01*
G01X298669Y996966D02*
X298199Y997436D01*
X297312D01*
X296892Y997016D01*
Y994869D01*
X296472Y994449D01*
X295741D01*
X295321Y994869D01*
Y997016D01*
X294901Y997436D01*
X292277D01*
X291709Y996868D01*
X291710Y996276D01*
X292498Y995488D01*
Y994894D01*
X291981Y994377D01*
X291387Y994376D01*
X290599Y995164D01*
X290005D01*
X286330Y991489D01*
X249144D01*
X240585Y982930D01*
Y980569D01*
X238860Y978844D01*
G01X238747Y978731D02*
X237815Y977799D01*
Y976322D01*
X235845Y974352D01*
X233969D01*
G01X299304Y1000271D02*
X298739Y1000836D01*
X291885D01*
X285218Y994169D01*
X248031D01*
X246538Y992676D01*
X245944D01*
X245305Y993315D01*
X244711D01*
X244194Y992798D01*
Y992204D01*
X244833Y991565D01*
Y990971D01*
X244316Y990454D01*
X243722D01*
X243083Y991093D01*
X242489D01*
X241972Y990576D01*
Y989982D01*
X242611Y989343D01*
Y988749D01*
X237905Y984043D01*
Y981695D01*
X237255Y981045D01*
X233969D01*
G01X300011Y1003374D02*
X299869Y1003516D01*
X297615D01*
X297195Y1003936D01*
Y1005099D01*
X296775Y1005519D01*
X296044D01*
X295624Y1005099D01*
Y1003936D01*
X295204Y1003516D01*
X294473D01*
X294053Y1003936D01*
Y1005099D01*
X293633Y1005519D01*
X292902D01*
X292482Y1005099D01*
Y1003936D01*
X292062Y1003516D01*
X290773D01*
X284106Y996849D01*
X259584D01*
X259164Y997269D01*
Y998779D01*
X258744Y999199D01*
X258013D01*
X257593Y998779D01*
Y997269D01*
X257173Y996849D01*
X256442D01*
X256022Y997269D01*
Y998779D01*
X255602Y999199D01*
X254871D01*
X254451Y998779D01*
Y997269D01*
X254031Y996849D01*
X253300D01*
X252880Y997269D01*
Y998779D01*
X252460Y999199D01*
X251729D01*
X251309Y998779D01*
Y997269D01*
X250889Y996849D01*
X244037D01*
X237914Y990726D01*
Y989551D01*
X236100Y987737D01*
X233969D01*
G01X299529Y1007806D02*
X298283Y1009052D01*
X292517D01*
X282994Y999529D01*
X266744D01*
X261877Y1004396D01*
X259227D01*
X258807Y1003976D01*
Y1002959D01*
X258387Y1002539D01*
X257656D01*
X257236Y1002959D01*
Y1003976D01*
X256816Y1004396D01*
X256085D01*
X255665Y1003976D01*
Y1002959D01*
X255245Y1002539D01*
X254514D01*
X254094Y1002959D01*
Y1003976D01*
X253674Y1004396D01*
X252943D01*
X252523Y1003976D01*
Y1002959D01*
X252103Y1002539D01*
X251372D01*
X250952Y1002959D01*
Y1003976D01*
X250532Y1004396D01*
X247407D01*
X237441Y994430D01*
X233969D01*
G01X301013Y1008772D02*
X298973Y1010812D01*
Y1011549D01*
X298553Y1011969D01*
X297822D01*
X297402Y1011549D01*
Y1010812D01*
X296982Y1010392D01*
X296251D01*
X295831Y1010812D01*
Y1011549D01*
X295411Y1011969D01*
X294680D01*
X294260Y1011549D01*
Y1010812D01*
X293840Y1010392D01*
X291961D01*
X282438Y1000869D01*
X267300D01*
X262433Y1005736D01*
X246713D01*
X242100Y1001123D01*
X233969D01*
G01X299599Y1031667D02*
X285714D01*
X283053Y1034328D01*
X267495D01*
X261062Y1027895D01*
X257315D01*
X256895Y1027475D01*
Y1026589D01*
X256475Y1026169D01*
X255744D01*
X255324Y1026589D01*
Y1027475D01*
X254904Y1027895D01*
X254173D01*
X253753Y1027475D01*
Y1026589D01*
X253333Y1026169D01*
X252602D01*
X252182Y1026589D01*
Y1027475D01*
X251762Y1027895D01*
X251031D01*
X250611Y1027475D01*
Y1026589D01*
X250191Y1026169D01*
X249460D01*
X249040Y1026589D01*
Y1027475D01*
X248620Y1027895D01*
X247889D01*
X247469Y1027475D01*
Y1026589D01*
X247049Y1026169D01*
X246318D01*
X245898Y1026589D01*
Y1027475D01*
X245478Y1027895D01*
X233969D01*
G01X299599Y1034347D02*
X286826D01*
X284165Y1037008D01*
X266345D01*
X260343Y1031006D01*
X242726D01*
X242266Y1031466D01*
Y1032117D01*
X242726Y1032577D01*
X249429D01*
X249889Y1033037D01*
Y1033688D01*
X249429Y1034148D01*
X241155D01*
X240489Y1033482D01*
Y1032087D01*
X239978Y1031576D01*
X238859D01*
X235847Y1034588D01*
X233969D01*
G01X299599Y1037104D02*
X287861D01*
X285277Y1039688D01*
X265233D01*
X263191Y1037646D01*
X243956D01*
X243496Y1038106D01*
Y1038757D01*
X243956Y1039217D01*
X249889D01*
X250349Y1039677D01*
Y1040328D01*
X249889Y1040788D01*
X242385D01*
X241925Y1040328D01*
Y1038106D01*
X241465Y1037646D01*
X239548D01*
X235913Y1041281D01*
X233969D01*
G01X299829Y1039784D02*
X288973D01*
X286389Y1042368D01*
X253846D01*
X251888Y1044326D01*
X243843D01*
X243383Y1044786D01*
Y1045437D01*
X243843Y1045897D01*
X250439D01*
X250899Y1046357D01*
Y1047008D01*
X250439Y1047468D01*
X242272D01*
X241812Y1047008D01*
Y1044786D01*
X241352Y1044326D01*
X239177D01*
X235529Y1047974D01*
X233969D01*
G01X302094Y1050006D02*
X299061D01*
X297008Y1047953D01*
X257724D01*
X250648Y1055029D01*
X248635D01*
X248215Y1055449D01*
Y1056319D01*
X247795Y1056739D01*
X247064D01*
X246644Y1056319D01*
Y1055449D01*
X246224Y1055029D01*
X245414D01*
X243856Y1056587D01*
X243262Y1056588D01*
X242052Y1055378D01*
X241458D01*
X240940Y1055896D01*
X240941Y1056488D01*
X242151Y1057698D01*
Y1058292D01*
X239083Y1061360D01*
X233969D01*
G01X301502Y1045273D02*
X256609D01*
X255136Y1046746D01*
Y1046745D01*
X251733Y1050148D01*
X249034D01*
X248614Y1050568D01*
Y1051929D01*
X248194Y1052349D01*
X247463D01*
X247043Y1051929D01*
Y1050568D01*
X246623Y1050148D01*
X245892D01*
X245472Y1050568D01*
Y1051929D01*
X245052Y1052349D01*
X244321D01*
X243901Y1051929D01*
Y1050568D01*
X243481Y1050148D01*
X242644D01*
X241307Y1051485D01*
X240713D01*
X240083Y1050855D01*
X239489D01*
X238972Y1051372D01*
Y1051966D01*
X239602Y1052596D01*
Y1053190D01*
X238125Y1054667D01*
X233969D01*
G01X301129Y1053236D02*
X300395D01*
X297024Y1049865D01*
X257708D01*
X249074Y1058499D01*
Y1059209D01*
X248654Y1059629D01*
X247923D01*
X247503Y1059209D01*
Y1058499D01*
X247083Y1058079D01*
X245486D01*
X244751Y1058814D01*
X244752Y1059406D01*
X246112Y1060766D01*
Y1061360D01*
X245595Y1061877D01*
X245001Y1061878D01*
X243641Y1060518D01*
X243047D01*
X242529Y1061036D01*
X242530Y1061628D01*
X243890Y1062988D01*
Y1063582D01*
X243373Y1064099D01*
X242779Y1064100D01*
X241419Y1062740D01*
X240825D01*
X238859Y1064706D01*
X233969D01*
G01X298929Y1060096D02*
X297638D01*
X295926Y1058384D01*
Y1057790D01*
X296319Y1057397D01*
Y1056803D01*
X295802Y1056286D01*
X295208D01*
X294815Y1056679D01*
X294221D01*
X293704Y1056162D01*
Y1055568D01*
X294097Y1055175D01*
Y1054581D01*
X293580Y1054064D01*
X292986D01*
X292593Y1054457D01*
X291999D01*
X291201Y1053659D01*
X289621D01*
X289201Y1054079D01*
Y1054719D01*
X288781Y1055139D01*
X288050D01*
X287630Y1054719D01*
Y1054079D01*
X287210Y1053659D01*
X286479D01*
X286059Y1054079D01*
Y1054719D01*
X285639Y1055139D01*
X284908D01*
X284488Y1054719D01*
Y1054079D01*
X284068Y1053659D01*
X283337D01*
X282917Y1054079D01*
Y1054719D01*
X282497Y1055139D01*
X281766D01*
X281346Y1054719D01*
Y1054079D01*
X280926Y1053659D01*
X280195D01*
X279775Y1054079D01*
Y1054719D01*
X279355Y1055139D01*
X278624D01*
X278204Y1054719D01*
Y1054079D01*
X277784Y1053659D01*
X277053D01*
X276633Y1054079D01*
Y1054719D01*
X276213Y1055139D01*
X275482D01*
X275062Y1054719D01*
Y1054079D01*
X274642Y1053659D01*
X273911D01*
X273491Y1054079D01*
Y1054719D01*
X273071Y1055139D01*
X272340D01*
X271920Y1054719D01*
Y1054079D01*
X271500Y1053659D01*
X270769D01*
X270349Y1054079D01*
Y1054719D01*
X269929Y1055139D01*
X269198D01*
X268778Y1054719D01*
Y1054079D01*
X268358Y1053659D01*
X267627D01*
X267207Y1054079D01*
Y1054719D01*
X266787Y1055139D01*
X266056D01*
X265636Y1054719D01*
Y1054079D01*
X265216Y1053659D01*
X264485D01*
X264065Y1054079D01*
Y1054719D01*
X263645Y1055139D01*
X262914D01*
X262494Y1054719D01*
Y1054079D01*
X262074Y1053659D01*
X261343D01*
X260923Y1054079D01*
Y1054719D01*
X260503Y1055139D01*
X259772D01*
X259352Y1054719D01*
Y1054079D01*
X258932Y1053659D01*
X257822D01*
X242815Y1068666D01*
X240436D01*
X237703Y1071399D01*
X233969D01*
G01X298969Y1062776D02*
X296526D01*
X291569Y1057819D01*
X260843D01*
X254364Y1064298D01*
X253770D01*
X253218Y1063746D01*
X252624Y1063747D01*
X252107Y1064264D01*
Y1064858D01*
X252659Y1065410D01*
X252660Y1066002D01*
X252142Y1066520D01*
X251548D01*
X250996Y1065968D01*
X250402Y1065969D01*
X249885Y1066486D01*
Y1067080D01*
X250437Y1067632D01*
X250438Y1068224D01*
X249920Y1068742D01*
X249326D01*
X248774Y1068190D01*
X248180Y1068191D01*
X247663Y1068708D01*
Y1069302D01*
X248215Y1069854D01*
X248216Y1070446D01*
X247698Y1070964D01*
X247104D01*
X246552Y1070412D01*
X245958Y1070413D01*
X245441Y1070930D01*
Y1071524D01*
X245993Y1072076D01*
X245994Y1072668D01*
X245476Y1073186D01*
X244882D01*
X244330Y1072634D01*
X243736Y1072635D01*
X243219Y1073152D01*
Y1073746D01*
X243771Y1074298D01*
X243772Y1074890D01*
X243254Y1075408D01*
X242660D01*
X241644Y1074392D01*
X241050Y1074393D01*
X240533Y1074910D01*
Y1075504D01*
X241549Y1076520D01*
X241550Y1077112D01*
X241032Y1077630D01*
X240438D01*
X239886Y1077078D01*
X239292Y1077079D01*
X238279Y1078092D01*
X233969D01*
G01X299138Y1071846D02*
X293171D01*
X290599Y1069274D01*
X289606D01*
X289186Y1069694D01*
Y1071319D01*
X288766Y1071739D01*
X288035D01*
X287615Y1071319D01*
Y1069694D01*
X287195Y1069274D01*
X286464D01*
X286044Y1069694D01*
Y1071319D01*
X285624Y1071739D01*
X284893D01*
X284473Y1071319D01*
Y1069694D01*
X284053Y1069274D01*
X283322D01*
X282902Y1069694D01*
Y1071319D01*
X282482Y1071739D01*
X281751D01*
X281331Y1071319D01*
Y1069694D01*
X280911Y1069274D01*
X280180D01*
X279760Y1069694D01*
Y1071319D01*
X279340Y1071739D01*
X278609D01*
X278189Y1071319D01*
Y1069694D01*
X277769Y1069274D01*
X277038D01*
X276618Y1069694D01*
Y1071319D01*
X276198Y1071739D01*
X275467D01*
X275047Y1071319D01*
Y1069694D01*
X274627Y1069274D01*
X265931D01*
X240381Y1094824D01*
X233969D01*
G01X299059Y1074526D02*
X264471D01*
X263599Y1075398D01*
X263600Y1075990D01*
X263854Y1076244D01*
Y1076838D01*
X263337Y1077355D01*
X262743Y1077356D01*
X262489Y1077102D01*
X261895D01*
X261377Y1077620D01*
X261378Y1078212D01*
X261632Y1078466D01*
Y1079060D01*
X261115Y1079577D01*
X260521Y1079578D01*
X260267Y1079324D01*
X259673D01*
X259155Y1079842D01*
X259156Y1080434D01*
X259410Y1080688D01*
Y1081282D01*
X258893Y1081799D01*
X258299Y1081800D01*
X258045Y1081546D01*
X257451D01*
X256933Y1082064D01*
X256934Y1082656D01*
X257188Y1082910D01*
Y1083504D01*
X256671Y1084021D01*
X256077Y1084022D01*
X255823Y1083768D01*
X255229D01*
X254711Y1084286D01*
X254712Y1084878D01*
X254966Y1085132D01*
Y1085726D01*
X254449Y1086243D01*
X253855Y1086244D01*
X253601Y1085990D01*
X253007D01*
X252489Y1086508D01*
X252490Y1087100D01*
X252744Y1087354D01*
Y1087948D01*
X252227Y1088465D01*
X251633Y1088466D01*
X251379Y1088212D01*
X250785D01*
X250267Y1088730D01*
X250268Y1089322D01*
X250522Y1089576D01*
Y1090170D01*
X250005Y1090687D01*
X249411Y1090688D01*
X249157Y1090434D01*
X248563D01*
X248045Y1090952D01*
X248046Y1091544D01*
X248300Y1091798D01*
Y1092392D01*
X247783Y1092909D01*
X247189Y1092910D01*
X246935Y1092656D01*
X246341D01*
X245823Y1093174D01*
X245824Y1093766D01*
X246078Y1094020D01*
Y1094614D01*
X245561Y1095131D01*
X244967Y1095132D01*
X244713Y1094878D01*
X244119D01*
X243601Y1095396D01*
X243602Y1095988D01*
X243856Y1096242D01*
Y1096836D01*
X243339Y1097353D01*
X242745Y1097354D01*
X242491Y1097100D01*
X241897D01*
X241379Y1097618D01*
X241380Y1098210D01*
X241634Y1098464D01*
Y1099058D01*
X241117Y1099575D01*
X240523Y1099576D01*
X240269Y1099322D01*
X239675D01*
X237480Y1101517D01*
X233969D01*
G01X299789Y1078066D02*
X267069D01*
X266309Y1078826D01*
Y1079420D01*
X266870Y1079981D01*
Y1080575D01*
X266353Y1081092D01*
X265759D01*
X265198Y1080531D01*
X264604D01*
X264087Y1081048D01*
Y1081642D01*
X264648Y1082203D01*
Y1082797D01*
X264131Y1083314D01*
X263537D01*
X262976Y1082753D01*
X262382D01*
X261865Y1083270D01*
Y1083864D01*
X262426Y1084425D01*
Y1085019D01*
X261909Y1085536D01*
X261315D01*
X260754Y1084975D01*
X260160D01*
X259643Y1085492D01*
Y1086086D01*
X260204Y1086647D01*
Y1087241D01*
X259687Y1087758D01*
X259093D01*
X258532Y1087197D01*
X257938D01*
X257421Y1087714D01*
Y1088308D01*
X257982Y1088869D01*
Y1089463D01*
X257465Y1089980D01*
X256871D01*
X256310Y1089419D01*
X255716D01*
X255199Y1089936D01*
Y1090530D01*
X255760Y1091091D01*
Y1091685D01*
X255243Y1092202D01*
X254649D01*
X254088Y1091641D01*
X253494D01*
X252977Y1092158D01*
Y1092752D01*
X253538Y1093313D01*
Y1093907D01*
X253021Y1094424D01*
X252427D01*
X251866Y1093863D01*
X251272D01*
X250755Y1094380D01*
Y1094974D01*
X251316Y1095535D01*
Y1096129D01*
X250799Y1096646D01*
X250205D01*
X249644Y1096085D01*
X249050D01*
X248533Y1096602D01*
Y1097196D01*
X249094Y1097757D01*
Y1098351D01*
X248577Y1098868D01*
X247983D01*
X247422Y1098307D01*
X246828D01*
X246311Y1098824D01*
Y1099418D01*
X246872Y1099979D01*
Y1100573D01*
X246355Y1101090D01*
X245761D01*
X245200Y1100529D01*
X244606D01*
X244089Y1101046D01*
Y1101640D01*
X244650Y1102201D01*
Y1102795D01*
X244133Y1103312D01*
X243539D01*
X242978Y1102751D01*
X242384D01*
X241867Y1103268D01*
Y1103862D01*
X242428Y1104423D01*
Y1105017D01*
X241911Y1105534D01*
X241317D01*
X240920Y1105137D01*
X238890D01*
X238470Y1105557D01*
Y1107750D01*
X238010Y1108210D01*
X233969D01*
G01X299059Y1080906D02*
X270331D01*
X269532Y1081705D01*
Y1082299D01*
X269821Y1082588D01*
Y1083182D01*
X269304Y1083699D01*
X268710D01*
X268421Y1083410D01*
X267827D01*
X267310Y1083927D01*
Y1084521D01*
X267599Y1084810D01*
Y1085404D01*
X267082Y1085921D01*
X266488D01*
X266199Y1085632D01*
X265605D01*
X265088Y1086149D01*
Y1086743D01*
X265377Y1087032D01*
Y1087626D01*
X264860Y1088143D01*
X264266D01*
X263977Y1087854D01*
X263383D01*
X262866Y1088371D01*
Y1088965D01*
X263155Y1089254D01*
Y1089848D01*
X262638Y1090365D01*
X262044D01*
X261755Y1090076D01*
X261161D01*
X260644Y1090593D01*
Y1091187D01*
X260933Y1091476D01*
Y1092070D01*
X260416Y1092587D01*
X259822D01*
X259533Y1092298D01*
X258939D01*
X258422Y1092815D01*
Y1093409D01*
X258711Y1093698D01*
Y1094292D01*
X258194Y1094809D01*
X257600D01*
X257311Y1094520D01*
X256717D01*
X256200Y1095037D01*
Y1095631D01*
X256489Y1095920D01*
Y1096514D01*
X255972Y1097031D01*
X255378D01*
X255089Y1096742D01*
X254495D01*
X253978Y1097259D01*
Y1097853D01*
X254267Y1098142D01*
Y1098736D01*
X253750Y1099253D01*
X253156D01*
X252867Y1098964D01*
X252273D01*
X251756Y1099481D01*
Y1100075D01*
X252045Y1100364D01*
Y1100958D01*
X251528Y1101475D01*
X250934D01*
X250645Y1101186D01*
X250051D01*
X249534Y1101703D01*
Y1102297D01*
X249823Y1102586D01*
Y1103180D01*
X249306Y1103697D01*
X248712D01*
X248423Y1103408D01*
X247829D01*
X247312Y1103925D01*
Y1104519D01*
X247601Y1104808D01*
Y1105402D01*
X247084Y1105919D01*
X246490D01*
X246201Y1105630D01*
X245607D01*
X245090Y1106147D01*
Y1106741D01*
X245379Y1107030D01*
Y1107624D01*
X244862Y1108141D01*
X244268D01*
X243979Y1107852D01*
X243385D01*
X242868Y1108369D01*
Y1108963D01*
X243157Y1109252D01*
Y1109846D01*
X242640Y1110363D01*
X242046D01*
X241757Y1110074D01*
X241163D01*
X239971Y1111266D01*
X238429D01*
X237969Y1111726D01*
Y1114443D01*
X237509Y1114903D01*
X233969D01*
G01X301191Y1090755D02*
X277938D01*
X277329Y1091364D01*
X277328Y1091958D01*
X277594Y1092224D01*
Y1092818D01*
X277076Y1093336D01*
X276484Y1093335D01*
X276218Y1093069D01*
X275624D01*
X275107Y1093586D01*
X275106Y1094180D01*
X275372Y1094446D01*
Y1095040D01*
X274854Y1095558D01*
X274262Y1095557D01*
X273996Y1095291D01*
X273402D01*
X272885Y1095808D01*
X272884Y1096402D01*
X273150Y1096668D01*
Y1097262D01*
X272632Y1097780D01*
X272040Y1097779D01*
X271774Y1097513D01*
X271180D01*
X270663Y1098030D01*
X270662Y1098624D01*
X270928Y1098890D01*
Y1099484D01*
X270410Y1100002D01*
X269818Y1100001D01*
X269552Y1099735D01*
X268958D01*
X268441Y1100252D01*
X268440Y1100846D01*
X268706Y1101112D01*
Y1101706D01*
X268188Y1102224D01*
X267596Y1102223D01*
X267330Y1101957D01*
X266736D01*
X266219Y1102474D01*
X266218Y1103068D01*
X266484Y1103334D01*
Y1103928D01*
X265966Y1104446D01*
X265374Y1104445D01*
X265108Y1104179D01*
X264514D01*
X263997Y1104696D01*
X263996Y1105290D01*
X264262Y1105556D01*
Y1106150D01*
X263744Y1106668D01*
X263152Y1106667D01*
X262886Y1106401D01*
X262292D01*
X261775Y1106918D01*
X261774Y1107512D01*
X262040Y1107778D01*
Y1108372D01*
X261522Y1108890D01*
X260930Y1108889D01*
X260664Y1108623D01*
X260070D01*
X259553Y1109140D01*
X259552Y1109734D01*
X259818Y1110000D01*
Y1110594D01*
X259300Y1111112D01*
X258708Y1111111D01*
X258442Y1110845D01*
X257848D01*
X257331Y1111362D01*
X257330Y1111956D01*
X257596Y1112222D01*
Y1112816D01*
X257078Y1113334D01*
X256486Y1113333D01*
X256220Y1113067D01*
X255626D01*
X255109Y1113584D01*
X255108Y1114178D01*
X255374Y1114444D01*
Y1115038D01*
X254856Y1115556D01*
X254264Y1115555D01*
X253998Y1115289D01*
X253404D01*
X252887Y1115806D01*
X252886Y1116400D01*
X253152Y1116666D01*
Y1117260D01*
X252634Y1117778D01*
X252042Y1117777D01*
X251776Y1117511D01*
X251182D01*
X250665Y1118028D01*
X250664Y1118622D01*
X250930Y1118888D01*
Y1119482D01*
X250412Y1120000D01*
X249820Y1119999D01*
X249554Y1119733D01*
X248960D01*
X248443Y1120250D01*
X248442Y1120844D01*
X248708Y1121110D01*
Y1121704D01*
X248190Y1122222D01*
X247598Y1122221D01*
X247332Y1121955D01*
X246738D01*
X245638Y1123055D01*
Y1125731D01*
X239734Y1131635D01*
X233969D01*
G01X299217Y1093524D02*
X298246D01*
X297826Y1093944D01*
Y1094289D01*
X297406Y1094709D01*
X296675D01*
X296255Y1094289D01*
Y1093944D01*
X295835Y1093524D01*
X295104D01*
X294684Y1093944D01*
Y1094289D01*
X294264Y1094709D01*
X293533D01*
X293113Y1094289D01*
Y1093944D01*
X292693Y1093524D01*
X291962D01*
X291542Y1093944D01*
Y1094289D01*
X291122Y1094709D01*
X290391D01*
X289971Y1094289D01*
Y1093944D01*
X289551Y1093524D01*
X288820D01*
X288400Y1093944D01*
Y1094289D01*
X287980Y1094709D01*
X287249D01*
X286829Y1094289D01*
Y1093944D01*
X286409Y1093524D01*
X285678D01*
X285258Y1093944D01*
Y1094289D01*
X284838Y1094709D01*
X284107D01*
X283687Y1094289D01*
Y1093944D01*
X283267Y1093524D01*
X280681D01*
X280187Y1094018D01*
Y1094886D01*
X279510Y1095563D01*
X278642D01*
X277965Y1096240D01*
Y1097108D01*
X277288Y1097785D01*
X276420D01*
X275743Y1098462D01*
Y1099330D01*
X275066Y1100007D01*
X274198D01*
X273521Y1100684D01*
Y1101552D01*
X272844Y1102229D01*
X271976D01*
X271299Y1102906D01*
Y1103774D01*
X270622Y1104451D01*
X269754D01*
X269077Y1105128D01*
Y1105996D01*
X268400Y1106673D01*
X267532D01*
X266855Y1107350D01*
Y1108218D01*
X266178Y1108895D01*
X265310D01*
X264633Y1109572D01*
Y1110440D01*
X263956Y1111117D01*
X263088D01*
X262411Y1111794D01*
Y1112662D01*
X261734Y1113339D01*
X260866D01*
X260189Y1114016D01*
Y1114884D01*
X259512Y1115561D01*
X258644D01*
X257967Y1116238D01*
Y1117106D01*
X257290Y1117783D01*
X256422D01*
X255745Y1118460D01*
Y1119328D01*
X255068Y1120005D01*
X254200D01*
X253523Y1120682D01*
Y1121550D01*
X252846Y1122227D01*
X251978D01*
X251301Y1122904D01*
Y1123772D01*
X250624Y1124449D01*
X249756D01*
X248318Y1125887D01*
Y1126844D01*
X239974Y1135188D01*
X238680D01*
X238220Y1135648D01*
Y1137868D01*
X237760Y1138328D01*
X233969D01*
G01X298970Y1097882D02*
X282727D01*
X248143Y1132466D01*
X248145Y1133509D01*
X247627Y1134027D01*
X246582D01*
X245993Y1134616D01*
Y1135210D01*
X248267Y1137484D01*
X248268Y1138076D01*
X247750Y1138594D01*
X247156D01*
X244882Y1136320D01*
X244288Y1136321D01*
X243771Y1136838D01*
Y1137432D01*
X246719Y1140380D01*
X246720Y1140972D01*
X246202Y1141490D01*
X245608D01*
X242660Y1138542D01*
X242066Y1138543D01*
X241549Y1139060D01*
Y1139654D01*
X244497Y1142602D01*
X244498Y1143194D01*
X243980Y1143712D01*
X243386D01*
X240438Y1140764D01*
X239844Y1140765D01*
X239210Y1141399D01*
Y1141994D01*
X241845Y1144629D01*
Y1145279D01*
X241195Y1145929D01*
X239895D01*
X238987Y1145021D01*
X233969D01*
G01X299059Y1100651D02*
X283750D01*
X250948Y1133453D01*
Y1141379D01*
X251800Y1142231D01*
Y1144129D01*
X246053Y1149876D01*
X245458D01*
X244942Y1149360D01*
Y1148765D01*
X250230Y1143477D01*
Y1142883D01*
X249713Y1142366D01*
X249119D01*
X242640Y1148845D01*
X238890D01*
X236021Y1151714D01*
X233969D01*
G01X299092Y1109595D02*
X289396D01*
X261615Y1137376D01*
Y1148914D01*
X260934Y1149595D01*
Y1150189D01*
X261592Y1150847D01*
Y1151441D01*
X261075Y1151958D01*
X260481D01*
X259823Y1151300D01*
X259229D01*
X258712Y1151817D01*
Y1152411D01*
X259370Y1153069D01*
Y1153663D01*
X258853Y1154180D01*
X258259D01*
X257601Y1153522D01*
X257007D01*
X256490Y1154039D01*
Y1154633D01*
X257148Y1155291D01*
Y1155885D01*
X256631Y1156402D01*
X256037D01*
X255379Y1155744D01*
X254785D01*
X254268Y1156261D01*
Y1156855D01*
X254926Y1157513D01*
Y1158107D01*
X254409Y1158624D01*
X253815D01*
X253157Y1157966D01*
X252563D01*
X252046Y1158483D01*
Y1159077D01*
X252704Y1159735D01*
Y1160329D01*
X252187Y1160846D01*
X251593D01*
X250935Y1160188D01*
X250341D01*
X249824Y1160705D01*
Y1161299D01*
X250482Y1161957D01*
Y1162551D01*
X249965Y1163068D01*
X249371D01*
X248713Y1162410D01*
X248119D01*
X247602Y1162927D01*
Y1163521D01*
X248260Y1164179D01*
Y1164773D01*
X247743Y1165290D01*
X247149D01*
X246491Y1164632D01*
X245897D01*
X245380Y1165149D01*
Y1165743D01*
X246038Y1166401D01*
Y1166995D01*
X245521Y1167512D01*
X244927D01*
X244269Y1166854D01*
X243675D01*
X243122Y1167407D01*
X239048D01*
X238009Y1168446D01*
X233969D01*
G01X299059Y1114196D02*
X297935D01*
X297515Y1113776D01*
Y1112739D01*
X297095Y1112319D01*
X296364D01*
X295944Y1112739D01*
Y1113776D01*
X295524Y1114196D01*
X294793D01*
X294373Y1113776D01*
Y1112739D01*
X293953Y1112319D01*
X293222D01*
X292802Y1112739D01*
Y1113776D01*
X292382Y1114196D01*
X291651D01*
X291231Y1113776D01*
Y1113123D01*
X290811Y1112703D01*
X290080D01*
X289660Y1113123D01*
Y1113776D01*
X289240Y1114196D01*
X288587D01*
X264322Y1138461D01*
Y1152537D01*
X246159Y1170700D01*
X243396D01*
X242976Y1171120D01*
Y1172749D01*
X242556Y1173169D01*
X241825D01*
X241405Y1172749D01*
Y1171120D01*
X240985Y1170700D01*
X240276D01*
X238519Y1172457D01*
Y1174679D01*
X238059Y1175139D01*
X233969D01*
G01X300154Y1117371D02*
X289854D01*
X267493Y1139732D01*
Y1153809D01*
X266370Y1154932D01*
Y1155526D01*
X267077Y1156233D01*
Y1156827D01*
X266560Y1157344D01*
X265966D01*
X265259Y1156637D01*
X264665D01*
X264148Y1157154D01*
Y1157748D01*
X264855Y1158455D01*
Y1159049D01*
X264338Y1159566D01*
X263744D01*
X263037Y1158859D01*
X262443D01*
X261926Y1159376D01*
Y1159970D01*
X262633Y1160677D01*
Y1161271D01*
X262116Y1161788D01*
X261522D01*
X260815Y1161081D01*
X260221D01*
X259704Y1161598D01*
Y1162192D01*
X260411Y1162899D01*
Y1163493D01*
X259894Y1164010D01*
X259300D01*
X258593Y1163303D01*
X257999D01*
X257482Y1163820D01*
Y1164414D01*
X258189Y1165121D01*
Y1165715D01*
X257672Y1166232D01*
X257078D01*
X256371Y1165525D01*
X255777D01*
X255260Y1166042D01*
Y1166636D01*
X255967Y1167343D01*
Y1167937D01*
X255450Y1168454D01*
X254856D01*
X254149Y1167747D01*
X253555D01*
X253038Y1168264D01*
Y1168858D01*
X253745Y1169565D01*
Y1170159D01*
X253228Y1170676D01*
X252634D01*
X251927Y1169969D01*
X251333D01*
X250816Y1170486D01*
Y1171080D01*
X251523Y1171787D01*
Y1172381D01*
X251006Y1172898D01*
X250412D01*
X249705Y1172191D01*
X249111D01*
X248594Y1172708D01*
Y1173302D01*
X249301Y1174009D01*
Y1174603D01*
X248784Y1175120D01*
X248190D01*
X247483Y1174413D01*
X246889D01*
X246372Y1174930D01*
Y1175524D01*
X247079Y1176231D01*
Y1176825D01*
X246562Y1177342D01*
X245968D01*
X245261Y1176635D01*
X244667D01*
X244150Y1177152D01*
Y1177746D01*
X244857Y1178453D01*
Y1179047D01*
X244340Y1179564D01*
X243746D01*
X243039Y1178857D01*
X242445D01*
X241928Y1179374D01*
Y1179968D01*
X242635Y1180675D01*
Y1181269D01*
X242118Y1181786D01*
X241524D01*
X240817Y1181079D01*
X240223D01*
X239470Y1181832D01*
X233969D01*
G01X299059Y1120051D02*
X290966D01*
X270173Y1140844D01*
Y1157524D01*
X269367Y1158330D01*
X269368Y1158922D01*
X269772Y1159326D01*
Y1159920D01*
X269255Y1160437D01*
X268661Y1160438D01*
X268257Y1160034D01*
X267663D01*
X267145Y1160552D01*
X267146Y1161144D01*
X267550Y1161548D01*
Y1162142D01*
X267033Y1162659D01*
X266439Y1162660D01*
X266035Y1162256D01*
X265441D01*
X264923Y1162774D01*
X264924Y1163366D01*
X265328Y1163770D01*
Y1164364D01*
X264811Y1164881D01*
X264217Y1164882D01*
X263813Y1164478D01*
X263219D01*
X262701Y1164996D01*
X262702Y1165588D01*
X263106Y1165992D01*
Y1166586D01*
X262589Y1167103D01*
X261995Y1167104D01*
X261591Y1166700D01*
X260997D01*
X260479Y1167218D01*
X260480Y1167810D01*
X260884Y1168214D01*
Y1168808D01*
X260367Y1169325D01*
X259773Y1169326D01*
X259369Y1168922D01*
X258775D01*
X258257Y1169440D01*
X258258Y1170032D01*
X258662Y1170436D01*
Y1171030D01*
X258145Y1171547D01*
X257551Y1171548D01*
X257147Y1171144D01*
X256553D01*
X256035Y1171662D01*
X256036Y1172254D01*
X256440Y1172658D01*
Y1173252D01*
X255923Y1173769D01*
X255329Y1173770D01*
X254925Y1173366D01*
X254331D01*
X253813Y1173884D01*
X253814Y1174476D01*
X254218Y1174880D01*
Y1175474D01*
X253701Y1175991D01*
X253107Y1175992D01*
X252703Y1175588D01*
X252109D01*
X251591Y1176106D01*
X251592Y1176698D01*
X251996Y1177102D01*
Y1177696D01*
X251479Y1178213D01*
X250885Y1178214D01*
X250481Y1177810D01*
X249887D01*
X249369Y1178328D01*
X249370Y1178920D01*
X249774Y1179324D01*
Y1179918D01*
X249257Y1180435D01*
X248663Y1180436D01*
X248259Y1180032D01*
X247665D01*
X247147Y1180550D01*
X247148Y1181142D01*
X247552Y1181546D01*
Y1182140D01*
X247035Y1182657D01*
X246441Y1182658D01*
X246037Y1182254D01*
X245443D01*
X244925Y1182772D01*
X244926Y1183364D01*
X245330Y1183768D01*
Y1184362D01*
X244813Y1184879D01*
X244219Y1184880D01*
X243815Y1184476D01*
X243220D01*
X242851Y1184845D01*
X239809D01*
X239225Y1185429D01*
Y1187280D01*
X237980Y1188525D01*
X233969D01*
G01X299599Y1129066D02*
X294625D01*
X279048Y1144643D01*
Y1167138D01*
X277576Y1168610D01*
Y1169204D01*
X277861Y1169489D01*
Y1170083D01*
X277344Y1170600D01*
X276750D01*
X276465Y1170315D01*
X275871D01*
X275354Y1170832D01*
Y1171426D01*
X275639Y1171711D01*
Y1172305D01*
X275122Y1172822D01*
X274528D01*
X274243Y1172537D01*
X273649D01*
X273132Y1173054D01*
Y1173648D01*
X273417Y1173933D01*
Y1174527D01*
X272900Y1175044D01*
X272306D01*
X272021Y1174759D01*
X271427D01*
X270910Y1175276D01*
Y1175870D01*
X271195Y1176155D01*
Y1176749D01*
X270678Y1177266D01*
X270084D01*
X269799Y1176981D01*
X269205D01*
X268688Y1177498D01*
Y1178092D01*
X268973Y1178377D01*
Y1178971D01*
X268456Y1179488D01*
X267862D01*
X267577Y1179203D01*
X266983D01*
X266466Y1179720D01*
Y1180314D01*
X266751Y1180599D01*
Y1181193D01*
X266234Y1181710D01*
X265640D01*
X265355Y1181425D01*
X264761D01*
X264244Y1181942D01*
Y1182536D01*
X264529Y1182821D01*
Y1183415D01*
X264012Y1183932D01*
X263418D01*
X263133Y1183647D01*
X262539D01*
X262022Y1184164D01*
Y1184758D01*
X262307Y1185043D01*
Y1185637D01*
X261790Y1186154D01*
X261196D01*
X260911Y1185869D01*
X260317D01*
X259800Y1186386D01*
Y1186980D01*
X260085Y1187265D01*
Y1187859D01*
X259568Y1188376D01*
X258974D01*
X258689Y1188091D01*
X258095D01*
X257578Y1188608D01*
Y1189202D01*
X257863Y1189487D01*
Y1190081D01*
X257346Y1190598D01*
X256752D01*
X256467Y1190313D01*
X255873D01*
X255356Y1190830D01*
Y1191424D01*
X255641Y1191709D01*
Y1192303D01*
X255124Y1192820D01*
X254530D01*
X254245Y1192535D01*
X253651D01*
X253134Y1193052D01*
Y1193646D01*
X253419Y1193931D01*
Y1194525D01*
X252902Y1195042D01*
X252308D01*
X252023Y1194757D01*
X251429D01*
X250912Y1195274D01*
Y1195868D01*
X251197Y1196153D01*
Y1196747D01*
X250680Y1197264D01*
X250086D01*
X249801Y1196979D01*
X249207D01*
X248690Y1197496D01*
Y1198090D01*
X248975Y1198375D01*
Y1198969D01*
X248458Y1199486D01*
X247864D01*
X247579Y1199201D01*
X246985D01*
X246468Y1199718D01*
Y1200312D01*
X246753Y1200597D01*
Y1201191D01*
X246236Y1201708D01*
X245642D01*
X245357Y1201423D01*
X244763D01*
X240929Y1205257D01*
X233969D01*
G01X299059Y1132267D02*
X295216D01*
X281728Y1145755D01*
Y1170009D01*
X280862Y1170875D01*
Y1172061D01*
X280344Y1172579D01*
X279158D01*
X278640Y1173097D01*
Y1174283D01*
X278122Y1174801D01*
X276936D01*
X276418Y1175319D01*
Y1176505D01*
X275900Y1177023D01*
X274714D01*
X274196Y1177541D01*
Y1178727D01*
X273678Y1179245D01*
X272492D01*
X271974Y1179763D01*
Y1180949D01*
X271456Y1181467D01*
X270270D01*
X269752Y1181985D01*
Y1183171D01*
X269234Y1183689D01*
X268048D01*
X267530Y1184207D01*
Y1185393D01*
X267012Y1185911D01*
X265826D01*
X265308Y1186429D01*
Y1187615D01*
X264790Y1188133D01*
X263604D01*
X263086Y1188651D01*
Y1189837D01*
X262568Y1190355D01*
X261382D01*
X260864Y1190873D01*
Y1192059D01*
X260346Y1192577D01*
X259160D01*
X258642Y1193095D01*
Y1194281D01*
X258124Y1194799D01*
X256938D01*
X256420Y1195317D01*
Y1196503D01*
X255902Y1197021D01*
X254716D01*
X254198Y1197539D01*
Y1198725D01*
X253680Y1199243D01*
X252494D01*
X251976Y1199761D01*
Y1200947D01*
X251458Y1201465D01*
X250272D01*
X249754Y1201983D01*
Y1203169D01*
X249236Y1203687D01*
X248050D01*
X247532Y1204205D01*
Y1205391D01*
X247014Y1205909D01*
X245828D01*
X245310Y1206427D01*
Y1207613D01*
X244792Y1208131D01*
X243606D01*
X241848Y1209889D01*
X241254D01*
X240801Y1209436D01*
X240207Y1209437D01*
X239690Y1209954D01*
Y1210548D01*
X240143Y1211001D01*
X240144Y1211593D01*
X239787Y1211950D01*
X233969D01*
G01X299159Y1135566D02*
X296359D01*
X284868Y1147057D01*
Y1173697D01*
X243885Y1214680D01*
Y1215330D01*
X244346Y1215791D01*
X244996D01*
X253055Y1207732D01*
X253705D01*
X254166Y1208193D01*
Y1208843D01*
X244996Y1218013D01*
X244346D01*
X242774Y1216441D01*
X242124D01*
X239922Y1218643D01*
X233969D01*
G01X299059Y1138766D02*
X297359D01*
X287548Y1148577D01*
Y1174809D01*
X259085Y1203272D01*
Y1203922D01*
X259546Y1204383D01*
X260196D01*
X265071Y1199508D01*
X265721D01*
X266182Y1199969D01*
Y1200619D01*
X260196Y1206605D01*
X259546D01*
X257974Y1205033D01*
X257324D01*
X256846Y1205511D01*
Y1209955D01*
X241465Y1225336D01*
X233969D01*
G01X299312Y1151031D02*
X297729Y1152614D01*
Y1183618D01*
X244203Y1237144D01*
Y1237738D01*
X244720Y1238255D01*
X245314D01*
X250702Y1232867D01*
X251352D01*
X251813Y1233328D01*
Y1233978D01*
X244726Y1241065D01*
X244076D01*
X242900Y1239889D01*
X242306D01*
X240127Y1242068D01*
X233969D01*
G01X300409Y1153876D02*
Y1184730D01*
X260799Y1224340D01*
Y1224990D01*
X261260Y1225451D01*
X261910D01*
X265337Y1222024D01*
X265987D01*
X266448Y1222485D01*
Y1223135D01*
X261910Y1227673D01*
X261260D01*
X259688Y1226101D01*
X259038D01*
X257923Y1227216D01*
Y1231660D01*
X240822Y1248761D01*
X233969D01*
G01X249909Y58971D02*
Y60644D01*
X248266Y62287D01*
G01Y65437D02*
Y68469D01*
X248487Y68690D01*
G01X257722Y87543D02*
X253264D01*
X253086Y87365D01*
G01X256978Y111771D02*
X253877D01*
X253874Y111774D01*
G01X250372Y111743D02*
X253843D01*
X253874Y111774D01*
G01X256978Y107835D02*
X251487D01*
G01D02*
X247487D01*
G01X249695Y146879D02*
X254933D01*
X254936Y146882D01*
G01X259736Y144882D02*
Y140882D01*
G01X254936Y146882D02*
X257736D01*
X259736Y144882D01*
G01X267028Y137302D02*
X263316D01*
X259736Y140882D01*
G01X249695Y149438D02*
X252319D01*
X254821Y151940D01*
G01X256586Y140882D02*
Y138373D01*
G01X260100Y157037D02*
Y157800D01*
X261700Y159400D01*
Y160300D01*
X262500Y161100D01*
G01X260100Y153887D02*
X256768D01*
X254821Y151940D01*
G01X249735Y160162D02*
X248220D01*
X247654Y159596D01*
Y158093D01*
X248144Y157603D01*
X249735D01*
G01X259496Y162665D02*
X258629Y163532D01*
X250639D01*
X249735Y162628D01*
Y160162D01*
G01X254756Y159877D02*
X255979Y161100D01*
X257931D01*
X259496Y162665D01*
G01X266978Y147203D02*
X264871Y149310D01*
X262351D01*
X260596Y151065D01*
G01X260135Y207660D02*
X259015Y206540D01*
X256090D01*
G01D02*
X253500D01*
X252389Y207651D01*
X250156D01*
G01X314602Y271016D02*
X314534Y270948D01*
X314474D01*
X314451Y270925D01*
X313606D01*
X294871Y252190D01*
X281780D01*
X265437Y235847D01*
X258097D01*
X247465Y225215D01*
Y224370D01*
G01X250615D02*
X259865Y233620D01*
X266360D01*
X282226Y249486D01*
X288949D01*
G01X323496Y880671D02*
Y870830D01*
X344979Y849347D01*
Y827487D01*
X330444Y812952D01*
X329949Y812747D01*
X295756D01*
X288050Y805041D01*
X283283Y803067D01*
X278273Y798057D01*
Y795904D01*
X273274Y790905D01*
X269178D01*
X254671Y776398D01*
Y776388D01*
G01X325346Y877482D02*
Y870564D01*
X346099Y849811D01*
Y827023D01*
X330703Y811627D01*
X330421Y811510D01*
X296103D01*
X288367Y803774D01*
X283599Y801799D01*
X279393Y797593D01*
Y795440D01*
X273738Y789785D01*
X269642D01*
X256660Y776803D01*
Y773181D01*
X257071Y772770D01*
G01X259490Y1565110D02*
X266027D01*
X271580Y1559557D01*
Y1554350D01*
G01X254470Y1555340D02*
X257790Y1558660D01*
X258560D01*
G01X261530Y1555320D02*
X260875Y1555975D01*
Y1556705D01*
X258920Y1558660D01*
X258560D01*
G01X276622Y32756D02*
Y30071D01*
X275116Y28565D01*
G01X266000Y125800D02*
Y125401D01*
X266427Y124974D01*
Y115315D01*
G01X264293Y120972D02*
X264459Y120806D01*
Y115315D01*
G01X268395D02*
Y120003D01*
X269487Y121095D01*
G01X274301Y115216D02*
Y118756D01*
X275793Y120248D01*
G01X268297Y127468D02*
X267668D01*
X266000Y125800D01*
G01X261297Y123968D02*
X264293Y120972D01*
G01X269487Y121095D02*
X271797Y123405D01*
Y123968D01*
G01X270178Y137302D02*
X272698D01*
X279783Y130217D01*
Y127143D01*
G01X270125Y142892D02*
Y147200D01*
X270128Y147203D01*
G01X280741Y153819D02*
X279066D01*
X275049Y149802D01*
Y148706D01*
G01X270128Y147203D02*
X273546D01*
X275049Y148706D01*
G01X270178Y140322D02*
Y137302D01*
G01X270128Y155203D02*
Y151203D01*
G01X280741Y155787D02*
X278802D01*
X276880Y153865D01*
X274996D01*
G01X270128Y155203D02*
X271242D01*
X272580Y153865D01*
X274996D01*
G01X280741Y157756D02*
X276446D01*
X274996Y159206D01*
G01X270128Y159203D02*
X274993D01*
X274996Y159206D01*
G01X266978Y151203D02*
X264577D01*
X264574Y151206D01*
G01X261925Y217500D02*
Y212556D01*
X269689Y204792D01*
X287384D01*
X292811Y210219D01*
Y213242D01*
G01X266360Y203070D02*
Y204585D01*
X263285Y207660D01*
G01X265075Y221500D02*
X266575Y223000D01*
X271500D01*
G01X265075Y221500D02*
Y217500D01*
G01D02*
Y213077D01*
G01D02*
Y212174D01*
X266249Y211000D01*
X269925D01*
G01X271500Y225559D02*
X274000D01*
X275000Y224559D01*
Y219500D01*
X273075Y217575D01*
Y215000D01*
G01D02*
X276925D01*
G01X273075Y211000D02*
X276925D01*
G01X269925Y215000D02*
Y217700D01*
G01X271500Y225559D02*
X267209D01*
X264818Y227950D01*
G01X327196Y874293D02*
Y870298D01*
X347219Y850275D01*
Y826559D01*
X331050Y810390D01*
X296567D01*
X289000Y802823D01*
X284233Y800849D01*
X280513Y797129D01*
Y794976D01*
X274156Y788619D01*
X271802D01*
X263271Y780088D01*
Y771988D01*
G01X347551Y877482D02*
Y872764D01*
X356855Y863460D01*
X358219D01*
X360425Y861254D01*
Y858445D01*
X360930Y857940D01*
Y829910D01*
X360280Y829260D01*
X360274D01*
X333667Y802653D01*
X299456D01*
X277391Y780588D01*
X271161D01*
G01X268991Y783248D02*
X278465D01*
X278468Y783249D01*
X298992Y803773D01*
X333203D01*
X359810Y830380D01*
Y857470D01*
X359305Y857975D01*
Y860790D01*
X357894Y862201D01*
X356530D01*
X345571Y873160D01*
Y875761D01*
X343850Y877482D01*
G01X336448D02*
Y868460D01*
X352299Y852609D01*
Y824453D01*
X332739Y804893D01*
X298527D01*
X278565Y784931D01*
X271788D01*
X271245Y785474D01*
G01X274282Y786741D02*
X278096D01*
X297668Y806313D01*
X332150D01*
X350879Y825042D01*
Y852020D01*
X332748Y870151D01*
Y877482D01*
G01X278350Y1503100D02*
X278010D01*
X272451Y1508659D01*
X269325D01*
X266283Y1505617D01*
X262768D01*
X261095Y1507290D01*
Y1509459D01*
G01X265173Y1515083D02*
X266828Y1514073D01*
G01X265173Y1517445D02*
X266772Y1516336D01*
G01X262276Y1511505D02*
X263099Y1512328D01*
X263577D01*
X264178Y1512929D01*
X265295D01*
X268102Y1510122D01*
X272923D01*
X276445Y1506600D01*
X278350D01*
G01X276704Y1526953D02*
X275386Y1525635D01*
X269884D01*
X266634Y1522385D01*
Y1521268D01*
X265173Y1519807D01*
G01Y1522169D02*
X269624Y1526620D01*
X272880D01*
X275119Y1528859D01*
X276094Y1529263D01*
X279394D01*
X281704Y1526953D01*
G01X265173Y1536343D02*
X266826D01*
X267123Y1536640D01*
G01X265173Y1533980D02*
X265733Y1534540D01*
X267123D01*
G01X265173Y1531618D02*
X267124D01*
G01X265173Y1529256D02*
X265731Y1528698D01*
X267035D01*
G01X273350Y1538370D02*
X272344D01*
X270590Y1536616D01*
Y1535577D01*
X268093Y1533080D01*
X266290D01*
X266009Y1532799D01*
X263128D01*
G01Y1530437D02*
X265981D01*
X266260Y1530158D01*
X268141D01*
X268878Y1530895D01*
Y1532140D01*
X272008Y1535270D01*
X273350D01*
G01D02*
Y1533725D01*
X273981Y1533094D01*
X288460D01*
X289161Y1533795D01*
X293163D01*
X294107Y1532851D01*
G01X265819Y1540477D02*
X270973Y1545631D01*
X272292Y1548815D01*
Y1549635D01*
X273109Y1551608D01*
Y1553173D01*
X271932Y1554350D01*
X271580D01*
G01X261530Y1555320D02*
X262950D01*
X263830Y1554440D01*
Y1546630D01*
X261095Y1543895D01*
Y1540477D01*
G01X268380Y1558650D02*
X266240D01*
X265250Y1557660D01*
Y1545668D01*
X262276Y1542694D01*
Y1538431D01*
G01X268380Y1553650D02*
X267222D01*
X266670Y1553098D01*
Y1546746D01*
X267297Y1546119D01*
G01X268380Y1558650D02*
Y1560204D01*
X267064Y1561520D01*
X264617D01*
G01X268380Y1556550D02*
Y1553650D01*
G01X288433Y32756D02*
Y21802D01*
X286996Y20365D01*
G01X276622Y44370D02*
Y48149D01*
X275896Y48875D01*
G01X288433Y44370D02*
Y54448D01*
X287988Y54893D01*
G01X275797Y123968D02*
Y120252D01*
X275793Y120248D01*
G01X279783Y123993D02*
X275822D01*
X275797Y123968D01*
G01Y127118D02*
Y129591D01*
X275793Y129595D01*
G01X308240Y148100D02*
X299600Y139460D01*
X293050D01*
X284840Y131250D01*
Y128740D01*
X283243Y127143D01*
X279783D01*
G01X285269Y149291D02*
Y145892D01*
X287196Y143965D01*
G01X287237Y149291D02*
Y147509D01*
X290730Y144016D01*
X292496D01*
G01X289206Y149291D02*
Y148288D01*
X290788Y146706D01*
X295155D01*
X297696Y144165D01*
G01X286875Y136962D02*
X286996Y137083D01*
Y139865D01*
G01X283300Y149291D02*
Y145269D01*
X281996Y143965D01*
G01X283725Y136962D02*
X283049Y137638D01*
Y139731D01*
G01X281996Y143965D02*
Y140784D01*
X283049Y139731D01*
G01X276825Y136962D02*
Y140461D01*
X276821Y140465D01*
G01X279975Y136962D02*
Y140986D01*
X276996Y143965D01*
G01X280741Y151850D02*
X279906D01*
X278808Y150752D01*
Y145777D01*
X276996Y143965D01*
G01X287237Y160315D02*
Y166477D01*
X290840Y170080D01*
G01X285269Y160315D02*
Y167741D01*
X284990Y168020D01*
G01X283300Y160315D02*
Y162292D01*
X280496Y165096D01*
X278697D01*
G01X280075Y211000D02*
Y207000D01*
G01D02*
X286000D01*
X288000Y209000D01*
G01X276925Y211000D02*
Y212580D01*
X277345Y213000D01*
X279574D01*
X280075Y213501D01*
Y215000D01*
G01X283811Y215870D02*
Y218955D01*
X282325Y220441D01*
X278500D01*
G01X280075Y215000D02*
X282941D01*
X283811Y215870D01*
G01X288597Y215444D02*
X288743D01*
X289163Y215024D01*
Y212503D01*
G01X288597Y218594D02*
Y220067D01*
X286546Y222118D01*
G01D02*
X285260Y223404D01*
Y227776D01*
G01X289000Y237224D02*
Y239948D01*
X287000Y241948D01*
Y243069D01*
G01D02*
Y244387D01*
X288949Y246336D01*
G01X292705Y586029D02*
X290444D01*
X289659Y585244D01*
Y579766D01*
X292237Y577188D01*
X294299D01*
G01X292705Y586029D02*
X288267Y590467D01*
X281712D01*
X279729Y592450D01*
Y594223D01*
G01X297815Y586029D02*
X297062Y586782D01*
X295115D01*
X289815Y592082D01*
X282397D01*
X281698Y592781D01*
Y594223D01*
G01X284035Y796850D02*
X286195D01*
X297078Y807733D01*
X302396D01*
X302399Y807734D01*
X331562D01*
X349459Y825631D01*
Y851431D01*
X330897Y869993D01*
Y874293D01*
G01X285258Y799314D02*
X287075D01*
X297031Y809270D01*
X331514D01*
X348339Y826095D01*
Y850967D01*
X329351Y869955D01*
Y875001D01*
X330897Y876547D01*
Y880671D01*
G01X278350Y1506600D02*
Y1506202D01*
X279552Y1505000D01*
X283550D01*
G01D02*
Y1505659D01*
X286872Y1508981D01*
G01X294450Y1517640D02*
Y1518989D01*
X293819Y1519620D01*
X290040D01*
X289460Y1520200D01*
G01X286200Y1521750D02*
Y1518850D01*
G01X281704Y1526953D02*
X283502Y1528751D01*
X285447D01*
X287703Y1526495D01*
Y1522917D01*
X286536Y1521750D01*
X286200D01*
G01X283000D02*
Y1518850D01*
G01Y1521750D02*
X282476Y1521745D01*
X281522Y1522688D01*
Y1524012D01*
X280962Y1524572D01*
X278751Y1525488D01*
X278169D01*
X276704Y1526953D01*
G01X293450Y1510800D02*
Y1511135D01*
X290271Y1514314D01*
X289224D01*
G01X302606Y32756D02*
Y26365D01*
G01X290795Y32756D02*
Y28365D01*
G01X293157Y32756D02*
Y25576D01*
X292056Y24475D01*
G01X295516Y26365D02*
Y32752D01*
X295520Y32756D01*
G01X300244D02*
Y28365D01*
G01X297882Y32756D02*
Y24479D01*
X299496Y22865D01*
G01X307331Y32756D02*
Y27065D01*
X304923Y24657D01*
G01X304968Y32756D02*
Y28365D01*
G01X291379Y55746D02*
X290795Y55162D01*
Y44370D01*
G01X293157D02*
Y50525D01*
G01X304968Y44370D02*
Y41928D01*
X302716Y39676D01*
Y38735D01*
X303252Y38199D01*
G01X295520Y44370D02*
Y55038D01*
X296337Y55855D01*
G01X300244Y44370D02*
Y49493D01*
X301306Y50555D01*
Y52485D01*
G01X297882Y44370D02*
Y50668D01*
X298302Y51088D01*
X298542D01*
G01X302606Y44370D02*
Y49755D01*
X303711Y50860D01*
G01X301241Y67128D02*
X302145Y68032D01*
X305266D01*
G01X301107Y75676D02*
X301104Y75673D01*
X298522D01*
G01X301107Y75676D02*
X303677D01*
X306521Y78520D01*
G01X305820Y73693D02*
Y71736D01*
X305266Y71182D01*
G01D02*
X305212Y71128D01*
X301241D01*
G01X306521Y82457D02*
X302223D01*
X301780Y82900D01*
G01D02*
X301363Y82483D01*
X299002D01*
G01Y85983D02*
X304964D01*
X306521Y84426D01*
G01X299002Y88700D02*
Y85983D01*
G01X308490Y84426D02*
Y88509D01*
X305232Y91767D01*
G01X305315Y95724D02*
Y91850D01*
X305232Y91767D01*
G01X292740Y237224D02*
Y242691D01*
G01X292949Y249486D02*
X294069D01*
X295529Y248026D01*
Y243145D01*
X296283Y242391D01*
G01X302500Y253575D02*
Y255500D01*
X303528Y256528D01*
X306528D01*
G01X292740Y242691D02*
Y246127D01*
X292949Y246336D01*
G01X297815Y586029D02*
X300261D01*
X302130Y584160D01*
G01X294450Y1517640D02*
X295544D01*
X295944Y1518040D01*
X297350D01*
G01D02*
Y1516839D01*
X297959Y1516230D01*
X302710D01*
X303485Y1517005D01*
Y1519121D01*
X304171Y1519807D01*
X307519D01*
G01X297350Y1514420D02*
X294330D01*
X294224Y1514314D01*
G01X307519Y1517445D02*
X306765D01*
X304123Y1514803D01*
Y1514248D01*
X302485Y1512610D01*
X297970D01*
X297350Y1513230D01*
Y1514420D01*
G01X305148Y1518121D02*
X306143D01*
X306648Y1518626D01*
X309565D01*
G01X293450Y1510800D02*
X297350D01*
G01D02*
Y1509522D01*
X298181Y1508691D01*
X302016D01*
X305134Y1511809D01*
Y1514568D01*
X306830Y1516264D01*
X309565D01*
G01Y1532799D02*
X306103D01*
X303848Y1535054D01*
Y1540117D01*
X314507Y1550776D01*
Y1555570D01*
X314771Y1555834D01*
G01X307519Y1531618D02*
X305442D01*
X302680Y1534380D01*
Y1540738D01*
X308786Y1546844D01*
Y1551952D01*
X307850Y1552888D01*
X307199D01*
G01X309565Y1530437D02*
X303963D01*
X300751Y1533649D01*
Y1550552D01*
X300199Y1551104D01*
Y1553688D01*
G01X303041Y1544299D02*
X302233Y1545107D01*
Y1552096D01*
X303025Y1552888D01*
X303999D01*
G01X312715Y1575985D02*
X298517Y1561787D01*
Y1554269D01*
X299098Y1553688D01*
X300199D01*
G01X303999Y1552888D02*
Y1555788D01*
G01X300199D02*
X303999D01*
G01X307331Y44370D02*
Y47300D01*
X310396Y50365D01*
G01X310459Y78520D02*
Y75899D01*
X310455Y75895D01*
G01X305266Y68032D02*
X306700D01*
X310711Y72043D01*
Y75639D01*
X310455Y75895D01*
G01X322467Y69863D02*
X321342D01*
X320190Y71015D01*
Y77648D01*
G01X305820Y73693D02*
X308490Y76363D01*
Y78520D01*
G01X318333Y80489D02*
X319039D01*
X322871Y84321D01*
G01X316364Y84426D02*
Y88385D01*
X316982Y89003D01*
G01D02*
Y91803D01*
G01X320190Y77648D02*
Y78100D01*
X319770Y78520D01*
X318333D01*
G01X317028Y99837D02*
Y95856D01*
X317024Y95852D01*
G01D02*
Y91845D01*
X316982Y91803D01*
G01X305315Y95724D02*
X307813D01*
X307816Y95727D01*
G01X319075Y263000D02*
Y260075D01*
G01X314602Y271016D02*
Y267374D01*
X318976Y263000D01*
X319075D01*
G01X315925D02*
X312075D01*
G01X306528Y256528D02*
X309760D01*
G01X312075Y263000D02*
Y258843D01*
X309760Y256528D01*
G01X326177Y274000D02*
X319641D01*
G01D02*
X319635Y274006D01*
X314762D01*
X314602Y274166D01*
G01X319795Y887049D02*
X317957Y886002D01*
G01X321645Y890238D02*
X319807Y889191D01*
G01X321645Y909371D02*
X319807Y908325D01*
G01X319795Y899805D02*
X317957Y898758D01*
G01X321645Y902994D02*
X319807Y901947D01*
G01X319795Y906182D02*
X317957Y905135D01*
G01X319795Y918938D02*
X317957Y917891D01*
G01X321645Y922127D02*
X319807Y921080D01*
G01X319795Y925316D02*
X317957Y924269D01*
G01X321645Y928505D02*
X319807Y927458D01*
G01X319795Y938072D02*
X317957Y937025D01*
G01X321645Y941261D02*
X319807Y940214D01*
G01X319795Y944450D02*
X317957Y943403D01*
G01X321645Y947639D02*
X319807Y946592D01*
G01X319795Y963584D02*
X317957Y962537D01*
G01X321645Y966773D02*
X319807Y965726D01*
G01X319795Y957206D02*
X317957Y956159D01*
G01X321645Y960395D02*
X319807Y959348D01*
G01X319795Y976340D02*
X317957Y975293D01*
G01X321645Y979529D02*
X319807Y978482D01*
G01X319795Y995474D02*
X317957Y994427D01*
G01X321645Y998663D02*
X319807Y997616D01*
G01X321645Y992285D02*
X319807Y991238D01*
G01X319795Y989096D02*
X317957Y988049D01*
G01X319795Y1001852D02*
X317957Y1000805D01*
G01X321645Y1005041D02*
X319807Y1003994D01*
G01X315425Y1027009D02*
X313587Y1028056D01*
G01X320976Y1036576D02*
X319138Y1037623D01*
G01X320976Y1042954D02*
X319138Y1044001D01*
G01X320976Y1030198D02*
X319138Y1031245D01*
G01X320976Y1049332D02*
X319138Y1050379D01*
G01X320976Y1055710D02*
X319138Y1056757D01*
G01X320976Y1062088D02*
X319138Y1063135D01*
G01X320976Y1074844D02*
X319138Y1075891D01*
G01X320976Y1081222D02*
X319138Y1082269D01*
G01X320976Y1100356D02*
X319138Y1101403D01*
G01X320976Y1093978D02*
X319138Y1095025D01*
G01X320976Y1113112D02*
X319138Y1114159D01*
G01X320976Y1119490D02*
X319138Y1120537D01*
G01X320976Y1132246D02*
X319138Y1133293D01*
G01X320976Y1138623D02*
X319138Y1139670D01*
G01X311724Y1160946D02*
X308149Y1164521D01*
Y1168800D01*
X317178Y1177829D01*
X338291D01*
X348404Y1187942D01*
Y1205907D01*
X347885Y1206426D01*
G01X317275Y1157757D02*
X315437Y1158804D01*
G01X320976Y1151379D02*
X319138Y1152426D01*
G01X379223Y1219527D02*
Y1212396D01*
X382105Y1209514D01*
Y1195441D01*
X356401Y1169737D01*
X323376D01*
X319126Y1165487D01*
Y1160946D01*
G01X361922Y1206891D02*
X356311Y1201280D01*
Y1187608D01*
X340499Y1171796D01*
X322879D01*
X317275Y1166192D01*
Y1164135D01*
G01X315425Y1160946D02*
Y1166846D01*
X322145Y1173566D01*
X339399D01*
X354520Y1188687D01*
Y1202505D01*
X357271Y1205256D01*
Y1208988D01*
G01X306807Y1513218D02*
X308881D01*
X309565Y1513902D01*
G01X305549Y1521612D02*
X306173Y1520988D01*
X309565D01*
G01Y1535162D02*
X306131D01*
X305595Y1535698D01*
G01X307519Y1536343D02*
X305964Y1537898D01*
X305595D01*
G01X311476Y1559939D02*
Y1557039D01*
G01D02*
X313566D01*
X314771Y1555834D01*
G01X307199Y1555788D02*
Y1552888D01*
G01Y1555788D02*
X308248D01*
X309130Y1556670D01*
Y1560171D01*
X308222Y1561079D01*
G01X325617Y69863D02*
Y73788D01*
G01D02*
X323699D01*
X323036Y73125D01*
G01X325617Y84318D02*
X322874D01*
X322871Y84321D01*
G01X326071Y147120D02*
X323646D01*
G01X329221D02*
Y152120D01*
G01X326071Y160120D02*
X323646D01*
G01X326071Y156120D02*
X323646D01*
G01X326071Y152120D02*
X323646D01*
G01X329221Y164920D02*
Y171170D01*
G01Y152120D02*
Y156120D01*
G01D02*
Y160120D01*
G01Y164920D02*
Y160120D01*
G01X331780Y178610D02*
Y182900D01*
G01X330934Y560271D02*
Y559185D01*
X333879Y556240D01*
Y528248D01*
X346751Y515376D01*
G01X330934Y552397D02*
Y555609D01*
X330451Y556092D01*
X326299D01*
X325816Y555609D01*
Y552397D01*
G01D02*
Y545521D01*
G01Y543012D02*
Y545521D01*
G01Y560271D02*
Y559009D01*
X322955Y556148D01*
G01X329047Y883860D02*
X327209Y882813D01*
G01X325346Y890238D02*
X323508Y889191D01*
G01X327196Y893427D02*
X325358Y892380D01*
G01X334598Y887049D02*
X332760Y886002D01*
G01X332748Y890238D02*
X330910Y889191D01*
G01X325346Y883860D02*
X323508Y882813D01*
G01X325346Y902994D02*
X323508Y901947D01*
G01X327196Y906182D02*
X325358Y905135D01*
G01X325346Y909371D02*
X323508Y908325D01*
G01X332748Y909371D02*
X330910Y908325D01*
G01X334598Y899805D02*
X332760Y898758D01*
G01X332748Y902994D02*
X330910Y901947D01*
G01X334598Y906182D02*
X332760Y905135D01*
G01X327196Y912560D02*
X325358Y911513D01*
G01X325346Y922127D02*
X323508Y921080D01*
G01X327196Y925316D02*
X325358Y924269D01*
G01X334598Y918938D02*
X332760Y917891D01*
G01X332748Y922127D02*
X330910Y921080D01*
G01X334598Y925316D02*
X332760Y924269D01*
G01X325346Y928505D02*
X323508Y927458D01*
G01X327196Y931694D02*
X325358Y930647D01*
G01X325346Y941261D02*
X323508Y940214D01*
G01X332748Y928505D02*
X330910Y927458D01*
G01X334598Y938072D02*
X332760Y937025D01*
G01X332748Y941261D02*
X330910Y940214D01*
G01X327196Y944450D02*
X325358Y943403D01*
G01X325346Y947639D02*
X323508Y946592D01*
G01X327196Y950828D02*
X325358Y949781D01*
G01X334598Y944450D02*
X332760Y943403D01*
G01X332748Y947639D02*
X330910Y946592D01*
G01X325346Y966773D02*
X323508Y965726D01*
G01X327196Y969962D02*
X325358Y968915D01*
G01X325346Y960395D02*
X323508Y959348D01*
G01X327196Y963584D02*
X325358Y962537D01*
G01X334598Y963584D02*
X332760Y962537D01*
G01X332748Y966773D02*
X330910Y965726D01*
G01X334598Y957206D02*
X332760Y956159D01*
G01X332748Y960395D02*
X330910Y959348D01*
G01X325346Y985907D02*
X323508Y984860D01*
G01X325346Y979529D02*
X323508Y978482D01*
G01X327196Y982718D02*
X325358Y981671D01*
G01X334598Y976340D02*
X332760Y975293D01*
G01X332748Y979529D02*
X330910Y978482D01*
G01X327196Y989096D02*
X325358Y988049D01*
G01X325346Y998663D02*
X323508Y997616D01*
G01X327196Y995474D02*
X325358Y994427D01*
G01X334598Y995474D02*
X332760Y994427D01*
G01X332748Y998663D02*
X330910Y997616D01*
G01X332748Y992285D02*
X330910Y991238D01*
G01X334598Y989096D02*
X332760Y988049D01*
G01X325346Y992285D02*
X323508Y991238D01*
G01X327196Y1001852D02*
X325358Y1000805D01*
G01X325346Y1005041D02*
X323508Y1003994D01*
G01X327196Y1008230D02*
X325358Y1007183D01*
G01X334598Y1001852D02*
X332760Y1000805D01*
G01X332748Y1005041D02*
X330910Y1003994D01*
G01X325346Y1011419D02*
X323508Y1010372D01*
G01X326527Y1027009D02*
X324689Y1028056D01*
G01X333929Y1027009D02*
X332091Y1028056D01*
G01X322826Y1027009D02*
X320988Y1028056D01*
G01X328378Y1030198D02*
X326539Y1031245D01*
G01X326527Y1033387D02*
X324689Y1034434D01*
G01X322826Y1033387D02*
X320988Y1034434D01*
G01X328378Y1036576D02*
X326539Y1037623D01*
G01X326527Y1039765D02*
X324689Y1040812D01*
G01X322826Y1039765D02*
X320988Y1040812D01*
G01X333929Y1033387D02*
X332091Y1034434D01*
G01X335779Y1036576D02*
X333941Y1037623D01*
G01X333929Y1039765D02*
X332091Y1040812D01*
G01X335779Y1042954D02*
X333941Y1044001D01*
G01X335779Y1030198D02*
X333941Y1031245D01*
G01X328378Y1042954D02*
X326540Y1044001D01*
G01X328378Y1049332D02*
X326539Y1050379D01*
G01X322826Y1058899D02*
X320988Y1059946D01*
G01X326527Y1046143D02*
X324689Y1047190D01*
G01X322826Y1052521D02*
X320988Y1053568D01*
G01X333929Y1058899D02*
X332091Y1059946D01*
G01X335779Y1049332D02*
X333941Y1050379D01*
G01X333929Y1052521D02*
X332091Y1053568D01*
G01X335779Y1055710D02*
X333941Y1056757D01*
G01X333929Y1046143D02*
X332091Y1047190D01*
G01X322826Y1046143D02*
X320988Y1047190D01*
G01X326527Y1052521D02*
X324689Y1053568D01*
G01X322826Y1071655D02*
X320988Y1072702D01*
G01X328378Y1074844D02*
X326539Y1075891D01*
G01X328378Y1062088D02*
X326539Y1063135D01*
G01X326527Y1065277D02*
X324689Y1066324D01*
G01X333929Y1071655D02*
X332091Y1072702D01*
G01X335779Y1062088D02*
X333941Y1063135D01*
G01X326527Y1078033D02*
X324689Y1079080D01*
G01X322826Y1078033D02*
X320988Y1079080D01*
G01X328378Y1081222D02*
X326539Y1082269D01*
G01X326527Y1084411D02*
X324689Y1085458D01*
G01X335779Y1074844D02*
X333941Y1075891D01*
G01X333929Y1078033D02*
X332091Y1079080D01*
G01X335779Y1081222D02*
X333941Y1082269D01*
G01X326527Y1103545D02*
X324689Y1104592D01*
G01X322826Y1090789D02*
X320988Y1091836D01*
G01X328378Y1093978D02*
X326539Y1095025D01*
G01X326527Y1097167D02*
X324689Y1098214D01*
G01X322826Y1097167D02*
X320988Y1098214D01*
G01X328378Y1100356D02*
X326539Y1101403D01*
G01X335779Y1100356D02*
X333941Y1101403D01*
G01X333929Y1090789D02*
X332091Y1091836D01*
G01X335779Y1093978D02*
X333941Y1095025D01*
G01X333929Y1097167D02*
X332091Y1098214D01*
G01X322826Y1109923D02*
X320988Y1110970D01*
G01X328378Y1113112D02*
X326539Y1114159D01*
G01X326527Y1116301D02*
X324689Y1117348D01*
G01X322826Y1116301D02*
X320988Y1117348D01*
G01X328378Y1119490D02*
X326539Y1120537D01*
G01X333929Y1109923D02*
X332091Y1110970D01*
G01X335779Y1113112D02*
X333941Y1114159D01*
G01X333929Y1116301D02*
X332091Y1117348D01*
G01X326527Y1122679D02*
X324689Y1123726D01*
G01X322826Y1129057D02*
X320988Y1130103D01*
G01X328378Y1132246D02*
X326539Y1133293D01*
G01X335779Y1119490D02*
X333941Y1120537D01*
G01X333929Y1129057D02*
X332091Y1130103D01*
G01X335779Y1132246D02*
X333941Y1133293D01*
G01X326527Y1135434D02*
X324689Y1136481D01*
G01X322826Y1135434D02*
X320988Y1136481D01*
G01X328378Y1138623D02*
X326539Y1139670D01*
G01X326527Y1141812D02*
X324689Y1142859D01*
G01X322826Y1148190D02*
X320988Y1149237D01*
G01X333929Y1135434D02*
X332091Y1136481D01*
G01X335779Y1138623D02*
X333941Y1139670D01*
G01X333929Y1148190D02*
X332091Y1149237D01*
G01X328378Y1151379D02*
X326539Y1152426D01*
G01X326527Y1154568D02*
X324689Y1155615D01*
G01X335779Y1151379D02*
X333941Y1152426D01*
G01X333929Y1154568D02*
X332091Y1155615D01*
G01X333929Y1160946D02*
X332091Y1161993D01*
G01X328378Y1164135D02*
X326539Y1165182D01*
G01X326527Y1160946D02*
X324689Y1161993D01*
G01X380718Y1221906D02*
X381757Y1220867D01*
Y1213520D01*
X385079Y1210198D01*
Y1196126D01*
X357072Y1168119D01*
X323693D01*
X320976Y1165402D01*
Y1164135D01*
G01X335779D02*
X333941Y1165182D01*
G01X339811Y123102D02*
Y121180D01*
X340436Y120555D01*
G01X347673Y130005D02*
X344611D01*
X343446Y131170D01*
G01X347673Y126265D02*
X344598D01*
X339811Y131052D01*
G01D02*
Y126252D01*
G01X346291Y225070D02*
X347907D01*
X352000Y229163D01*
Y230643D01*
G01X346695Y233980D02*
X341895D01*
G01D02*
Y230380D01*
X343095Y229180D01*
G01X346695Y237130D02*
X350023D01*
X351510Y235643D01*
X352000D01*
G01X335823Y270260D02*
X342192D01*
G01D02*
X344498D01*
X344550Y270312D01*
X346152D01*
X346153Y270311D01*
G01X342000Y277425D02*
X344631D01*
X346275Y279069D01*
Y299093D01*
X367931Y320749D01*
X426947D01*
G01X346153Y273461D02*
X344353D01*
X342000Y275814D01*
Y277425D01*
G01X570216Y759762D02*
X570676Y759302D01*
Y570128D01*
X522704Y522156D01*
X364455D01*
X340192Y546419D01*
Y573192D01*
X341500Y574500D01*
G01X575216Y759762D02*
X572448Y756994D01*
Y569394D01*
X523438Y520384D01*
X363721D01*
X338420Y545685D01*
Y574500D01*
G01X337750Y584750D02*
X336500Y583500D01*
Y544810D01*
X362902Y518408D01*
X524257D01*
X574424Y568575D01*
Y755129D01*
X578351Y759056D01*
Y775350D01*
X526982Y826719D01*
Y833014D01*
X533795Y849463D01*
Y858876D01*
X529841Y862830D01*
X504660D01*
X502984Y864506D01*
Y877482D01*
G01X348157Y571265D02*
X345902D01*
X342311Y567674D01*
Y546958D01*
X349859Y539410D01*
X372490D01*
X375271Y542191D01*
G01X353582Y562415D02*
Y560889D01*
X353001Y560308D01*
X349601D01*
X345521Y564388D01*
G01X353582Y574415D02*
Y572849D01*
X353162Y572429D01*
X349321D01*
X348157Y571265D01*
G01X353582Y582415D02*
X342585D01*
X342500Y582500D01*
G01X353582Y578415D02*
X342585D01*
X342500Y578500D01*
G01X348732Y586415D02*
X351157D01*
G01X337750Y584750D02*
X342000Y589000D01*
X346147D01*
X348732Y586415D01*
G01X338299Y880671D02*
Y876583D01*
X340116Y874766D01*
Y869376D01*
X353510Y855982D01*
X357400D01*
G01X338299Y874293D02*
Y868901D01*
X356535Y850665D01*
Y849708D01*
G01X342000Y874293D02*
Y870901D01*
X353281Y859620D01*
G01X366864Y857274D02*
X366386D01*
X363005Y860655D01*
Y862004D01*
X357815Y867194D01*
X356466D01*
X351116Y872544D01*
Y875266D01*
X349401Y876981D01*
Y880671D01*
G01Y874293D02*
Y872498D01*
X356042Y865857D01*
X357563D01*
X361890Y861530D01*
Y860190D01*
X364897Y857183D01*
Y852564D01*
G01X356895Y859791D02*
X356635D01*
X343881Y872545D01*
Y875031D01*
X342000Y876912D01*
Y880671D01*
G01X345700Y887049D02*
X343862Y886002D01*
G01X351252Y890238D02*
X349414Y889191D01*
G01X347551Y890238D02*
X345713Y889191D01*
G01X340149Y890238D02*
X338311Y889191D01*
G01X338299Y893427D02*
X336461Y892380D01*
G01X347551Y909371D02*
X345713Y908325D01*
G01X345700Y899805D02*
X343862Y898758D01*
G01X351252Y902994D02*
X349414Y901947D01*
G01X347551Y902994D02*
X345713Y901947D01*
G01X345700Y906182D02*
X343862Y905135D01*
G01X351252Y909371D02*
X349414Y908325D01*
G01X340149Y902994D02*
X338311Y901947D01*
G01X338299Y906182D02*
X336461Y905135D01*
G01X340149Y909371D02*
X338311Y908325D01*
G01X345700Y918938D02*
X343862Y917891D01*
G01X351252Y922127D02*
X349414Y921080D01*
G01X347551Y922127D02*
X345713Y921080D01*
G01X345700Y925316D02*
X343862Y924269D01*
G01X338299Y912560D02*
X336461Y911513D01*
G01X340149Y922127D02*
X338311Y921080D01*
G01X338299Y925316D02*
X336461Y924269D01*
G01X351252Y928505D02*
X349414Y927458D01*
G01X347551Y928505D02*
X345713Y927458D01*
G01X345700Y938072D02*
X343862Y937025D01*
G01X351252Y941261D02*
X349414Y940214D01*
G01X347551Y941261D02*
X345713Y940214D01*
G01X340149Y928505D02*
X338311Y927458D01*
G01X338299Y931694D02*
X336461Y930647D01*
G01X340149Y941261D02*
X338311Y940214D01*
G01X345700Y944450D02*
X343862Y943403D01*
G01X351252Y947639D02*
X349414Y946592D01*
G01X347551Y947639D02*
X345713Y946592D01*
G01X338299Y944450D02*
X336461Y943403D01*
G01X340149Y947639D02*
X338311Y946592D01*
G01X338299Y950828D02*
X336461Y949781D01*
G01X345700Y963584D02*
X343862Y962537D01*
G01X351252Y966773D02*
X349414Y965726D01*
G01X347551Y966773D02*
X345713Y965726D01*
G01X345700Y957206D02*
X343862Y956159D01*
G01X351252Y960395D02*
X349414Y959348D01*
G01X347551Y960395D02*
X345713Y959348D01*
G01X340149Y966773D02*
X338311Y965726D01*
G01X338299Y969962D02*
X336461Y968915D01*
G01X340149Y960395D02*
X338311Y959348D01*
G01X338299Y963584D02*
X336461Y962537D01*
G01X351252Y985907D02*
X349414Y984860D01*
G01X345700Y976340D02*
X343862Y975293D01*
G01X351252Y979529D02*
X349414Y978482D01*
G01X347551Y979529D02*
X345713Y978482D01*
G01X340149Y985907D02*
X338311Y984860D01*
G01X340149Y979529D02*
X338311Y978482D01*
G01X338299Y982718D02*
X336461Y981671D01*
G01X345700Y995474D02*
X343862Y994427D01*
G01X347551Y998663D02*
X345713Y997616D01*
G01X351252Y998663D02*
X349414Y997616D01*
G01X347551Y992285D02*
X345713Y991238D01*
G01X338299Y989096D02*
X336461Y988049D01*
G01X340149Y998663D02*
X338311Y997616D01*
G01X338299Y995474D02*
X336461Y994427D01*
G01X340149Y992285D02*
X338311Y991238D01*
G01X351252Y992285D02*
X349414Y991238D01*
G01X345700Y989096D02*
X343862Y988049D01*
G01X345700Y1001852D02*
X343862Y1000805D01*
G01X347551Y1005041D02*
X345713Y1003994D01*
G01X351252Y1005041D02*
X349414Y1003994D01*
G01X338299Y1001852D02*
X336461Y1000805D01*
G01X340149Y1005041D02*
X338311Y1003994D01*
G01X338299Y1008230D02*
X336461Y1007183D01*
G01X340149Y1011419D02*
X338311Y1010372D01*
G01X351252Y1011419D02*
X349414Y1010372D01*
G01X341330Y1027009D02*
X339492Y1028056D01*
G01X348732Y1027009D02*
X346894Y1028056D01*
G01X348732Y1033387D02*
X346894Y1034434D01*
G01X346881Y1036576D02*
X345043Y1037623D01*
G01X348732Y1039765D02*
X346894Y1040812D01*
G01X346881Y1042954D02*
X345043Y1044001D01*
G01X339480Y1030198D02*
X337642Y1031245D01*
G01X341330Y1033387D02*
X339492Y1034434D01*
G01X339480Y1036576D02*
X337642Y1037623D01*
G01X341330Y1039765D02*
X339492Y1040812D01*
G01X339480Y1042954D02*
X337642Y1044001D01*
G01X346881Y1030198D02*
X345043Y1031245D01*
G01X348732Y1058899D02*
X346894Y1059946D01*
G01X346881Y1049332D02*
X345043Y1050379D01*
G01X348732Y1052521D02*
X346894Y1053568D01*
G01X339480Y1049332D02*
X337642Y1050379D01*
G01X341330Y1046143D02*
X339492Y1047190D01*
G01X341330Y1052521D02*
X339492Y1053568D01*
G01X346881Y1055710D02*
X345043Y1056757D01*
G01X348732Y1046143D02*
X346894Y1047190D01*
G01X348732Y1071655D02*
X346894Y1072702D01*
G01X346881Y1074844D02*
X345043Y1075891D01*
G01X346881Y1062088D02*
X345043Y1063135D01*
G01X339480Y1074844D02*
X337642Y1075891D01*
G01X339480Y1062088D02*
X337642Y1063135D01*
G01X341330Y1065277D02*
X339492Y1066324D01*
G01X348732Y1078033D02*
X346894Y1079080D01*
G01X346881Y1081222D02*
X345043Y1082269D01*
G01X341330Y1078033D02*
X339492Y1079080D01*
G01X339480Y1081222D02*
X337642Y1082269D01*
G01X341330Y1084411D02*
X339492Y1085458D01*
G01X346881Y1100356D02*
X345043Y1101403D01*
G01X348732Y1090789D02*
X346894Y1091836D01*
G01X346881Y1093978D02*
X345043Y1095025D01*
G01X348732Y1097167D02*
X346894Y1098214D01*
G01X341330Y1103545D02*
X339492Y1104592D01*
G01X339480Y1093978D02*
X337642Y1095025D01*
G01X341330Y1097167D02*
X339492Y1098214D01*
G01X339480Y1100356D02*
X337642Y1101403D01*
G01X348732Y1109923D02*
X346894Y1110970D01*
G01X346881Y1113112D02*
X345043Y1114159D01*
G01X348732Y1116301D02*
X346894Y1117348D01*
G01X346881Y1119490D02*
X345043Y1120537D01*
G01X339480Y1113112D02*
X337642Y1114159D01*
G01X341330Y1116301D02*
X339492Y1117348D01*
G01X339480Y1119490D02*
X337642Y1120537D01*
G01X348732Y1129057D02*
X346894Y1130103D01*
G01X346881Y1132246D02*
X345043Y1133293D01*
G01X341330Y1122679D02*
X339492Y1123726D01*
G01X339480Y1132246D02*
X337642Y1133293D01*
G01X348732Y1135434D02*
X346894Y1136481D01*
G01X346881Y1138623D02*
X345043Y1139670D01*
G01X348732Y1148190D02*
X346894Y1149237D01*
G01X341330Y1135434D02*
X339492Y1136481D01*
G01X339480Y1138623D02*
X337642Y1139670D01*
G01X341330Y1141812D02*
X339492Y1142859D01*
G01X346881Y1151379D02*
X345043Y1152426D01*
G01X339480Y1151379D02*
X337642Y1152426D01*
G01X341330Y1160946D02*
X339492Y1161993D01*
G01X343181Y1164135D02*
X341343Y1165182D01*
G01X357319Y122525D02*
X359932D01*
X361744Y120713D01*
G01X365836Y163265D02*
X362788Y160217D01*
Y140495D01*
X364386Y138897D01*
X370999D01*
G01X355508Y219343D02*
Y215343D01*
X355490Y215325D01*
G01D02*
Y211425D01*
X355508Y211407D01*
G01X356108Y226702D02*
Y224045D01*
X355910Y223847D01*
G01D02*
X355508Y223445D01*
Y219343D01*
G01X363982Y226702D02*
Y223628D01*
X365739Y221871D01*
G01X352000Y230643D02*
X352004Y230639D01*
X354139D01*
G01X362013Y232608D02*
Y240219D01*
X365160Y243366D01*
X365162D01*
G01X352000Y235643D02*
Y233665D01*
X353057Y232608D01*
X354139D01*
G01X363982D02*
Y237319D01*
X365559Y238896D01*
G01X362651Y283902D02*
X359819D01*
X357341Y281424D01*
G01X352608Y279905D02*
X355822D01*
X357341Y281424D01*
G01X352628Y283715D02*
Y279925D01*
X352608Y279905D01*
G01X362651Y285870D02*
X358395D01*
X357391Y286874D01*
G01X355828Y291815D02*
Y288437D01*
X357391Y286874D01*
G01X357925Y307500D02*
Y304082D01*
G01X361075Y307500D02*
X366000D01*
G01X357582Y555215D02*
X359182Y553615D01*
Y550415D01*
G01D02*
Y546242D01*
X357330Y544390D01*
X355100D01*
G01X356732Y562415D02*
Y562498D01*
X358136Y563902D01*
X359352D01*
X362200Y566750D01*
G01X356732Y566415D02*
X357704D01*
X358279Y566990D01*
X359200D01*
G01X353582Y558365D02*
X357582D01*
G01D02*
X360261Y561044D01*
G01X356732Y574415D02*
X359157D01*
G01X356732Y570415D02*
Y574415D01*
G01X355982Y590415D02*
X351157D01*
G01X355982Y586415D02*
X351157D01*
G01X369626Y860717D02*
X360255Y870088D01*
X356716D01*
X355116Y871688D01*
Y874766D01*
X353102Y876780D01*
Y880671D01*
G01Y874293D02*
Y872132D01*
X356534Y868700D01*
X357973D01*
X364821Y861852D01*
G01X366055Y877482D02*
X364217Y876435D01*
G01X360504Y880671D02*
X358665Y879624D01*
G01X353102Y893427D02*
X351264Y892380D01*
G01X360504Y887049D02*
X358665Y886002D01*
G01X366055Y890238D02*
X364217Y889191D01*
G01X358653Y890238D02*
X356815Y889191D01*
G01X364204Y893427D02*
X362366Y892380D01*
G01X353102Y906182D02*
X351264Y905135D01*
G01X358653Y909371D02*
X356815Y908325D01*
G01X360504Y899805D02*
X358665Y898758D01*
G01X366055Y902994D02*
X364217Y901947D01*
G01X358653Y902994D02*
X356815Y901947D01*
G01X364204Y906182D02*
X362366Y905135D01*
G01X360504Y906182D02*
X358665Y905135D01*
G01X366055Y909371D02*
X364217Y908325D01*
G01X353102Y912560D02*
X351264Y911513D01*
G01X353102Y925316D02*
X351264Y924269D01*
G01X364204Y912560D02*
X362366Y911513D01*
G01X360504Y918938D02*
X358665Y917891D01*
G01X366055Y922127D02*
X364217Y921080D01*
G01X358653Y922127D02*
X356815Y921080D01*
G01X364204Y925316D02*
X362366Y924269D01*
G01X360504Y925316D02*
X358665Y924269D01*
G01X353102Y931694D02*
X351264Y930647D01*
G01X366055Y928505D02*
X364217Y927458D01*
G01X358653Y928505D02*
X356815Y927458D01*
G01X364204Y931694D02*
X362366Y930647D01*
G01X360504Y938072D02*
X358665Y937025D01*
G01X366055Y941261D02*
X364217Y940214D01*
G01X358653Y941261D02*
X356815Y940214D01*
G01X353102Y944450D02*
X351264Y943403D01*
G01X353102Y950828D02*
X351264Y949781D01*
G01X364204Y944450D02*
X362366Y943403D01*
G01X360504Y944450D02*
X358665Y943403D01*
G01X366055Y947639D02*
X364217Y946592D01*
G01X358653Y947639D02*
X356815Y946592D01*
G01X364204Y950828D02*
X362366Y949781D01*
G01X353102Y969962D02*
X351264Y968915D01*
G01X353102Y963584D02*
X351264Y962537D01*
G01X360504Y963584D02*
X358665Y962537D01*
G01X366055Y966773D02*
X364217Y965726D01*
G01X358653Y966773D02*
X356815Y965726D01*
G01X364204Y969962D02*
X362366Y968915D01*
G01X360504Y957206D02*
X358665Y956159D01*
G01X366055Y960395D02*
X364217Y959348D01*
G01X358653Y960395D02*
X356815Y959348D01*
G01X364204Y963584D02*
X362366Y962537D01*
G01X353102Y982718D02*
X351264Y981671D01*
G01X366055Y985907D02*
X364217Y984860D01*
G01X360504Y976340D02*
X358665Y975293D01*
G01X366055Y979529D02*
X364217Y978482D01*
G01X358653Y979529D02*
X356815Y978482D01*
G01X364204Y982718D02*
X362366Y981671D01*
G01X353102Y989096D02*
X351264Y988049D01*
G01X353102Y995474D02*
X351264Y994427D01*
G01X364204Y989096D02*
X362366Y988049D01*
G01X360504Y995474D02*
X358665Y994427D01*
G01X358653Y998663D02*
X356815Y997616D01*
G01X366055Y998663D02*
X364217Y997616D01*
G01X358653Y992285D02*
X356815Y991238D01*
G01X364204Y995474D02*
X362366Y994427D01*
G01X366055Y992285D02*
X364217Y991238D01*
G01X360504Y989096D02*
X358666Y988049D01*
G01X353102Y1001852D02*
X351264Y1000805D01*
G01X353102Y1008230D02*
X351264Y1007183D01*
G01X364204Y1001852D02*
X362366Y1000805D01*
G01X360504Y1001852D02*
X358665Y1000805D01*
G01X358653Y1005041D02*
X356815Y1003994D01*
G01X366055Y1005041D02*
X364217Y1003994D01*
G01X364204Y1008230D02*
X362366Y1007183D01*
G01X366055Y1011419D02*
X364217Y1010372D01*
G01X352433Y1027009D02*
X350595Y1028056D01*
G01X359834Y1027009D02*
X357996Y1028056D01*
G01X354283Y1030198D02*
X352445Y1031245D01*
G01X352433Y1033387D02*
X350595Y1034434D01*
G01X354283Y1036576D02*
X352445Y1037623D01*
G01X352433Y1039765D02*
X350595Y1040812D01*
G01X365385Y1030198D02*
X363547Y1031245D01*
G01X359834Y1033387D02*
X357996Y1034434D01*
G01X361685Y1036576D02*
X359847Y1037623D01*
G01X365385Y1036576D02*
X363547Y1037623D01*
G01X359834Y1039765D02*
X357996Y1040812D01*
G01X361685Y1042954D02*
X359847Y1044001D01*
G01X365385Y1042954D02*
X363547Y1044001D01*
G01X361685Y1030198D02*
X359847Y1031245D01*
G01X354283Y1042954D02*
X352445Y1044001D01*
G01X354283Y1049332D02*
X352445Y1050379D01*
G01X352433Y1046143D02*
X350595Y1047190D01*
G01X365385Y1049332D02*
X363547Y1050379D01*
G01X359834Y1058899D02*
X357996Y1059946D01*
G01X361685Y1049332D02*
X359847Y1050379D01*
G01X359834Y1052521D02*
X357996Y1053568D01*
G01X361685Y1055710D02*
X359847Y1056757D01*
G01X359834Y1046143D02*
X357996Y1047190D01*
G01X352433Y1052521D02*
X350595Y1053568D01*
G01X354283Y1074844D02*
X352445Y1075891D01*
G01X354283Y1062088D02*
X352445Y1063135D01*
G01X352433Y1065277D02*
X350595Y1066324D01*
G01X359834Y1071655D02*
X357996Y1072702D01*
G01X361685Y1074844D02*
X359847Y1075891D01*
G01X365385Y1062088D02*
X363547Y1063135D01*
G01X361685Y1062088D02*
X359847Y1063135D01*
G01X352433Y1078033D02*
X350595Y1079080D01*
G01X354283Y1081222D02*
X352445Y1082269D01*
G01X352433Y1084411D02*
X350595Y1085458D01*
G01X365385Y1074844D02*
X363547Y1075891D01*
G01X359834Y1078033D02*
X357996Y1079080D01*
G01X365385Y1081222D02*
X363547Y1082269D01*
G01X361685Y1081222D02*
X359847Y1082269D01*
G01X352433Y1103545D02*
X350595Y1104592D01*
G01X354283Y1093978D02*
X352445Y1095025D01*
G01X352433Y1097167D02*
X350595Y1098214D01*
G01X354283Y1100356D02*
X352445Y1101403D01*
G01X361685Y1100356D02*
X359847Y1101403D01*
G01X359834Y1090789D02*
X357996Y1091836D01*
G01X365385Y1093978D02*
X363547Y1095025D01*
G01X361685Y1093978D02*
X359847Y1095025D01*
G01X359834Y1097167D02*
X357996Y1098214D01*
G01X365385Y1100356D02*
X363547Y1101403D01*
G01X354283Y1113112D02*
X352445Y1114159D01*
G01X352433Y1116301D02*
X350595Y1117348D01*
G01X354283Y1119490D02*
X352445Y1120537D01*
G01X359834Y1109923D02*
X357996Y1110970D01*
G01X365385Y1113112D02*
X363547Y1114159D01*
G01X361685Y1113112D02*
X359847Y1114159D01*
G01X359834Y1116301D02*
X357996Y1117348D01*
G01X361685Y1119490D02*
X359847Y1120537D01*
G01X352433Y1122679D02*
X350595Y1123726D01*
G01X354283Y1132246D02*
X352445Y1133293D01*
G01X365385Y1119490D02*
X363547Y1120537D01*
G01X359834Y1129057D02*
X357996Y1130103D01*
G01X365385Y1132246D02*
X363547Y1133293D01*
G01X361685Y1132246D02*
X359847Y1133293D01*
G01X352433Y1135434D02*
X350595Y1136481D01*
G01X354283Y1138623D02*
X352445Y1139670D01*
G01X352433Y1141812D02*
X350595Y1142859D01*
G01X359834Y1135434D02*
X357996Y1136481D01*
G01X365385Y1138623D02*
X363547Y1139670D01*
G01X361685Y1138623D02*
X359847Y1139670D01*
G01X359834Y1148190D02*
X357996Y1149237D01*
G01X354283Y1151379D02*
X352445Y1152426D01*
G01X352433Y1154568D02*
X350595Y1155615D01*
G01X365385Y1151379D02*
X363547Y1152426D01*
G01X361685Y1151379D02*
X359847Y1152426D01*
G01X359834Y1154568D02*
X357996Y1155615D01*
G01X361685Y1164135D02*
X359847Y1165182D01*
G01X359834Y1160946D02*
X357996Y1161993D01*
G01X352433Y1160946D02*
X350595Y1161993D01*
G01X354283Y1164135D02*
X352445Y1165182D01*
G01X365400Y146910D02*
Y145244D01*
X368007Y142637D01*
X370999D01*
G01X384155Y157936D02*
X379090D01*
G01D02*
X374130D01*
X374038Y158028D01*
G01D02*
Y163173D01*
G01X370888D02*
X370796Y163265D01*
X365836D01*
G01X377118Y222229D02*
X374646D01*
X373470Y223405D01*
Y225145D01*
G01X365739Y221871D02*
Y219362D01*
X365740Y219361D01*
G01X368890Y215361D02*
Y215815D01*
X365740Y218965D01*
Y219361D01*
G01X365951Y228671D02*
X370047D01*
X370327Y228951D01*
G01D02*
X373164D01*
X373470Y228645D01*
G01X373950Y235455D02*
X370352D01*
G01D02*
X368798D01*
X365951Y232608D01*
G01Y226702D02*
X371913D01*
X373470Y225145D01*
G01X373980Y239615D02*
X370118D01*
X370064Y239561D01*
G01X365559Y238896D02*
X366224Y239561D01*
X370064D01*
G01X373980Y243615D02*
X373076Y242711D01*
X370064D01*
G01X365162Y243366D02*
X365163Y243365D01*
X369410D01*
X370064Y242711D01*
G01X381013Y280370D02*
X376187D01*
X376091Y280274D01*
G01X370525Y283902D02*
X372463D01*
X376091Y280274D01*
G01Y295474D02*
X372802Y292185D01*
Y289210D01*
X371430Y287838D01*
X370525D01*
G01X376091Y295474D02*
X379909D01*
X381013Y294370D01*
G01Y287370D02*
X376595D01*
X376091Y287874D01*
G01D02*
X376079Y287862D01*
X373664D01*
X371672Y285870D01*
X370525D01*
G01X372677Y307500D02*
X366000D01*
G01X378184Y471926D02*
Y474834D01*
X380076Y476726D01*
X382184D01*
G01Y468776D02*
X378184D01*
G01X365852Y516466D02*
X525452D01*
X559280Y550294D01*
X665689D01*
G01X371962Y534092D02*
Y524954D01*
G01Y537242D02*
X375914D01*
X375943Y537271D01*
G01D02*
X380713D01*
X380771Y537213D01*
G01X371606Y874293D02*
X369768Y873246D01*
G01X375307Y874293D02*
X373469Y873246D01*
G01X379007Y874293D02*
X377169Y873246D01*
G01X371606Y887049D02*
X369768Y886002D01*
G01X377157Y890238D02*
X375319Y889191D01*
G01X373456Y890238D02*
X371618Y889191D01*
G01X379007Y893427D02*
X377169Y892380D01*
G01X373456Y909371D02*
X371618Y908325D01*
G01X371606Y899805D02*
X369768Y898758D01*
G01X377157Y902994D02*
X375319Y901947D01*
G01X373456Y902994D02*
X371618Y901947D01*
G01X379007Y906182D02*
X377169Y905135D01*
G01X371606Y906182D02*
X369768Y905135D01*
G01X377157Y909371D02*
X375319Y908325D01*
G01X379007Y912560D02*
X377169Y911513D01*
G01X371606Y918938D02*
X369768Y917891D01*
G01X377157Y922127D02*
X375319Y921080D01*
G01X373456Y922127D02*
X371618Y921080D01*
G01X379007Y925316D02*
X377169Y924269D01*
G01X371606Y925316D02*
X369768Y924269D01*
G01X377157Y928505D02*
X375319Y927458D01*
G01X373456Y928505D02*
X371618Y927458D01*
G01X379007Y931694D02*
X377169Y930647D01*
G01X371606Y938072D02*
X369768Y937025D01*
G01X377157Y941261D02*
X375319Y940214D01*
G01X373456Y941261D02*
X371618Y940214D01*
G01X379007Y944450D02*
X377169Y943403D01*
G01X371606Y944450D02*
X369768Y943403D01*
G01X377157Y947639D02*
X375319Y946592D01*
G01X373456Y947639D02*
X371618Y946592D01*
G01X379007Y950828D02*
X377169Y949781D01*
G01X371606Y963584D02*
X369768Y962537D01*
G01X377157Y966773D02*
X375319Y965726D01*
G01X373456Y966773D02*
X371618Y965726D01*
G01X379007Y969962D02*
X377169Y968915D01*
G01X371606Y957206D02*
X369768Y956159D01*
G01X377157Y960395D02*
X375319Y959348D01*
G01X373456Y960395D02*
X371618Y959348D01*
G01X379007Y963584D02*
X377169Y962537D01*
G01X377157Y985907D02*
X375319Y984860D01*
G01X371606Y976340D02*
X369768Y975293D01*
G01X377157Y979529D02*
X375319Y978482D01*
G01X373456Y979529D02*
X371618Y978482D01*
G01X379007Y982718D02*
X377169Y981671D01*
G01X379007Y989096D02*
X377169Y988049D01*
G01X371606Y995474D02*
X369768Y994427D01*
G01X373456Y998663D02*
X371618Y997616D01*
G01X377157Y998663D02*
X375319Y997616D01*
G01X373456Y992285D02*
X371618Y991238D01*
G01X379007Y995474D02*
X377169Y994427D01*
G01X377157Y992285D02*
X375319Y991238D01*
G01X371606Y989096D02*
X369768Y988049D01*
G01X379007Y1001852D02*
X377169Y1000805D01*
G01X371606Y1001852D02*
X369768Y1000805D01*
G01X373456Y1005041D02*
X371618Y1003994D01*
G01X377157Y1005041D02*
X375319Y1003994D01*
G01X379007Y1008230D02*
X377169Y1007183D01*
G01X377157Y1011419D02*
X375319Y1010372D01*
G01X378338Y1027009D02*
X376500Y1028056D01*
G01X367236Y1027009D02*
X365398Y1028056D01*
G01X374637Y1027009D02*
X372799Y1028056D01*
G01X380189Y1030198D02*
X378351Y1031245D01*
G01X378338Y1033387D02*
X376500Y1034434D01*
G01X374637Y1033387D02*
X372799Y1034434D01*
G01X372787Y1036576D02*
X370949Y1037623D01*
G01X380189Y1036576D02*
X378351Y1037623D01*
G01X378338Y1039765D02*
X376500Y1040812D01*
G01X374637Y1039765D02*
X372799Y1040812D01*
G01X372787Y1042954D02*
X370949Y1044001D01*
G01X367236Y1033387D02*
X365398Y1034434D01*
G01X367236Y1039765D02*
X365398Y1040812D01*
G01X380189Y1042954D02*
X378351Y1044001D01*
G01X372787Y1030198D02*
X370949Y1031245D01*
G01X380189Y1049332D02*
X378351Y1050379D01*
G01X374637Y1058899D02*
X372799Y1059946D01*
G01X378338Y1046143D02*
X376500Y1047190D01*
G01X372787Y1049332D02*
X370949Y1050379D01*
G01X374637Y1052521D02*
X372799Y1053568D01*
G01X367236Y1046143D02*
X365398Y1047190D01*
G01X367236Y1052521D02*
X365398Y1053568D01*
G01X372787Y1055710D02*
X370949Y1056757D01*
G01X374637Y1046143D02*
X372799Y1047190D01*
G01X378338Y1052521D02*
X376500Y1053568D01*
G01X374637Y1071655D02*
X372799Y1072702D01*
G01X372787Y1074844D02*
X370949Y1075891D01*
G01X380189Y1062088D02*
X378351Y1063135D01*
G01X372787Y1062088D02*
X370949Y1063135D01*
G01X378338Y1065277D02*
X376500Y1066324D01*
G01X367236Y1065277D02*
X365398Y1066324D01*
G01X380189Y1074844D02*
X378351Y1075891D01*
G01X378338Y1078033D02*
X376500Y1079080D01*
G01X374637Y1078033D02*
X372799Y1079080D01*
G01X380189Y1081222D02*
X378351Y1082269D01*
G01X372787Y1081222D02*
X370949Y1082269D01*
G01X378338Y1084411D02*
X376500Y1085458D01*
G01X367236Y1078033D02*
X365398Y1079080D01*
G01X367236Y1084411D02*
X365398Y1085458D01*
G01X372787Y1100356D02*
X370949Y1101403D01*
G01X378338Y1103545D02*
X376500Y1104592D01*
G01X374637Y1090789D02*
X372799Y1091836D01*
G01X380189Y1093978D02*
X378351Y1095025D01*
G01X372787Y1093978D02*
X370949Y1095025D01*
G01X378338Y1097167D02*
X376500Y1098214D01*
G01X374637Y1097167D02*
X372799Y1098214D01*
G01X380189Y1100356D02*
X378351Y1101403D01*
G01X367236Y1103545D02*
X365398Y1104592D01*
G01X367236Y1097167D02*
X365398Y1098214D01*
G01X374637Y1109923D02*
X372799Y1110970D01*
G01X380189Y1113112D02*
X378351Y1114159D01*
G01X372787Y1113112D02*
X370949Y1114159D01*
G01X378338Y1116301D02*
X376500Y1117348D01*
G01X374637Y1116301D02*
X372799Y1117348D01*
G01X372787Y1119490D02*
X370949Y1120537D01*
G01X367236Y1116301D02*
X365398Y1117348D01*
G01X380189Y1119490D02*
X378351Y1120537D01*
G01X378338Y1122679D02*
X376500Y1123726D01*
G01X374637Y1129057D02*
X372799Y1130103D01*
G01X380189Y1132246D02*
X378351Y1133293D01*
G01X372787Y1132246D02*
X370949Y1133293D01*
G01X367236Y1122679D02*
X365398Y1123726D01*
G01X378338Y1135434D02*
X376500Y1136481D01*
G01X374637Y1135434D02*
X372799Y1136481D01*
G01X380189Y1138623D02*
X378351Y1139670D01*
G01X372787Y1138623D02*
X370949Y1139670D01*
G01X378338Y1141812D02*
X376500Y1142859D01*
G01X374637Y1148190D02*
X372799Y1149237D01*
G01X367236Y1135434D02*
X365398Y1136481D01*
G01X367236Y1141812D02*
X365398Y1142859D01*
G01X376488Y1164135D02*
X374650Y1165182D01*
G01X380189Y1151379D02*
X378351Y1152426D01*
G01X372787Y1151379D02*
X370949Y1152426D01*
G01X378338Y1154568D02*
X376500Y1155615D01*
G01X367236Y1160946D02*
X365398Y1161993D01*
G01X369086Y1157757D02*
X367248Y1158804D01*
G01X380189Y1164135D02*
X378351Y1165182D01*
G01X369750Y1582600D02*
X366170Y1579020D01*
Y1576330D01*
X370170Y1572330D01*
X372740D01*
X373370Y1571700D01*
X376970D01*
X381390Y1567280D01*
X386193D01*
X387939Y1565534D01*
G01X380277Y1585203D02*
X379235D01*
X377150Y1583118D01*
Y1577153D01*
X376197Y1576200D01*
G01D02*
X372530D01*
X369750Y1578980D01*
Y1579400D01*
G01D02*
X368620D01*
X368200Y1578980D01*
Y1576870D01*
X370690Y1574380D01*
X374600D01*
X375340Y1573640D01*
X377440D01*
X381460Y1569620D01*
X385949D01*
X387156Y1568413D01*
X389276D01*
G01X419254Y1566828D02*
X418056Y1568026D01*
Y1573107D01*
X411842Y1579321D01*
X407622D01*
X402881Y1574580D01*
X399795D01*
X395167Y1569952D01*
X391303D01*
X390494Y1570761D01*
X386890D01*
X386691Y1570960D01*
X382650D01*
X378513Y1575097D01*
Y1582171D01*
X379577Y1583235D01*
X380277D01*
G01Y1587172D02*
X375513D01*
G01X369750Y1582600D02*
Y1583748D01*
X371803Y1585801D01*
X374144Y1585803D01*
X375513Y1587172D01*
G01X372950Y1639400D02*
X375050D01*
G01D02*
X377150D01*
G01Y1642600D02*
X375428D01*
X373512Y1644516D01*
X371823D01*
G01X377150Y1645800D02*
Y1646323D01*
X374962Y1648511D01*
G01X377150Y1649000D02*
X372953Y1653197D01*
G01X382992Y1674871D02*
X379662D01*
X373330Y1668539D01*
G01X387894Y135157D02*
X395654D01*
X395831Y134980D01*
G01X380447Y135157D02*
X387894D01*
G01X386703Y126912D02*
X386750Y126959D01*
X390859D01*
G01D02*
X391065Y126753D01*
X395048D01*
G01X402218Y157034D02*
X397197D01*
X395540Y155377D01*
X391635D01*
G01Y152818D02*
X393014D01*
X394091Y151741D01*
X397090D01*
G01X398599Y209695D02*
X392153D01*
G01X381013Y287370D02*
Y285713D01*
X381513Y285213D01*
X385040D01*
X389908Y280345D01*
X389912D01*
G01X384163Y287370D02*
X387667D01*
X390881Y284156D01*
G01X382323Y303760D02*
X389000D01*
G01X393925Y304000D02*
X389240D01*
X389000Y303760D01*
G01X382184Y476726D02*
X384625Y479167D01*
Y482395D01*
G01X382184Y466351D02*
Y468776D01*
G01X389743Y482395D02*
Y479963D01*
X392980Y476726D01*
X394184D01*
G01X393376Y472272D02*
X394500Y473396D01*
Y476410D01*
X394184Y476726D01*
G01X389743Y491057D02*
Y494285D01*
X392184Y496726D01*
G01X384625Y491057D02*
Y494285D01*
X382184Y496726D01*
G01X397184Y501526D02*
X395334D01*
X392184Y504676D01*
G01Y501526D02*
Y496726D01*
G01X382184Y504676D02*
Y507101D01*
G01Y501526D02*
Y496726D01*
G01X380771Y537213D02*
Y542138D01*
G01X387440Y539878D02*
X384031D01*
X381771Y542138D01*
X380771D01*
G01X390532Y571115D02*
Y576612D01*
X393393Y579473D01*
X393604D01*
G01D02*
X400898D01*
X406536Y573835D01*
Y573477D01*
X416874Y563139D01*
Y549036D01*
X422271Y543639D01*
Y540575D01*
G01X390532Y571115D02*
X393357D01*
X393481Y571239D01*
G01X382708Y880671D02*
X380870Y879624D01*
G01X386409Y880671D02*
X384571Y879624D01*
G01X382708Y874293D02*
X380870Y873246D01*
G01X393811Y874293D02*
X391973Y873246D01*
G01X393811Y880671D02*
X391973Y879624D01*
G01X390110Y938072D02*
X388272Y937025D01*
G01X393811Y938072D02*
X391973Y937025D01*
G01X386409Y938072D02*
X384571Y937025D01*
G01X385740Y1052521D02*
X383902Y1053568D01*
G01X394992Y1100356D02*
X393154Y1101403D01*
G01X391291Y1100356D02*
X389453Y1101403D01*
G01X387590Y1100356D02*
X385752Y1101403D01*
G01X406412Y1503100D02*
Y1503484D01*
X404448Y1505448D01*
X403724D01*
X400513Y1508659D01*
X397387D01*
X394345Y1505617D01*
X390830D01*
X389157Y1507290D01*
Y1509459D01*
G01X406412Y1506600D02*
X404507D01*
X401050Y1510057D01*
X396229D01*
X393357Y1512929D01*
X392240D01*
X391639Y1512328D01*
X391161D01*
X390338Y1511505D01*
G01X404766Y1526953D02*
X403400Y1525587D01*
X397898D01*
X394696Y1522385D01*
Y1521268D01*
X393235Y1519807D01*
G01Y1515083D02*
X394890Y1514073D01*
G01X393235Y1517445D02*
X394834Y1516336D01*
G01X393235Y1522169D02*
X397808Y1526742D01*
X401276D01*
X403493Y1528959D01*
X404227Y1529263D01*
X407456D01*
X409766Y1526953D01*
G01X393235Y1536343D02*
X394888D01*
X395185Y1536640D01*
G01X393235Y1533980D02*
X393795Y1534540D01*
X395185D01*
G01X393235Y1531618D02*
X395186D01*
G01X393235Y1529256D02*
X393793Y1528698D01*
X395097D01*
G01X404775Y1540976D02*
X404051D01*
X396155Y1533080D01*
X394352D01*
X394071Y1532799D01*
X391190D01*
G01X404775Y1535976D02*
X400776D01*
X396940Y1532140D01*
Y1530895D01*
X396203Y1530158D01*
X394322D01*
X394043Y1530437D01*
X391190D01*
G01X393881Y1540477D02*
X399035Y1545631D01*
X401171Y1550788D01*
Y1552457D01*
X399978Y1553650D01*
X399642D01*
G01X396442Y1558650D02*
X394302D01*
X393312Y1557660D01*
Y1545668D01*
X390338Y1542694D01*
Y1538431D01*
G01X396442Y1553650D02*
X395284D01*
X394732Y1553098D01*
Y1547146D01*
X395359Y1546519D01*
G01X389157Y1540477D02*
Y1543895D01*
X391892Y1546630D01*
Y1552684D01*
X390926Y1553650D01*
X390082D01*
G01X399642D02*
X398225Y1555067D01*
Y1560296D01*
X392826Y1565695D01*
X391175D01*
G01X396442Y1558650D02*
Y1559484D01*
X395151Y1560775D01*
X393261D01*
G01X390082Y1553650D02*
Y1556550D01*
G01D02*
X386822D01*
G01X389128Y1576969D02*
X388607Y1576448D01*
X385773D01*
G01X385317Y1581266D02*
X386227D01*
X389128Y1578365D01*
Y1576969D01*
G01X380277Y1581266D02*
Y1575233D01*
X383210Y1572300D01*
X387220D01*
X387410Y1572110D01*
X391122D01*
X391835Y1571397D01*
X394139D01*
X398715Y1575973D01*
X402378D01*
X407066Y1580661D01*
X413595D01*
X421277Y1572979D01*
Y1571923D01*
G01X385317Y1585203D02*
X387750D01*
X388445Y1585898D01*
G01X388784Y1581801D02*
X387350Y1583235D01*
X385317D01*
G01X391604Y1587172D02*
X393526Y1585250D01*
X394998D01*
X395009Y1585239D01*
G01X385317Y1587172D02*
X386499D01*
X387079Y1587752D01*
X391024D01*
X391604Y1587172D01*
G01X394000Y1621500D02*
X392462D01*
X389824Y1624138D01*
G01X389000Y1621500D02*
X387462D01*
X384824Y1624138D01*
G01X389824Y1627288D02*
Y1629713D01*
G01Y1634154D02*
Y1629713D01*
G01X384824Y1627288D02*
Y1629713D01*
G01Y1634154D02*
Y1629713D01*
G01X389824Y1655020D02*
Y1661545D01*
G01D02*
X388324D01*
X387324Y1662545D01*
Y1670120D01*
G01D02*
Y1674920D01*
G01X394824Y1661545D02*
X393324D01*
X392324Y1662545D01*
Y1670120D01*
G01D02*
Y1674920D01*
G01X414400Y110770D02*
X413230Y109600D01*
X409574D01*
X406243Y106269D01*
Y105651D01*
G01X395871Y138980D02*
Y135020D01*
X395831Y134980D01*
G01X399264Y123569D02*
Y121144D01*
G01X398981Y134980D02*
X398070Y135891D01*
Y144530D01*
X395590Y147010D01*
G01X395048Y126753D02*
X395082Y126719D01*
X399264D01*
G01X426767Y136802D02*
X425918D01*
X422270Y140450D01*
X410351D01*
X403881Y133980D01*
G01D02*
X399264Y129363D01*
Y126719D01*
G01X408716Y148300D02*
Y144300D01*
G01Y148300D02*
Y149476D01*
X412390Y153150D01*
X413416D01*
G01X412566Y144300D02*
X410436Y142170D01*
X408687D01*
X406000Y139483D01*
G01D02*
X402299D01*
X400632Y141150D01*
G01X410678Y159140D02*
X410015Y159803D01*
X404987D01*
X402218Y157034D01*
G01X397090Y151741D02*
X401681D01*
X402218Y152278D01*
G01X429326Y141330D02*
Y142514D01*
X418419Y153421D01*
Y179035D01*
X407299Y190155D01*
Y201500D01*
G01X403299Y209695D02*
X398599D01*
G01X403299Y214496D02*
Y209695D01*
G01X411299D02*
X407299D01*
G01Y206545D02*
X403299D01*
G01X407299Y201500D02*
Y206545D01*
G01X403299Y217646D02*
Y219441D01*
X402440Y220300D01*
X400000D01*
G01X407299Y214496D02*
X403299D01*
G01D02*
X399299D01*
G01X414365Y230323D02*
X411148D01*
X409046Y232425D01*
Y270250D01*
X438309Y299513D01*
Y327628D01*
X467545Y356864D01*
G01X397075Y304000D02*
X401425D01*
G01D02*
Y306425D01*
X403000Y308000D01*
X419617D01*
G01X402184Y476844D02*
Y483094D01*
G01Y472044D02*
Y476844D01*
G01X397184Y496726D02*
X399625Y494285D01*
Y490476D01*
G01X402184Y496726D02*
Y490476D01*
G01X404743Y483094D02*
Y485085D01*
X404153Y485675D01*
X402774D01*
X402184Y485085D01*
Y483094D01*
G01X397184Y501526D02*
Y496726D01*
G01X402184D02*
Y501526D01*
G01D02*
X406184D01*
G01X406512Y534213D02*
X412771D01*
G01X406512D02*
X404696D01*
X402771Y536138D01*
X396102D01*
G01X395157Y573815D02*
X398194Y570778D01*
X400673D01*
G01X397511Y874293D02*
X395673Y873246D01*
G01X404913Y874293D02*
X403075Y873246D01*
G01X397511Y880671D02*
X395673Y879624D01*
G01X401212Y887049D02*
X399374Y886002D01*
G01X397511Y887049D02*
X395673Y886002D01*
G01X397511Y938072D02*
X395673Y937025D01*
G01X404913Y938072D02*
X403075Y937025D01*
G01X406763Y934883D02*
X404925Y933836D01*
G01X410464Y934883D02*
X408626Y933836D01*
G01X401212Y938072D02*
X399374Y937025D01*
G01X408614Y938072D02*
X406776Y937025D01*
G01X409795Y1100356D02*
X407957Y1101403D01*
G01X406094Y1100356D02*
X404256Y1101403D01*
G01X398693Y1100356D02*
X396855Y1101403D01*
G01X407944Y1103545D02*
X406107Y1104592D01*
G01X402393Y1100356D02*
X400555Y1101403D01*
G01X406412Y1506600D02*
Y1506202D01*
X407614Y1505000D01*
X411612D01*
G01X406412Y1503100D02*
X413106D01*
X414416Y1501790D01*
X416896D01*
X419934Y1504828D01*
Y1508981D01*
G01X411062Y1521750D02*
X410538Y1521745D01*
X409584Y1522688D01*
Y1524012D01*
X409024Y1524572D01*
X406813Y1525488D01*
X406231D01*
X404766Y1526953D01*
G01X404775Y1535976D02*
X407311Y1533440D01*
X411400D01*
G01X409150Y1544200D02*
X407999D01*
X404775Y1540976D01*
G01X407198Y1564990D02*
X407600Y1564588D01*
Y1562850D01*
G01X405379Y1569803D02*
Y1566809D01*
X407198Y1564990D01*
G01X401249Y1564422D02*
Y1565988D01*
X400379Y1566858D01*
Y1569803D01*
G01X404200Y1562850D02*
X402628Y1564422D01*
X401249D01*
G01X406086Y1554940D02*
Y1557572D01*
X405758Y1557900D01*
G01D02*
X407600Y1559742D01*
Y1560750D01*
G01X404200D02*
Y1559299D01*
X402912Y1558011D01*
G01X402983Y1554979D02*
Y1557940D01*
X402912Y1558011D01*
G01X411320Y1553150D02*
X409389D01*
X408895Y1553644D01*
G01X396442Y1556550D02*
Y1553650D01*
G01X395009Y1587339D02*
X397197D01*
X398542Y1585994D01*
X417338D01*
X417758Y1585574D01*
Y1583988D01*
X423263Y1578483D01*
X438752D01*
X441931Y1581662D01*
G01X404669Y1594317D02*
X405379Y1593607D01*
Y1590275D01*
G01X403005Y1598560D02*
X404669Y1596896D01*
Y1594317D01*
G01X397180Y1603022D02*
X401547D01*
G01D02*
X402885D01*
X407667Y1607804D01*
X408943D01*
G01X397180Y1599022D02*
X398841Y1600683D01*
X405950D01*
X407611Y1599022D01*
G01D02*
X410067Y1601478D01*
X412370D01*
X413372Y1602480D01*
Y1603375D01*
G01X399000Y1624138D02*
Y1622880D01*
X400380Y1621500D01*
G01X394824Y1624138D02*
X399000D01*
G01X402969Y1625899D02*
X407100D01*
X407676Y1626475D01*
G01X402969Y1622749D02*
X405146D01*
X405747Y1623350D01*
G01X394824Y1627288D02*
Y1629713D01*
G01Y1634154D02*
Y1629713D01*
G01X407676Y1626475D02*
X410353D01*
X413372Y1623456D01*
Y1622075D01*
G01X407581Y1631219D02*
X410333Y1628467D01*
X412342D01*
G01X404431Y1631219D02*
Y1633909D01*
X404661Y1634139D01*
G01X423500Y1652500D02*
X418665Y1647665D01*
X415679D01*
X412514Y1644500D01*
X410075D01*
X409075Y1645500D01*
G01X405925Y1649500D02*
Y1645500D01*
G01Y1649500D02*
Y1653500D01*
G01D02*
Y1656484D01*
X406441Y1657000D01*
G01X394824Y1655020D02*
Y1661545D01*
G01X399824Y1655020D02*
Y1661545D01*
G01X406441Y1662260D02*
Y1657000D01*
G01Y1669740D02*
Y1672441D01*
X409000Y1675000D01*
Y1677425D01*
G01X399824Y1661545D02*
X398324D01*
X397324Y1662545D01*
Y1670120D01*
G01D02*
Y1674920D01*
G01X405000Y1677425D02*
Y1675000D01*
G01Y1677425D02*
X409000D01*
G01X427549Y60016D02*
X422649D01*
X422568Y59935D01*
G01X419418D02*
Y54769D01*
X419425Y54762D01*
G01D02*
X417025D01*
G01X419262Y66865D02*
X417049D01*
X416549Y66365D01*
G01X422412Y66865D02*
X426300D01*
X428149Y65016D01*
G01X419262Y71665D02*
X416549D01*
G01X422412D02*
X426935D01*
X427300Y71300D01*
G01X421655Y83352D02*
X418309Y86698D01*
Y95029D01*
X419900Y96620D01*
G01X420226Y99148D02*
X419826Y99548D01*
Y104148D01*
G01X419900Y96620D02*
X420226Y96946D01*
Y99148D01*
G01X426767Y113180D02*
X423530D01*
X422586Y112236D01*
X419826Y105573D01*
Y104148D01*
G01X416276Y99148D02*
Y103748D01*
X416676Y104148D01*
G01X414963Y92014D02*
X411976D01*
X411556Y92434D01*
Y95516D01*
X412660Y96620D01*
X414100D01*
G01D02*
X415680D01*
X416276Y97216D01*
Y99148D01*
G01X426767Y115149D02*
X421954D01*
X420723Y113918D01*
X416676Y104148D01*
G01X426767Y117117D02*
X420747D01*
X414400Y110770D01*
G01X413416Y153150D02*
Y149150D01*
X412566Y148300D01*
G01X431295Y141330D02*
Y142765D01*
X419299Y154761D01*
Y201000D01*
G01X415716Y148300D02*
Y144300D01*
G01D02*
X420516D01*
Y144245D01*
X420527Y144234D01*
G01X426767Y138771D02*
X425990D01*
X420527Y144234D01*
G01X435232Y141330D02*
Y142978D01*
X421059Y157151D01*
Y187505D01*
X435299Y201745D01*
G01X433263Y141330D02*
Y142956D01*
X420179Y156040D01*
Y188609D01*
X427299Y195729D01*
Y199500D01*
G01X437200Y141330D02*
Y143137D01*
X421939Y158398D01*
Y187139D01*
X427690Y192890D01*
X434444D01*
X443299Y201745D01*
G01X439169Y141330D02*
Y142591D01*
X422819Y158941D01*
Y186774D01*
X427085Y191040D01*
X440444D01*
X451224Y201820D01*
G01X419299Y209695D02*
Y212096D01*
G01X423299Y209695D02*
Y212096D01*
G01X427299Y206545D02*
X423299D01*
G01X415299Y209695D02*
X416605D01*
X417200Y210290D01*
Y213841D01*
X420000Y216641D01*
Y219940D01*
G01X415299Y206545D02*
X419299D01*
G01Y201000D02*
Y206545D01*
G01X411299Y212096D02*
Y209695D01*
G01X428899Y227764D02*
X425582D01*
X422936Y225118D01*
Y223501D01*
G01X422302Y214926D02*
X426869D01*
X427299Y214496D01*
G01X422302Y214926D02*
Y214400D01*
X422722Y213980D01*
X424940D01*
X427299Y211621D01*
Y209695D01*
G01X420000Y219940D02*
X417630D01*
X417300Y219610D01*
Y216497D01*
X415299Y214496D01*
G01X411299D02*
Y212096D01*
G01X417515Y230323D02*
X420115D01*
G01X428899D02*
X420115D01*
G01X414365Y226323D02*
Y230323D01*
G01X422615Y238001D02*
X428899D01*
G01X422615D02*
X420115Y240501D01*
G01X417515Y235442D02*
X420115D01*
G01X428899D02*
X420115D01*
G01X417515Y240501D02*
X420115D01*
G01X414365D02*
X411940D01*
G01X428899Y240953D02*
X425937D01*
X423583Y243307D01*
Y245868D01*
G01X424220Y253768D02*
X423823Y254165D01*
X418290D01*
G01Y250165D02*
Y254165D01*
G01X430520Y253768D02*
X424220D01*
G01X418290Y270165D02*
Y266165D01*
G01X424220Y263768D02*
X430520D01*
G01X418290Y266165D02*
X420687Y263768D01*
X424220D01*
G01Y258768D02*
X423617Y258165D01*
X418290D01*
G01Y262165D02*
Y258165D01*
G01X430520Y258768D02*
X424220D01*
G01X415984Y476767D02*
Y483017D01*
G01Y471967D02*
Y476767D01*
G01X410984Y496649D02*
X413425Y494208D01*
Y490399D01*
G01X415984Y496649D02*
Y490399D01*
G01X418543Y483017D02*
Y485008D01*
X417953Y485598D01*
X416574D01*
X415984Y485008D01*
Y483017D01*
G01X410984Y501449D02*
Y496649D01*
G01X415984D02*
Y501449D01*
G01D02*
X419984D01*
G01X412771Y534213D02*
X414696D01*
X416208Y532701D01*
X418531D01*
G01X416015Y874293D02*
X414177Y873246D01*
G01X412315Y938072D02*
X410477Y937025D01*
G01X411645Y1103545D02*
X409807Y1104592D01*
G01X413496Y1100356D02*
X411658Y1101403D01*
G01X411612Y1505000D02*
Y1505659D01*
X414934Y1508981D01*
G01X409766Y1526953D02*
X411564Y1528751D01*
X413509D01*
X414382Y1527878D01*
X415765Y1524538D01*
Y1522917D01*
X414598Y1521750D01*
X414262D01*
G01Y1518850D02*
Y1521750D01*
G01X411062Y1518850D02*
Y1521750D01*
G01X435513Y1531694D02*
X431511D01*
X429432Y1533773D01*
X426782D01*
X424906Y1531897D01*
Y1529452D01*
X422437Y1526983D01*
G01X411400Y1533440D02*
Y1533772D01*
X412318Y1534690D01*
Y1536932D01*
X411250Y1538000D01*
G01X424488Y1565400D02*
X425718Y1564170D01*
X426600D01*
G01X425374Y1569803D02*
X424488Y1568917D01*
Y1565400D01*
G01X415990Y1557310D02*
X415326Y1556646D01*
X413540D01*
G01X466050Y1576200D02*
X467590D01*
X468050Y1575740D01*
Y1574024D01*
X463052Y1569026D01*
X445501D01*
X441890Y1565415D01*
X441306D01*
X436357Y1560466D01*
Y1558754D01*
X432970Y1555367D01*
X420033D01*
X418090Y1557310D01*
G01X466050Y1579400D02*
X467730D01*
X469652Y1577478D01*
Y1573151D01*
X464086Y1567585D01*
X446098D01*
X441930Y1563417D01*
X441226D01*
X437751Y1559942D01*
Y1558114D01*
X433563Y1553926D01*
X419484D01*
X418620Y1554790D01*
X412730D01*
X412270Y1555250D01*
X411320D01*
G01X413299Y1633417D02*
X414907Y1631809D01*
Y1625838D01*
X417309Y1623436D01*
Y1622075D01*
G01X415340D02*
Y1623428D01*
X412342Y1626426D01*
Y1628467D01*
G01X412075Y1641000D02*
Y1637000D01*
G01D02*
Y1634641D01*
X413299Y1633417D01*
G01X413925Y1649500D02*
Y1649102D01*
X412000Y1647177D01*
G01X417075Y1657500D02*
Y1653500D01*
G01D02*
Y1649500D01*
G01X411559Y1669740D02*
Y1675984D01*
X413000Y1677425D01*
G01X417075Y1657500D02*
Y1660925D01*
X417000Y1661000D01*
G01D02*
X415740Y1662260D01*
X411559D01*
G01X417000Y1677425D02*
Y1675000D01*
G01X413000Y1677425D02*
X417000D01*
G01X435262Y60016D02*
X427549D01*
G01X428149Y65016D02*
X435262D01*
G01X427300Y71300D02*
X427410Y71410D01*
X428004D01*
X429398Y70016D01*
X435262D01*
G01X433673Y80275D02*
X429673D01*
G01X433673Y84125D02*
X431779D01*
X431359Y83705D01*
Y82589D01*
G01D02*
X431748Y82200D01*
X433253D01*
X433673Y81780D01*
Y80275D01*
G01X432200Y101800D02*
Y98552D01*
X435730Y95022D01*
Y89332D01*
X433673Y87275D01*
G01X442221Y100933D02*
Y99084D01*
X437565Y94428D01*
Y88383D01*
X438673Y87275D01*
G01X436482Y98172D02*
Y98101D01*
X436610Y97973D01*
Y88741D01*
X436162Y88293D01*
Y82786D01*
X438673Y80275D01*
G01X429326Y106684D02*
Y104674D01*
X432200Y101800D01*
G01X433685Y94232D02*
X429685D01*
G01X428085Y98885D02*
Y98835D01*
X429685Y97235D01*
Y94232D01*
G01X426767Y109243D02*
X426234D01*
X425580Y108589D01*
Y101340D01*
X428035Y98885D01*
X428085D01*
G01X439169Y106684D02*
Y104712D01*
X442221Y101660D01*
Y100933D01*
G01X437200Y106684D02*
Y105031D01*
X436482Y104313D01*
Y98172D01*
G01X441137Y141330D02*
Y143268D01*
X435383Y149022D01*
Y149854D01*
G01D02*
X437997Y152468D01*
Y153550D01*
G01Y160550D02*
Y160488D01*
X436103Y158594D01*
G01D02*
X437997Y156700D01*
G01X429997Y160550D02*
X433997D01*
G01X429200Y155890D02*
Y159753D01*
X429997Y160550D01*
G01X429200Y155890D02*
X433187D01*
X433997Y156700D01*
G01X437997Y153550D02*
X433997D01*
G01X439299Y209695D02*
Y210891D01*
X438200Y211990D01*
Y212096D01*
G01X435299Y209695D02*
X431299D01*
G01Y212095D02*
Y209695D01*
G01X439299Y206545D02*
X435299D01*
G01D02*
Y201745D01*
G01X427299Y199500D02*
Y206545D01*
G01X439299Y214496D02*
X435299D01*
G01X438200Y212096D02*
X439299Y213195D01*
Y214496D01*
G01X431299D02*
Y212095D01*
G01X428899Y232883D02*
X432769D01*
X433427Y233541D01*
Y237343D01*
X432769Y238001D01*
X428899D01*
G01X450992Y258768D02*
X441578D01*
X435710Y252900D01*
Y250340D01*
G01X429784Y482940D02*
Y476690D01*
G01Y471890D02*
Y476690D01*
G01Y496572D02*
Y490322D01*
G01X432343Y482940D02*
Y484931D01*
X431753Y485521D01*
X430374D01*
X429784Y484931D01*
Y482940D01*
G01X424784Y496572D02*
X427225Y494131D01*
Y490322D01*
G01X439500Y496575D02*
X429787D01*
X429784Y496572D01*
G01X424784Y501372D02*
Y496572D01*
G01X435700Y1157757D02*
X433862Y1158804D01*
G01X433850Y1160946D02*
X432012Y1161993D01*
G01X435700Y1151379D02*
X433862Y1152426D01*
G01X433850Y1154568D02*
X432012Y1155615D01*
G01X428299Y1157757D02*
X426461Y1158804D01*
G01X430149Y1154568D02*
X428311Y1155615D01*
G01X433461Y1518040D02*
X432188D01*
X431788Y1517640D01*
X430561D01*
G01X425571Y1520200D02*
X426151Y1519620D01*
X428316D01*
X429832Y1518992D01*
X430561Y1518263D01*
Y1517640D01*
G01X433461Y1518040D02*
Y1516839D01*
X434070Y1516230D01*
X438821D01*
X439596Y1517005D01*
Y1519121D01*
X440282Y1519807D01*
X443630D01*
G01X433461Y1514420D02*
X430441D01*
X430335Y1514314D01*
G01X443630Y1517445D02*
X442876D01*
X440234Y1514803D01*
Y1514248D01*
X438596Y1512610D01*
X434081D01*
X433461Y1513230D01*
Y1514420D01*
G01Y1510800D02*
X429561D01*
G01X424775Y1513907D02*
X426789D01*
X429561Y1511135D01*
Y1510800D01*
G01X433461D02*
Y1509522D01*
X434292Y1508691D01*
X438127D01*
X441245Y1511809D01*
Y1514568D01*
X442941Y1516264D01*
X445676D01*
G01X439935Y1532600D02*
X438530Y1534005D01*
Y1541641D01*
X445426Y1548537D01*
Y1551939D01*
X444477Y1552888D01*
X443810D01*
G01X445676Y1530437D02*
X438956D01*
X437699Y1531694D01*
X435513D01*
G01Y1533794D02*
Y1536744D01*
X437022Y1538253D01*
Y1543678D01*
X437736Y1544392D01*
G01X440610Y1552888D02*
X440198D01*
X436922Y1549612D01*
Y1545206D01*
X437736Y1544392D01*
G01X431923Y1565790D02*
X430303Y1564170D01*
X430000D01*
G01X430374Y1569803D02*
Y1567339D01*
X431923Y1565790D01*
G01X432051Y1560635D02*
X430616Y1562070D01*
X430000D01*
G01X429963Y1559247D02*
X430663D01*
X432051Y1560635D01*
G01X426850Y1559196D02*
X425506D01*
X424616Y1560086D01*
G01D02*
X426600Y1562070D01*
G01X451768Y1579149D02*
X450772D01*
X448498Y1581423D01*
X444963D01*
X442526Y1583860D01*
X435600D01*
X433440Y1581700D01*
G01X451768Y1581117D02*
X450960D01*
X449268Y1582809D01*
X445573D01*
X442730Y1585652D01*
X431113D01*
X427081Y1581620D01*
G01X429947Y1594398D02*
X431491Y1595942D01*
Y1596983D01*
G01X430374Y1590275D02*
X429947Y1590702D01*
Y1594398D01*
G01X425183Y1603375D02*
Y1602817D01*
X426329Y1601671D01*
X431682D01*
G01D02*
X436954D01*
X438425Y1600200D01*
G01X433795Y1606554D02*
X432545Y1607804D01*
X427643D01*
G01X438425Y1604200D02*
X436149D01*
X433795Y1606554D01*
G01X427643Y1619615D02*
X431015D01*
X433012Y1621612D01*
G01X428500Y1630500D02*
Y1625800D01*
X425183Y1622483D01*
Y1622075D01*
G01X428500Y1633925D02*
Y1630500D01*
G01X442673Y87275D02*
X440186Y89762D01*
Y93386D01*
G01X443106Y106684D02*
Y104004D01*
X444431Y102679D01*
Y98020D01*
X440186Y93775D01*
Y93386D01*
G01X445074Y141330D02*
Y143414D01*
X454997Y153337D01*
Y155750D01*
G01X441997Y160550D02*
Y153778D01*
X441240Y153021D01*
Y149323D01*
G01D02*
X441737D01*
X443600Y151186D01*
Y155880D01*
X444420Y156700D01*
X445997D01*
G01Y153550D02*
Y151504D01*
X446797Y150704D01*
Y148500D01*
G01X443106Y141330D02*
Y144106D01*
X446797Y147797D01*
Y148500D01*
G01X449011Y141330D02*
Y142779D01*
X458962Y152730D01*
X465977D01*
X468997Y155750D01*
G01X450980Y141330D02*
Y142596D01*
X459726Y151342D01*
X469589D01*
X473997Y155750D01*
G01X447043Y141330D02*
Y143363D01*
X457900Y154220D01*
X460467D01*
X461997Y155750D01*
G01X449997Y160550D02*
X449929D01*
X448038Y158659D01*
G01D02*
X449997Y156700D01*
G01X453997Y160550D02*
X457997D01*
G01X441997D02*
X445997D01*
G01Y153550D02*
X449997D01*
G01X441997Y170701D02*
X444088Y168610D01*
X468390D01*
X469997Y167003D01*
Y163700D01*
G01X449997Y170701D02*
X469660D01*
X473997Y166364D01*
Y163700D01*
G01X448499Y212036D02*
X447299Y210836D01*
Y209695D01*
G01X459174Y204620D02*
X456374D01*
X454374Y206620D01*
G01X443299Y212095D02*
Y209695D01*
G01X447299Y206545D02*
X443299D01*
G01D02*
Y201745D01*
G01X451224Y210620D02*
Y206620D01*
G01D02*
Y201820D01*
G01X451931Y222253D02*
X456032D01*
X457931Y220354D01*
Y218253D01*
G01X451299Y214496D02*
X447299D01*
G01D02*
Y213236D01*
X448499Y212036D01*
G01X454374Y210620D02*
X455374Y209620D01*
X459174D01*
G01X443299Y214496D02*
Y212095D01*
G01X460567Y235442D02*
X451931D01*
G01Y227764D02*
X456231D01*
G01X451931Y238001D02*
X447318D01*
X446501Y237184D01*
Y228581D01*
X447318Y227764D01*
X451931D01*
G01X456231Y232883D02*
X451931D01*
G01X460624Y230323D02*
X451931D01*
G01X460567Y225205D02*
X451931D01*
G01X450992Y253768D02*
X444138D01*
X440710Y250340D01*
G01X450992Y248768D02*
X447282D01*
X446710Y249340D01*
G01X468971Y247764D02*
Y260170D01*
X453831Y275310D01*
X451959D01*
X445866Y281403D01*
Y321056D01*
X453851Y329041D01*
X462851D01*
X487827Y354017D01*
G01X439500Y493425D02*
Y489575D01*
G01X453472Y489760D02*
X453466Y489766D01*
X447691D01*
G01D02*
X447500Y489575D01*
X443500D01*
G01X439500D02*
X443500D01*
G01X453023Y874293D02*
X454861Y873246D01*
G01X447472Y877482D02*
X449310Y876435D01*
G01X449322Y880671D02*
X451160Y879624D01*
G01X453023Y880671D02*
X454861Y879624D01*
G01X449322Y874293D02*
X451160Y873246D01*
G01X445622Y887049D02*
X447460Y886002D01*
G01X447472Y883860D02*
X449310Y882813D01*
G01X448653Y1160946D02*
X450491Y1161993D01*
G01X446803Y1151379D02*
X444880D01*
X443271Y1152988D01*
Y1170288D01*
X440678Y1172881D01*
Y1184903D01*
X521361Y1265586D01*
X555091D01*
G01X450504Y1164135D02*
X452341Y1165182D01*
G01X446803Y1157757D02*
X448641Y1158804D01*
G01X454204Y1157757D02*
X456042Y1158804D01*
G01X450504Y1157757D02*
X452341Y1158804D01*
G01X454204Y1164135D02*
X456042Y1165182D01*
G01X448653Y1154568D02*
X450491Y1155615D01*
G01X442918Y1513218D02*
X444992D01*
X445676Y1513902D01*
G01Y1520988D02*
X442284D01*
X441660Y1521612D01*
G01X441259Y1518121D02*
X442254D01*
X442759Y1518626D01*
X445676D01*
G01Y1535162D02*
X442242D01*
X441706Y1535698D01*
G01X443630Y1536343D02*
X442075Y1537898D01*
X441706D01*
G01X453470Y1555409D02*
X450618Y1552557D01*
Y1551320D01*
X439959Y1540661D01*
Y1535322D01*
X442482Y1532799D01*
X445676D01*
G01X439935Y1532600D02*
X440917Y1531618D01*
X443630D01*
G01X457317Y1555409D02*
X453470D01*
G01X449597Y1557039D02*
X451840D01*
X453470Y1555409D01*
G01X446240Y1555808D02*
X445478D01*
X443810Y1554140D01*
Y1552888D01*
G01X443040Y1555808D02*
X441868D01*
X440610Y1554550D01*
Y1552888D01*
G01X446810Y1565020D02*
X448340Y1563490D01*
X462490D01*
X471840Y1572840D01*
Y1580050D01*
X465160Y1586730D01*
X462200D01*
X459162Y1583692D01*
X458470Y1582019D01*
X457568Y1581117D01*
X456808D01*
G01X446910Y1562098D02*
X463067D01*
X473232Y1572263D01*
Y1580627D01*
X465737Y1588122D01*
X461041D01*
X457860Y1584941D01*
Y1584138D01*
X456808Y1583086D01*
G01X445567Y1579843D02*
X443750D01*
X441931Y1581662D01*
G01X446959Y1576531D02*
X450366D01*
X451015Y1577180D01*
X451768D01*
G01X446959Y1576531D02*
Y1578236D01*
X447667Y1578944D01*
Y1579843D01*
G01X446807Y1585178D02*
X446218Y1585767D01*
Y1588417D01*
G01X451768Y1583086D02*
X451716D01*
X450239Y1584563D01*
X447422D01*
X446807Y1585178D01*
G01X449760Y1632441D02*
X451521D01*
X452000Y1632920D01*
Y1634500D01*
X451500Y1635000D01*
X449760D01*
G01X443594Y1644452D02*
Y1640854D01*
G01D02*
X445963Y1638485D01*
X447431D01*
X448013Y1637903D01*
Y1635500D01*
X448513Y1635000D01*
X449760D01*
G01X457240D02*
X455500D01*
X454500Y1636000D01*
Y1641575D01*
X453085Y1643858D01*
G01D02*
X448125D01*
X447576Y1644407D01*
G01D02*
X450547Y1647378D01*
Y1649111D01*
X451147Y1649711D01*
X453075Y1652575D01*
X459500Y1659000D01*
G01X456128Y60016D02*
X464249D01*
G01D02*
X472265D01*
X472278Y60029D01*
G01X456128Y55016D02*
X466449D01*
G01D02*
X472089D01*
X472208Y55135D01*
G01X456128Y65016D02*
X465849D01*
G01D02*
X472237D01*
X472278Y64975D01*
G01X465687Y105944D02*
X468656D01*
X471577Y103023D01*
Y102547D01*
X473550Y100574D01*
G01X461413Y109243D02*
X461977D01*
X462742Y108478D01*
Y105622D01*
X467495Y100869D01*
X469874D01*
G01X473550Y90574D02*
X472156D01*
X471200Y91530D01*
Y93400D01*
X468699Y95901D01*
X466396D01*
G01X458854Y106684D02*
Y105494D01*
X465448Y98900D01*
Y96849D01*
X466396Y95901D01*
G01X461413Y111212D02*
X463388D01*
X464657Y109943D01*
Y106974D01*
X465687Y105944D01*
G01X473550Y110574D02*
X471626D01*
X470939Y111261D01*
Y113661D01*
X466600Y118000D01*
G01X461413Y121054D02*
X463546D01*
X466600Y118000D01*
G01X473550Y105574D02*
Y106809D01*
X468348Y112011D01*
G01X461413Y117117D02*
X462483D01*
X467589Y112011D01*
X468348D01*
G01X473615Y115644D02*
Y115985D01*
X466680Y122920D01*
Y124253D01*
G01X461413Y134834D02*
X464766D01*
X466600Y133000D01*
G01X473615Y119644D02*
Y120832D01*
X467150Y127297D01*
Y132450D01*
X466600Y133000D01*
G01X473615Y123644D02*
X472653D01*
X469020Y127277D01*
Y135580D01*
X466600Y138000D01*
G01X461413Y130897D02*
X463204D01*
X465427Y128674D01*
Y125435D01*
X466609Y124253D01*
X466680D01*
G01X454917Y141330D02*
Y143703D01*
X461086Y149872D01*
X473119D01*
X478997Y155750D01*
G01X462637Y146170D02*
X466380D01*
X466600Y145950D01*
G01X458854Y141330D02*
Y142796D01*
X462228Y146170D01*
X462637D01*
G01X456885Y141330D02*
Y143767D01*
X461602Y148484D01*
X475513D01*
X482779Y155750D01*
X485997D01*
G01X461413Y136802D02*
X465402D01*
X466600Y138000D01*
G01X457997Y160550D02*
Y158750D01*
X454997Y155750D01*
G01X469997Y160550D02*
Y156750D01*
X468997Y155750D01*
G01X461997Y160550D02*
X465997D01*
G01X461997D02*
Y155750D01*
G01X459174Y209620D02*
X464424D01*
X465424Y210620D01*
G01Y206620D02*
X463424Y204620D01*
X459174D01*
G01X471371Y222764D02*
X468971D01*
G01X457931Y218253D02*
X461931D01*
G01D02*
X464440D01*
G01X460567Y225205D02*
X463008Y222764D01*
X465821D01*
G01X460567Y235442D02*
Y237317D01*
X463014Y239764D01*
X465821D01*
G01X468971Y243764D02*
Y239764D01*
G01X456231Y227764D02*
X465821D01*
G01X471371D02*
X468971D01*
G01X465821Y231764D02*
Y235764D01*
G01Y231764D02*
X464740D01*
X463621Y232883D01*
X456231D01*
G01X468971Y243764D02*
Y247764D01*
G01X460425Y880671D02*
X462263Y879624D01*
G01X456724Y880671D02*
X458562Y879624D01*
G01X456724Y874293D02*
X458562Y873246D01*
G01X460425Y874293D02*
X462263Y873246D01*
G01X464126Y880671D02*
X465964Y879624D01*
G01X464126Y874293D02*
X465964Y873246D01*
G01X458574Y883860D02*
X460412Y882813D01*
G01X462275Y883860D02*
X464113Y882813D01*
G01X467826Y887049D02*
X469664Y886002D01*
G01X460425Y887049D02*
X462263Y886002D01*
G01X456724Y887049D02*
X458562Y886002D01*
G01X454874Y883860D02*
X456712Y882813D01*
G01X464126Y931694D02*
X465964Y930647D01*
G01X467826Y938072D02*
X469664Y937025D01*
G01X469007Y1100356D02*
X470845Y1101403D01*
G01X465307Y1164135D02*
X467145Y1165182D01*
G01X457905Y1164135D02*
X459743Y1165182D01*
G01X456055Y1154568D02*
X457893Y1155615D01*
G01X459755Y1160946D02*
X461593Y1161993D01*
G01X459755Y1154568D02*
X461593Y1155615D01*
G01X461606Y1151379D02*
X463444Y1152426D01*
G01X461606Y1157757D02*
X463444Y1158804D01*
G01X465307Y1157757D02*
X467145Y1158804D01*
G01X467157Y1154568D02*
X468995Y1155615D01*
G01X469007Y1151379D02*
X470845Y1152426D01*
G01X461606Y1164135D02*
X463444Y1165182D01*
G01X459673Y1572604D02*
Y1575991D01*
X458484Y1577180D01*
X456808D01*
G01X466050Y1576200D02*
Y1575825D01*
X462829Y1572604D01*
X459673D01*
G01X456808Y1579149D02*
X457560D01*
X459689Y1581278D01*
X460404Y1583004D01*
X461620Y1584220D01*
X463581D01*
G01D02*
X466050Y1581751D01*
Y1579400D01*
G01X457240Y1637559D02*
Y1641261D01*
X457000Y1641501D01*
Y1643925D01*
G01X461000D02*
Y1643042D01*
X462753Y1641289D01*
G01X457000Y1643925D02*
X461000D01*
G01X465000Y1647425D02*
X470575D01*
X473000Y1645000D01*
G01X465000Y1647425D02*
Y1644000D01*
G01X470441Y1650740D02*
Y1653134D01*
X468075Y1655500D01*
G01Y1659500D02*
Y1655500D01*
G01Y1668000D02*
X471575Y1664500D01*
X476500D01*
X477000Y1664000D01*
X479690D01*
X483500Y1660190D01*
Y1658500D01*
G01X464925Y1668000D02*
Y1672000D01*
G01X468075Y1659500D02*
Y1662500D01*
G01X464925Y1672000D02*
Y1676000D01*
G01X464500Y1679774D02*
X467750Y1683024D01*
Y1684738D01*
G01X464925Y1676000D02*
X464500Y1676425D01*
Y1679774D01*
G01X467750Y1692218D02*
Y1694251D01*
X468575Y1695076D01*
Y1697000D01*
G01D02*
Y1701000D01*
G01D02*
Y1704000D01*
G01X472425Y1706500D02*
X466000D01*
X465000Y1705500D01*
G01X467416Y1720053D02*
Y1719417D01*
X463002Y1715003D01*
Y1712998D01*
X464500Y1711500D01*
G01X468575Y1733500D02*
Y1731000D01*
G01Y1733500D02*
X472425D01*
G01X472278Y60029D02*
Y61899D01*
X472949Y62570D01*
X483343D01*
X485808Y60105D01*
G01X472208Y55135D02*
Y56809D01*
X472628Y57229D01*
X485548D01*
X485968Y56809D01*
Y55095D01*
G01X472278Y64975D02*
Y67599D01*
X473649Y68970D01*
X483849D01*
X485698Y67121D01*
Y64965D01*
G01X473550Y95574D02*
X472183D01*
X471506Y96251D01*
Y99237D01*
X469874Y100869D01*
G01X477997Y160550D02*
X481997D01*
G01X477997D02*
Y156750D01*
X478997Y155750D01*
G01X473997Y160550D02*
Y155750D01*
G01X512969Y160328D02*
Y164147D01*
X511051Y166065D01*
X507135D01*
X483800Y189400D01*
G01X511394Y160328D02*
Y163494D01*
X510398Y164490D01*
X506110D01*
X480200Y190400D01*
Y191900D01*
G01X479870Y270400D02*
X476260Y266790D01*
Y223010D01*
X472430Y219180D01*
Y208041D01*
X473911Y206560D01*
X475435D01*
G01Y209710D02*
Y214842D01*
X475578Y214985D01*
G01X487620Y270400D02*
X478370Y261150D01*
Y226810D01*
X481211Y223969D01*
Y217227D01*
G01X475578Y214985D02*
X476245Y215652D01*
X481211D01*
G01X486328Y206827D02*
X489707D01*
X496970Y214090D01*
Y225580D01*
X492640Y229910D01*
X482570D01*
X480817Y231663D01*
Y237685D01*
X494693Y251561D01*
X576571D01*
X577949Y252939D01*
Y257171D01*
G01X474070Y295282D02*
X473282D01*
X471060Y293060D01*
X470243Y291088D01*
Y285693D01*
G01X485962Y290679D02*
Y291003D01*
X484463Y292502D01*
Y295561D01*
X482773Y297251D01*
X481156D01*
G01X481550Y303156D02*
X482156D01*
X484063Y305063D01*
Y305669D01*
G01D02*
Y308397D01*
G01X482629Y874293D02*
X484467Y873246D01*
G01X471527Y874293D02*
X473365Y873246D01*
G01X475228Y874293D02*
X477066Y873246D01*
G01X482629Y880671D02*
X484467Y879624D01*
G01X475228Y880671D02*
X477066Y879624D01*
G01X471527Y880671D02*
X473365Y879624D01*
G01X482629Y887049D02*
X484467Y886002D01*
G01X478929Y887049D02*
X480767Y886002D01*
G01X471527Y887049D02*
X473365Y886002D01*
G01X475228Y938072D02*
X477066Y937025D01*
G01X478929Y938072D02*
X480767Y937025D01*
G01X473378Y934883D02*
X475215Y933836D01*
G01X469677Y934883D02*
X471515Y933836D01*
G01X482629Y938072D02*
X484467Y937025D01*
G01X471527Y938072D02*
X473365Y937025D01*
G01X476409Y1100356D02*
X478247Y1101403D01*
G01X483811Y1100356D02*
X485649Y1101403D01*
G01X470858Y1103545D02*
X472696Y1104592D01*
G01X480110Y1100356D02*
X481948Y1101403D01*
G01X474559Y1103545D02*
X476397Y1104592D01*
G01X472708Y1100356D02*
X474546Y1101403D01*
G01X481960Y1154568D02*
X483798Y1155615D01*
G01X480110Y1164135D02*
X481948Y1165182D01*
G01X481960Y1160946D02*
X483798Y1161993D01*
G01X483811Y1157757D02*
X485649Y1158804D01*
G01X470858Y1154568D02*
X472696Y1155615D01*
G01X480110Y1151379D02*
X481948Y1152426D01*
G01X483811Y1164135D02*
X485649Y1165182D01*
G01X476409Y1157757D02*
X478247Y1158804D01*
G01X472708Y1157757D02*
X474546Y1158804D01*
G01X476409Y1164135D02*
X478247Y1165182D01*
G01X478259Y1154568D02*
X480097Y1155615D01*
G01X472708Y1164135D02*
X474546Y1165182D01*
G01X470858Y1160946D02*
X472696Y1161993D01*
G01X475559Y1643260D02*
Y1644941D01*
X475000Y1645500D01*
X473500D01*
X473000Y1645000D01*
G01D02*
Y1643260D01*
G01X472425Y1659500D02*
Y1655500D01*
G01X473000Y1650740D02*
Y1652501D01*
X472425Y1653076D01*
Y1655500D01*
G01X479500Y1666500D02*
X477000D01*
X476500Y1666000D01*
X472925D01*
X472425Y1666500D01*
Y1668000D01*
G01X475575Y1672000D02*
Y1668000D01*
G01X472425Y1659500D02*
Y1661425D01*
X473500Y1662500D01*
G01X475575Y1676000D02*
Y1672000D01*
G01Y1676000D02*
X477856Y1678281D01*
Y1682741D01*
G01D02*
X475859Y1684738D01*
X472868D01*
G01Y1692218D02*
Y1694633D01*
X472425Y1695076D01*
Y1697000D01*
G01Y1701000D02*
Y1697000D01*
G01Y1701000D02*
Y1702425D01*
X474000Y1704000D01*
G01X475575Y1706500D02*
X479000D01*
G01D02*
X485000Y1712500D01*
Y1724134D01*
X495078Y1734212D01*
G01X472534Y1720053D02*
Y1714609D01*
X472425Y1714500D01*
G01D02*
Y1710500D01*
G01D02*
Y1706500D01*
G01Y1733500D02*
Y1730609D01*
X472534Y1730500D01*
Y1727533D01*
G01X493051Y109959D02*
X491807D01*
X491251Y110515D01*
Y112249D01*
X491671Y112669D01*
X496174D01*
X497569Y111274D01*
X498385D01*
G01X502750Y111276D02*
X502748Y111274D01*
X498385D01*
G01X498314Y115343D02*
X497504Y114533D01*
X489659D01*
X486949Y117243D01*
G01X498314Y115343D02*
X499756D01*
X500674Y116261D01*
G01X485997Y163700D02*
X485260Y164437D01*
Y168390D01*
G01X489997Y160550D02*
X485997D01*
G01D02*
Y155750D01*
G01X502204Y179084D02*
X498006D01*
X492257Y184833D01*
Y189516D01*
G01X489922Y167625D02*
Y171625D01*
G01X485260Y168390D02*
X487521D01*
X488286Y167625D01*
X489922D01*
G01X489107Y189516D02*
X486682D01*
G01X492257Y193516D02*
Y197516D01*
G01Y193516D02*
Y189516D01*
G01X485541Y212896D02*
Y210214D01*
X486328Y209427D01*
Y206827D01*
G01X501201Y205285D02*
X497086D01*
X496831Y205030D01*
G01X492257Y197516D02*
Y201516D01*
G01X491635Y225970D02*
Y219127D01*
X489735Y217227D01*
X488297D01*
G01X494144Y221370D02*
Y218802D01*
G01X491635Y215652D02*
X494144D01*
G01X488297D02*
X491635D01*
G01X497609Y233000D02*
X500209D01*
G01X489259D02*
X491859D01*
G01X494459D02*
X491859D01*
G01X500209Y238119D02*
X497609D01*
G01Y243178D02*
X500114D01*
X500119Y243173D01*
G01X494459Y243178D02*
X491639D01*
X491577Y243240D01*
G01X487107Y288304D02*
Y289534D01*
X485962Y290679D01*
G01X501500Y422575D02*
X495830D01*
X495740Y422665D01*
G01X570216Y772262D02*
Y775135D01*
X523248Y822103D01*
Y833253D01*
X529895Y849301D01*
Y854114D01*
X524819Y859190D01*
X502169D01*
X493732Y867627D01*
Y874293D01*
G01X575216Y772262D02*
Y774078D01*
X525125Y824169D01*
Y833157D01*
X531665Y848946D01*
Y857897D01*
X528502Y861060D01*
X503399D01*
X497433Y867026D01*
Y874293D01*
G01Y880671D02*
X499271Y879624D01*
G01X486330Y874293D02*
X488168Y873246D01*
G01X486330Y880671D02*
X488168Y879624D01*
G01X493732Y880671D02*
X495570Y879624D01*
G01X493732Y887049D02*
X495570Y886002D01*
G01X490031Y887049D02*
X491869Y886002D01*
G01X495582Y883860D02*
X497420Y882813D01*
G01X486330Y938072D02*
X488168Y937025D01*
G01X490031Y938072D02*
X491869Y937025D01*
G01X493732Y938072D02*
X495570Y937025D01*
G01X494913Y1049332D02*
X496751Y1050379D01*
G01X491212Y1100356D02*
X493050Y1101403D01*
G01X487511Y1100356D02*
X489349Y1101403D01*
G01X494913Y1164135D02*
X496751Y1165182D01*
G01X494913Y1157757D02*
X496751Y1158804D01*
G01X487511Y1157757D02*
X489349Y1158804D01*
G01X489362Y1154568D02*
X491200Y1155615D01*
G01X491212Y1151379D02*
X493050Y1152426D01*
G01X493063Y1160946D02*
X494901Y1161993D01*
G01X493063Y1154568D02*
X494901Y1155615D01*
G01X498614Y1157757D02*
X500452Y1158804D01*
G01X498614Y1164135D02*
X500452Y1165182D01*
G01X487511Y1164135D02*
X489349Y1165182D01*
G01X513177Y65157D02*
Y71767D01*
X510477Y74467D01*
Y77767D01*
G01X515539Y85717D02*
X505399D01*
X504796Y86320D01*
G01X514544Y130014D02*
Y125118D01*
X509351Y119925D01*
Y116151D01*
X504476Y111276D01*
X502750D01*
G01X512969Y130014D02*
Y125514D01*
X503716Y116261D01*
X500674D01*
G01X514544Y160328D02*
Y164616D01*
X502204Y176956D01*
Y179084D01*
G01X507204D02*
X505616D01*
X500807Y183893D01*
Y185516D01*
G01X516119Y160328D02*
Y165152D01*
X515470Y165801D01*
Y170818D01*
X507204Y179084D01*
G01X512204D02*
X509082Y182206D01*
Y185516D01*
G01X517694Y160328D02*
Y165626D01*
X516999Y166321D01*
Y174289D01*
X512204Y179084D01*
G01X500807Y197516D02*
Y193516D01*
G01D02*
X504662D01*
X505570Y194424D01*
X510786D01*
G01X525568Y160328D02*
Y176210D01*
X512009Y189769D01*
Y193201D01*
X510786Y194424D01*
G01X500807Y189516D02*
X505662D01*
X506462Y190316D01*
G01X522418Y160328D02*
Y162824D01*
X523428Y163834D01*
Y175772D01*
X508884Y190316D01*
X506462D01*
G01X504351Y205285D02*
Y202776D01*
G01Y205285D02*
Y209285D01*
G01X510501Y209742D02*
Y208304D01*
X509823Y207626D01*
X508184D01*
X506525Y209285D01*
X504351D01*
G01X508238Y199506D02*
Y202367D01*
X508201Y202404D01*
G01X512076Y206404D02*
Y203129D01*
X511351Y202404D01*
G01X512076Y209742D02*
Y206404D01*
G01X501201Y220166D02*
X499380Y221987D01*
Y222510D01*
G01X512076Y216828D02*
Y220827D01*
X511684Y221219D01*
G01X508001Y220166D02*
X508601D01*
X510501Y218266D01*
Y216828D01*
G01X504351Y220166D02*
X508001D01*
G01X506945Y233000D02*
X500209D01*
G01X506945Y235560D02*
X510815D01*
X511473Y236218D01*
Y240020D01*
X510815Y240678D01*
X506945D01*
G01Y238119D02*
X500209D01*
G01X506945Y230441D02*
X502769D01*
X500209Y227881D01*
G01X506945Y240678D02*
X504722D01*
X502227Y243173D01*
X500119D01*
G01X506945Y243630D02*
X508655D01*
X510692Y245667D01*
Y248651D01*
G01X518500Y432575D02*
X512000D01*
G01D02*
Y435685D01*
X513193Y436878D01*
G01X501500Y422575D02*
Y426425D01*
G01D02*
X505500Y430425D01*
Y443000D01*
X508240Y445740D01*
X511601D01*
G01X513193Y436878D02*
X514575Y438260D01*
X519185D01*
G01Y445740D02*
X511601D01*
G01X508535Y880671D02*
X510373Y879624D01*
G01X512236Y880671D02*
X514074Y879624D01*
G01X508535Y887049D02*
X510373Y886002D01*
G01X502984Y890238D02*
X504822Y889191D01*
G01X506685Y890238D02*
X508523Y889191D01*
G01X501133Y893427D02*
X502971Y892380D01*
G01X499283Y883860D02*
X501121Y882813D01*
G01X506685Y909371D02*
X508523Y908325D01*
G01X508535Y899805D02*
X510373Y898758D01*
G01X502984Y902994D02*
X504822Y901947D01*
G01X506685Y902994D02*
X508523Y901947D01*
G01X501133Y906182D02*
X502971Y905135D01*
G01X508535Y906182D02*
X510373Y905135D01*
G01X502984Y909371D02*
X504822Y908325D01*
G01X501133Y912560D02*
X502971Y911513D01*
G01X508535Y918938D02*
X510373Y917891D01*
G01X502984Y922127D02*
X504822Y921080D01*
G01X506685Y922127D02*
X508523Y921080D01*
G01X501133Y925316D02*
X502971Y924269D01*
G01X508535Y925316D02*
X510373Y924269D01*
G01X502984Y928505D02*
X504822Y927458D01*
G01X506685Y928505D02*
X508523Y927458D01*
G01X501133Y931694D02*
X502971Y930647D01*
G01X508535Y938072D02*
X510373Y937025D01*
G01X502984Y941261D02*
X504822Y940214D01*
G01X506685Y941261D02*
X508523Y940214D01*
G01X501133Y944450D02*
X502971Y943403D01*
G01X508535Y944450D02*
X510373Y943403D01*
G01X502984Y947639D02*
X504822Y946592D01*
G01X506685Y947639D02*
X508523Y946592D01*
G01X501133Y950828D02*
X502971Y949781D01*
G01X508535Y963584D02*
X510373Y962537D01*
G01X502984Y966773D02*
X504822Y965726D01*
G01X506685Y966773D02*
X508523Y965726D01*
G01X501133Y969962D02*
X502971Y968915D01*
G01X508535Y957206D02*
X510373Y956159D01*
G01X502984Y960395D02*
X504822Y959348D01*
G01X506685Y960395D02*
X508523Y959348D01*
G01X501133Y963584D02*
X502971Y962537D01*
G01X502984Y985907D02*
X504822Y984860D01*
G01X508535Y976340D02*
X510373Y975293D01*
G01X502984Y979529D02*
X504822Y978482D01*
G01X506685Y979529D02*
X508523Y978482D01*
G01X501133Y982718D02*
X502971Y981671D01*
G01X501133Y989096D02*
X502971Y988049D01*
G01X508535Y995474D02*
X510373Y994427D01*
G01X506685Y998663D02*
X508523Y997616D01*
G01X502984Y998663D02*
X504822Y997616D01*
G01X508535Y989096D02*
X510373Y988049D01*
G01X502984Y992285D02*
X504822Y991238D01*
G01X501133Y995474D02*
X502971Y994427D01*
G01X506685Y992285D02*
X508523Y991238D01*
G01X501133Y1001852D02*
X502971Y1000805D01*
G01X508535Y1001852D02*
X510373Y1000805D01*
G01X506685Y1005041D02*
X508523Y1003994D01*
G01X502984Y1005041D02*
X504822Y1003994D01*
G01X501133Y1008230D02*
X502971Y1007183D01*
G01X502984Y1011419D02*
X504822Y1010372D01*
G01X504165Y1027009D02*
X506003Y1028056D01*
G01X507866Y1027009D02*
X509704Y1028056D01*
G01X502315Y1030198D02*
X504153Y1031245D01*
G01X504165Y1033387D02*
X506003Y1034434D01*
G01X507866Y1033387D02*
X509704Y1034434D01*
G01X509716Y1036576D02*
X511554Y1037623D01*
G01X502315Y1036576D02*
X504153Y1037623D01*
G01X504165Y1039765D02*
X506003Y1040812D01*
G01X507866Y1039765D02*
X509704Y1040812D01*
G01X502315Y1042954D02*
X504153Y1044001D01*
G01X509716Y1042954D02*
X511554Y1044001D01*
G01X509716Y1030198D02*
X511554Y1031245D01*
G01X502315Y1049332D02*
X504153Y1050379D01*
G01X507866Y1058899D02*
X509704Y1059946D01*
G01X504165Y1046143D02*
X506003Y1047190D01*
G01X509716Y1049332D02*
X511554Y1050379D01*
G01X507866Y1052521D02*
X509704Y1053568D01*
G01X509716Y1055710D02*
X511554Y1056757D01*
G01X507866Y1046143D02*
X509704Y1047190D01*
G01X504165Y1052521D02*
X506003Y1053568D01*
G01X507866Y1071655D02*
X509704Y1072702D01*
G01X502315Y1074844D02*
X504153Y1075891D01*
G01X509716Y1074844D02*
X511554Y1075891D01*
G01X502315Y1062088D02*
X504153Y1063135D01*
G01X509716Y1062088D02*
X511554Y1063135D01*
G01X504165Y1065277D02*
X506003Y1066324D01*
G01X504165Y1078033D02*
X506003Y1079080D01*
G01X507866Y1078033D02*
X509704Y1079080D01*
G01X502315Y1081222D02*
X504153Y1082269D01*
G01X509716Y1081222D02*
X511554Y1082269D01*
G01X504165Y1084411D02*
X506003Y1085458D01*
G01X509716Y1100356D02*
X511554Y1101403D01*
G01X504165Y1103545D02*
X506003Y1104592D01*
G01X507866Y1090789D02*
X509704Y1091836D01*
G01X502315Y1093978D02*
X504153Y1095025D01*
G01X509716Y1093978D02*
X511554Y1095025D01*
G01X504165Y1097167D02*
X506003Y1098214D01*
G01X507866Y1097167D02*
X509704Y1098214D01*
G01X502315Y1100356D02*
X504153Y1101403D01*
G01X507866Y1109923D02*
X509704Y1110970D01*
G01X502315Y1113112D02*
X504153Y1114159D01*
G01X509716Y1113112D02*
X511554Y1114159D01*
G01X504165Y1116301D02*
X506003Y1117348D01*
G01X507866Y1116301D02*
X509704Y1117348D01*
G01X502315Y1119490D02*
X504153Y1120537D01*
G01X509716Y1119490D02*
X511554Y1120537D01*
G01X504165Y1122679D02*
X506003Y1123726D01*
G01X507866Y1129057D02*
X509704Y1130103D01*
G01X502315Y1132246D02*
X504153Y1133293D01*
G01X509716Y1132246D02*
X511554Y1133293D01*
G01X504165Y1135434D02*
X506003Y1136481D01*
G01X507866Y1135434D02*
X509704Y1136481D01*
G01X502315Y1138623D02*
X504153Y1139670D01*
G01X509716Y1138623D02*
X511554Y1139670D01*
G01X504165Y1141812D02*
X506003Y1142859D01*
G01X507866Y1148190D02*
X509704Y1149237D01*
G01X502315Y1151379D02*
X504153Y1152426D01*
G01X509716Y1151379D02*
X511554Y1152426D01*
G01X504165Y1154568D02*
X506003Y1155615D01*
G01X504165Y1160946D02*
X506003Y1161993D01*
G01X506015Y1164135D02*
X507853Y1165182D01*
G01X502315Y1164135D02*
X504153Y1165182D01*
G01X527350Y53543D02*
Y35983D01*
X524713Y33346D01*
G01X527350Y65157D02*
Y73567D01*
X523150Y77767D01*
G01X515539Y65157D02*
Y77767D01*
G01X529713Y65157D02*
X529712D01*
Y76267D01*
X528212Y77767D01*
G01X515539Y82567D02*
Y77767D01*
G01X528717Y160328D02*
Y182152D01*
X536821Y190256D01*
G01X527142Y160328D02*
Y185577D01*
X536821Y195256D01*
G01X514832Y214072D02*
X523504D01*
G01D02*
X528304D01*
G01X529977Y240678D02*
X525364D01*
X524547Y239861D01*
Y231258D01*
X525364Y230441D01*
X529977D01*
G01X522500Y432575D02*
X518500D01*
G01X522500D02*
X522575Y432500D01*
X526425D01*
G01X519637Y880671D02*
X521475Y879624D01*
G01X517787Y877482D02*
X519625Y876435D01*
G01X515937Y880671D02*
X517775Y879624D01*
G01X519637Y874293D02*
X521475Y873246D01*
G01X515937Y874293D02*
X517775Y873246D01*
G01X528889Y877482D02*
X530727Y876435D01*
G01X525189Y877482D02*
X527027Y876435D01*
G01X527039Y880671D02*
X528877Y879624D01*
G01X528889Y890238D02*
X530727Y889191D01*
G01X527039Y893427D02*
X528877Y892380D01*
G01X519637Y887049D02*
X521475Y886002D01*
G01X514086Y890238D02*
X515924Y889191D01*
G01X521488Y890238D02*
X523326Y889191D01*
G01X515937Y893427D02*
X517775Y892380D01*
G01X514086Y883860D02*
X515924Y882813D01*
G01X528889Y883860D02*
X530727Y882813D01*
G01X525189Y883860D02*
X527027Y882813D01*
G01X528889Y902994D02*
X530727Y901947D01*
G01X527039Y906182D02*
X528877Y905135D01*
G01X528889Y909371D02*
X530727Y908325D01*
G01X521488Y909371D02*
X523326Y908325D01*
G01X519637Y899805D02*
X521475Y898758D01*
G01X514086Y902994D02*
X515924Y901947D01*
G01X521488Y902994D02*
X523326Y901947D01*
G01X515937Y906182D02*
X517775Y905135D01*
G01X519637Y906182D02*
X521475Y905135D01*
G01X514086Y909371D02*
X515924Y908325D01*
G01X527039Y912560D02*
X528877Y911513D01*
G01X528889Y922127D02*
X530727Y921080D01*
G01X527039Y925316D02*
X528877Y924269D01*
G01X515937Y912560D02*
X517775Y911513D01*
G01X519637Y918938D02*
X521475Y917891D01*
G01X514086Y922127D02*
X515924Y921080D01*
G01X521488Y922127D02*
X523326Y921080D01*
G01X515937Y925316D02*
X517775Y924269D01*
G01X519637Y925316D02*
X521475Y924269D01*
G01X528889Y928505D02*
X530727Y927458D01*
G01X527039Y931694D02*
X528877Y930647D01*
G01X514086Y928505D02*
X515924Y927458D01*
G01X521488Y928505D02*
X523326Y927458D01*
G01X515937Y931694D02*
X517775Y930647D01*
G01X519637Y938072D02*
X521475Y937025D01*
G01X514086Y941261D02*
X515924Y940214D01*
G01X521488Y941261D02*
X523326Y940214D01*
G01X528889Y941261D02*
X530727Y940214D01*
G01X527039Y944450D02*
X528877Y943403D01*
G01X528889Y947639D02*
X530727Y946592D01*
G01X527039Y950828D02*
X528877Y949781D01*
G01X515937Y944450D02*
X517775Y943403D01*
G01X519637Y944450D02*
X521475Y943403D01*
G01X514086Y947639D02*
X515924Y946592D01*
G01X521488Y947639D02*
X523326Y946592D01*
G01X515937Y950828D02*
X517775Y949781D01*
G01X528889Y966773D02*
X530727Y965726D01*
G01X527039Y969962D02*
X528877Y968915D01*
G01X528889Y960395D02*
X530727Y959348D01*
G01X527039Y963584D02*
X528877Y962537D01*
G01X519637Y963584D02*
X521475Y962537D01*
G01X514086Y966773D02*
X515924Y965726D01*
G01X521488Y966773D02*
X523326Y965726D01*
G01X515937Y969962D02*
X517775Y968915D01*
G01X519637Y957206D02*
X521475Y956159D01*
G01X514086Y960395D02*
X515924Y959348D01*
G01X521488Y960395D02*
X523326Y959348D01*
G01X515937Y963584D02*
X517775Y962537D01*
G01X528889Y979529D02*
X530727Y978482D01*
G01X527039Y982718D02*
X528877Y981671D01*
G01X514086Y985907D02*
X515924Y984860D01*
G01X519637Y976340D02*
X521475Y975293D01*
G01X514086Y979529D02*
X515924Y978482D01*
G01X521488Y979529D02*
X523326Y978482D01*
G01X515937Y982718D02*
X517775Y981671D01*
G01X528889Y985907D02*
X530727Y984860D01*
G01X527039Y989096D02*
X528877Y988049D01*
G01X528889Y998663D02*
X530727Y997616D01*
G01X528889Y992285D02*
X530727Y991238D01*
G01X515937Y989096D02*
X517775Y988049D01*
G01X519637Y995474D02*
X521475Y994427D01*
G01X521488Y998663D02*
X523326Y997616D01*
G01X514086Y998663D02*
X515924Y997616D01*
G01X519637Y989096D02*
X521475Y988049D01*
G01X514086Y992285D02*
X515924Y991238D01*
G01X515937Y995474D02*
X517775Y994427D01*
G01X521488Y992285D02*
X523326Y991238D01*
G01X527039Y995474D02*
X528877Y994427D01*
G01X527039Y1001852D02*
X528877Y1000805D01*
G01X528889Y1005041D02*
X530727Y1003994D01*
G01X527039Y1008230D02*
X528877Y1007183D01*
G01X515937Y1001852D02*
X517775Y1000805D01*
G01X519637Y1001852D02*
X521475Y1000805D01*
G01X521488Y1005041D02*
X523326Y1003994D01*
G01X514086Y1005041D02*
X515924Y1003994D01*
G01X515937Y1008230D02*
X517775Y1007183D01*
G01X514086Y1011419D02*
X515924Y1010372D01*
G01X528889Y1011419D02*
X530727Y1010372D01*
G01X515267Y1027009D02*
X517105Y1028056D01*
G01X522669Y1027009D02*
X524507Y1028056D01*
G01X528220Y1030198D02*
X530058Y1031245D01*
G01X528220Y1036576D02*
X530058Y1037623D01*
G01X528220Y1042954D02*
X530058Y1044001D01*
G01X517118Y1030198D02*
X518956Y1031245D01*
G01X515267Y1033387D02*
X517105Y1034434D01*
G01X522669Y1033387D02*
X524507Y1034434D01*
G01X520818Y1036576D02*
X522657Y1037623D01*
G01X517118Y1036576D02*
X518956Y1037623D01*
G01X515267Y1039765D02*
X517105Y1040812D01*
G01X522669Y1039765D02*
X524507Y1040812D01*
G01X517118Y1042954D02*
X518956Y1044001D01*
G01X520818Y1042954D02*
X522656Y1044001D01*
G01X520818Y1030198D02*
X522656Y1031245D01*
G01X528220Y1049332D02*
X530058Y1050379D01*
G01X517118Y1049332D02*
X518956Y1050379D01*
G01X522669Y1058899D02*
X524507Y1059946D01*
G01X515267Y1046143D02*
X517105Y1047190D01*
G01X520818Y1049332D02*
X522657Y1050379D01*
G01X522669Y1052521D02*
X524507Y1053568D01*
G01X520818Y1055710D02*
X522656Y1056757D01*
G01X522669Y1046143D02*
X524507Y1047190D01*
G01X515267Y1052521D02*
X517105Y1053568D01*
G01X528220Y1074844D02*
X530058Y1075891D01*
G01X528220Y1062088D02*
X530058Y1063135D01*
G01X522669Y1071655D02*
X524507Y1072702D01*
G01X517118Y1074844D02*
X518956Y1075891D01*
G01X520818Y1074844D02*
X522657Y1075891D01*
G01X517118Y1062088D02*
X518956Y1063135D01*
G01X520818Y1062088D02*
X522657Y1063135D01*
G01X515267Y1065277D02*
X517105Y1066324D01*
G01X528220Y1081222D02*
X530058Y1082269D01*
G01X515267Y1078033D02*
X517105Y1079080D01*
G01X522669Y1078033D02*
X524507Y1079080D01*
G01X517118Y1081222D02*
X518956Y1082269D01*
G01X520818Y1081222D02*
X522657Y1082269D01*
G01X515267Y1084411D02*
X517105Y1085458D01*
G01X528220Y1093978D02*
X530058Y1095025D01*
G01X528220Y1100356D02*
X530058Y1101403D01*
G01X520818Y1100356D02*
X522657Y1101403D01*
G01X515267Y1103545D02*
X517105Y1104592D01*
G01X522669Y1090789D02*
X524507Y1091836D01*
G01X517118Y1093978D02*
X518956Y1095025D01*
G01X520818Y1093978D02*
X522657Y1095025D01*
G01X515267Y1097167D02*
X517105Y1098214D01*
G01X522669Y1097167D02*
X524507Y1098214D01*
G01X517118Y1100356D02*
X518956Y1101403D01*
G01X528220Y1113112D02*
X530058Y1114159D01*
G01X528220Y1119490D02*
X530058Y1120537D01*
G01X522669Y1109923D02*
X524507Y1110970D01*
G01X517118Y1113112D02*
X518956Y1114159D01*
G01X520818Y1113112D02*
X522657Y1114159D01*
G01X515267Y1116301D02*
X517105Y1117348D01*
G01X522669Y1116301D02*
X524507Y1117348D01*
G01X517118Y1119490D02*
X518956Y1120537D01*
G01X520818Y1119490D02*
X522657Y1120537D01*
G01X528220Y1132246D02*
X530058Y1133293D01*
G01X515267Y1122679D02*
X517105Y1123726D01*
G01X522669Y1129057D02*
X524507Y1130103D01*
G01X517118Y1132246D02*
X518956Y1133293D01*
G01X520818Y1132246D02*
X522657Y1133293D01*
G01X528220Y1138623D02*
X530058Y1139670D01*
G01X515267Y1135434D02*
X517105Y1136481D01*
G01X522669Y1135434D02*
X524507Y1136481D01*
G01X517118Y1138623D02*
X518956Y1139670D01*
G01X520818Y1138623D02*
X522657Y1139670D01*
G01X515267Y1141812D02*
X517105Y1142859D01*
G01X522669Y1148190D02*
X524507Y1149237D01*
G01X526370Y1160946D02*
X528208Y1161993D01*
G01X528220Y1151379D02*
X530058Y1152426D01*
G01X517118Y1151379D02*
X518956Y1152426D01*
G01X520818Y1151379D02*
X522657Y1152426D01*
G01X522669Y1154568D02*
X524507Y1155615D01*
G01X528220Y1164135D02*
Y1167366D01*
G01X517118Y1164135D02*
Y1167366D01*
G01X520818Y1164135D02*
Y1167366D01*
G01X522669Y1160946D02*
X524507Y1161993D01*
G01X518968Y1160946D02*
X520806Y1161993D01*
G01X517118Y1157757D02*
X518956Y1158804D01*
G01X542523Y1503100D02*
X542183D01*
X536624Y1508659D01*
X533498D01*
X530456Y1505617D01*
X526941D01*
X525268Y1507290D01*
Y1509459D01*
G01X542523Y1506600D02*
X540618D01*
X537209Y1510009D01*
X532388D01*
X529468Y1512929D01*
X528351D01*
X527750Y1512328D01*
X527272D01*
X526449Y1511505D01*
G01X537547Y1534709D02*
X534501D01*
X532872Y1533080D01*
X530463D01*
X530182Y1532799D01*
X527301D01*
G01X544100Y1531540D02*
X542940D01*
X541563Y1532917D01*
X534467D01*
X533358Y1531808D01*
Y1531202D01*
X532314Y1530158D01*
X530433D01*
X530154Y1530437D01*
X527301D01*
G01X532553Y1558650D02*
X533430D01*
X535040Y1557040D01*
Y1545940D01*
X532620Y1543520D01*
X527949D01*
X526449Y1542020D01*
Y1538431D01*
G01X528470Y1553600D02*
X526010D01*
X525268Y1552858D01*
Y1540477D01*
G01X528450Y1564400D02*
X529880D01*
X536460Y1557820D01*
Y1542119D01*
X537547Y1541032D01*
Y1539572D01*
G01X532553Y1558650D02*
X530290D01*
X524400Y1564540D01*
X523250D01*
G01X526193Y1556550D02*
X522933D01*
G01X526193D02*
X527560D01*
X528470Y1555640D01*
Y1553600D01*
G01X543886Y53543D02*
X543925Y53504D01*
Y45826D01*
X540961Y42862D01*
X539721D01*
G01X529713Y53543D02*
Y33346D01*
G01X541524Y53543D02*
Y58253D01*
X544592Y61321D01*
X576375D01*
X583685Y68631D01*
Y70678D01*
G01X543131Y126405D02*
Y128931D01*
X544600Y130400D01*
Y131060D01*
G01X537575Y134147D02*
X540324D01*
X543411Y131060D01*
X544600D01*
G01X530292Y160328D02*
Y173672D01*
X541301Y184681D01*
X545396D01*
G01X531867Y160328D02*
Y162813D01*
X531632Y163048D01*
Y166800D01*
X533850Y169018D01*
G01X535016Y160919D02*
Y163361D01*
X536620Y164965D01*
Y174661D01*
X541840Y179881D01*
X554196D01*
G01X538166Y157769D02*
X539789D01*
X541060Y159040D01*
X544088D01*
X546461Y156667D01*
G01X541621Y190256D02*
X536821D01*
G01X541621Y199256D02*
Y195256D01*
G01D02*
X536821D01*
G01X534277Y224930D02*
X529977D01*
G01X538613Y238119D02*
X529977D01*
G01X538613D02*
X540060Y239566D01*
X543413D01*
G01X534277Y230441D02*
X543413D01*
G01X529977D02*
X534277D01*
G01Y235560D02*
X529977D01*
G01X534277D02*
X543413D01*
G01X538613Y233000D02*
X529977D01*
G01X538613Y227882D02*
X529977D01*
G01X538613D02*
X540054Y226441D01*
X543413D01*
G01X593425Y449500D02*
X588698D01*
X581448Y442250D01*
X566250D01*
X551464Y427464D01*
X535552D01*
X534455Y428561D01*
G01X529815Y438260D02*
X529575Y438020D01*
Y432500D01*
G01X583631Y454242D02*
Y449130D01*
X580001Y445500D01*
X565500D01*
X558500Y438500D01*
Y436560D01*
X551078Y429138D01*
X539039D01*
X537402Y430775D01*
G01D02*
X535677Y432500D01*
X529575D01*
G01X529095Y452049D02*
Y458975D01*
X558568Y488448D01*
X600638Y505874D01*
X630758D01*
G01X530740Y874293D02*
X532578Y873246D01*
G01X534441Y887049D02*
X536279Y886002D01*
G01X532590Y890238D02*
X534428Y889191D01*
G01X539992Y890238D02*
X541830Y889191D01*
G01X541842Y893427D02*
X543680Y892380D01*
G01X539992Y883860D02*
X541830Y882813D01*
G01X532590Y909371D02*
X534428Y908325D01*
G01X534441Y899805D02*
X536279Y898758D01*
G01X532590Y902994D02*
X534428Y901947D01*
G01X534441Y906182D02*
X536279Y905135D01*
G01X539992Y902994D02*
X541830Y901947D01*
G01X541842Y906182D02*
X543680Y905135D01*
G01X539992Y909371D02*
X541830Y908325D01*
G01X534441Y918938D02*
X536279Y917891D01*
G01X532590Y922127D02*
X534428Y921080D01*
G01X534441Y925316D02*
X536279Y924269D01*
G01X541842Y912560D02*
X543680Y911513D01*
G01X539992Y922127D02*
X541830Y921080D01*
G01X541842Y925316D02*
X543680Y924269D01*
G01X532590Y928505D02*
X534428Y927458D01*
G01X534441Y938072D02*
X536279Y937025D01*
G01X532590Y941261D02*
X534428Y940214D01*
G01X539992Y928505D02*
X541830Y927458D01*
G01X541842Y931694D02*
X543680Y930647D01*
G01X539992Y941261D02*
X541830Y940214D01*
G01X534441Y944450D02*
X536279Y943403D01*
G01X532590Y947639D02*
X534428Y946592D01*
G01X541842Y944450D02*
X543680Y943403D01*
G01X539992Y947639D02*
X541830Y946592D01*
G01X541842Y950828D02*
X543680Y949781D01*
G01X534441Y963584D02*
X536279Y962537D01*
G01X532590Y966773D02*
X534428Y965726D01*
G01X534441Y957206D02*
X536279Y956159D01*
G01X532590Y960395D02*
X534428Y959348D01*
G01X539992Y966773D02*
X541830Y965726D01*
G01X541842Y969962D02*
X543680Y968915D01*
G01X539992Y960395D02*
X541830Y959348D01*
G01X541842Y963584D02*
X543680Y962537D01*
G01X534441Y976340D02*
X536279Y975293D01*
G01X532590Y979529D02*
X534428Y978482D01*
G01X539992Y985907D02*
X541830Y984860D01*
G01X539992Y979529D02*
X541830Y978482D01*
G01X541842Y982718D02*
X543680Y981671D01*
G01X534441Y995474D02*
X536279Y994427D01*
G01X532590Y998663D02*
X534428Y997616D01*
G01X534441Y989096D02*
X536279Y988049D01*
G01X541842Y989096D02*
X543680Y988049D01*
G01X539992Y998663D02*
X541830Y997616D01*
G01X539992Y992285D02*
X541830Y991238D01*
G01X541842Y995474D02*
X543680Y994427D01*
G01X532590Y992285D02*
X534428Y991238D01*
G01X534441Y1001852D02*
X536279Y1000805D01*
G01X532590Y1005041D02*
X534428Y1003994D01*
G01X541842Y1001852D02*
X543680Y1000805D01*
G01X539992Y1005041D02*
X541830Y1003994D01*
G01X541842Y1008230D02*
X543680Y1007183D01*
G01X539992Y1011419D02*
X541830Y1010372D01*
G01X530070Y1027009D02*
X531908Y1028056D01*
G01X541173Y1027009D02*
X543011Y1028056D01*
G01X533771Y1027009D02*
X535609Y1028056D01*
G01X530070Y1033387D02*
X531908Y1034434D01*
G01X533771Y1033387D02*
X535609Y1034434D01*
G01X535622Y1036576D02*
X537460Y1037623D01*
G01X530070Y1039765D02*
X531908Y1040812D01*
G01X533771Y1039765D02*
X535609Y1040812D01*
G01X543023Y1030198D02*
X544861Y1031245D01*
G01X541173Y1033387D02*
X543011Y1034434D01*
G01X543023Y1036576D02*
X544861Y1037623D01*
G01X541173Y1039765D02*
X543011Y1040812D01*
G01X543023Y1042954D02*
X544861Y1044001D01*
G01X535622Y1042954D02*
X537460Y1044001D01*
G01X535622Y1030198D02*
X537460Y1031245D01*
G01X533771Y1058899D02*
X535609Y1059946D01*
G01X530070Y1046143D02*
X531908Y1047190D01*
G01X535622Y1049332D02*
X537460Y1050379D01*
G01X533771Y1052521D02*
X535609Y1053568D01*
G01X543023Y1049332D02*
X544861Y1050379D01*
G01X541173Y1046143D02*
X543011Y1047190D01*
G01X541173Y1052521D02*
X543011Y1053568D01*
G01X535622Y1055710D02*
X537460Y1056757D01*
G01X533771Y1046143D02*
X535609Y1047190D01*
G01X530070Y1052521D02*
X531908Y1053568D01*
G01X533771Y1071655D02*
X535609Y1072702D01*
G01X535622Y1074844D02*
X537460Y1075891D01*
G01X535622Y1062088D02*
X537460Y1063135D01*
G01X530070Y1065277D02*
X531908Y1066324D01*
G01X543023Y1074844D02*
X544861Y1075891D01*
G01X543023Y1062088D02*
X544861Y1063135D01*
G01X541173Y1065277D02*
X543011Y1066324D01*
G01X530070Y1078033D02*
X531908Y1079080D01*
G01X533771Y1078033D02*
X535609Y1079080D01*
G01X535622Y1081222D02*
X537460Y1082269D01*
G01X530070Y1084411D02*
X531908Y1085458D01*
G01X541173Y1078033D02*
X543011Y1079080D01*
G01X543023Y1081222D02*
X544861Y1082269D01*
G01X541173Y1084411D02*
X543011Y1085458D01*
G01X535622Y1100356D02*
X537460Y1101403D01*
G01X530070Y1103545D02*
X531908Y1104592D01*
G01X533771Y1090789D02*
X535609Y1091836D01*
G01X535622Y1093978D02*
X537460Y1095025D01*
G01X530070Y1097167D02*
X531908Y1098214D01*
G01X533771Y1097167D02*
X535609Y1098214D01*
G01X541173Y1103545D02*
X543011Y1104592D01*
G01X543023Y1093978D02*
X544861Y1095025D01*
G01X541173Y1097167D02*
X543011Y1098214D01*
G01X543023Y1100356D02*
X544861Y1101403D01*
G01X533771Y1109923D02*
X535609Y1110970D01*
G01X535622Y1113112D02*
X537460Y1114159D01*
G01X530070Y1116301D02*
X531908Y1117348D01*
G01X533771Y1116301D02*
X535609Y1117348D01*
G01X535622Y1119490D02*
X537460Y1120537D01*
G01X543023Y1113112D02*
X544861Y1114159D01*
G01X541173Y1116301D02*
X543011Y1117348D01*
G01X543023Y1119490D02*
X544861Y1120537D01*
G01X530070Y1122679D02*
X531908Y1123726D01*
G01X533771Y1129057D02*
X535609Y1130103D01*
G01X535622Y1132246D02*
X537460Y1133293D01*
G01X541173Y1122679D02*
X543011Y1123726D01*
G01X543023Y1132246D02*
X544861Y1133293D01*
G01X530070Y1135434D02*
X531908Y1136481D01*
G01X533771Y1135434D02*
X535609Y1136481D01*
G01X535622Y1138623D02*
X537460Y1139670D01*
G01X530070Y1141812D02*
X531908Y1142859D01*
G01X533771Y1148190D02*
X535609Y1149237D01*
G01X541173Y1135434D02*
X543011Y1136481D01*
G01X543023Y1138623D02*
X544861Y1139670D01*
G01X541173Y1141812D02*
X543011Y1142859D01*
G01X539322Y1164135D02*
Y1165570D01*
X532639Y1172253D01*
Y1210234D01*
X557194Y1234789D01*
X560551D01*
X564669Y1238907D01*
G01X543023Y1164135D02*
Y1165444D01*
X534975Y1173492D01*
Y1209741D01*
X557196Y1231962D01*
X560774D01*
X563314Y1234502D01*
X564583D01*
X565537Y1235456D01*
G01X535622Y1151379D02*
X537460Y1152426D01*
G01X530070Y1154568D02*
X531908Y1155615D01*
G01X543023Y1151379D02*
X544861Y1152426D01*
G01X543023Y1157757D02*
X544861Y1158804D01*
G01X531921Y1164135D02*
Y1167366D01*
G01X530070Y1160946D02*
X531908Y1161993D01*
G01X533771Y1160946D02*
X535609Y1161993D01*
G01X537472Y1160946D02*
X539310Y1161993D01*
G01X535622Y1157757D02*
X537460Y1158804D01*
G01X539322Y1157757D02*
X541160Y1158804D01*
G01X548574Y1160946D02*
Y1165685D01*
X546903Y1167356D01*
Y1168209D01*
X539950Y1175162D01*
Y1209013D01*
X552900Y1221963D01*
X561402D01*
X567142Y1227703D01*
Y1232977D01*
X568424Y1234259D01*
Y1248239D01*
X567127Y1249536D01*
G01X673671Y1431922D02*
X650499Y1408750D01*
X629868D01*
X604708Y1383590D01*
Y1327013D01*
X574179Y1296484D01*
Y1258801D01*
X571482Y1256104D01*
Y1234082D01*
X569327Y1231927D01*
Y1226685D01*
X561875Y1219233D01*
X553400D01*
X542062Y1207895D01*
Y1176196D01*
X549331Y1168927D01*
Y1166526D01*
X550425Y1165432D01*
Y1164135D01*
G01X546724D02*
Y1165235D01*
X537610Y1174349D01*
Y1209881D01*
X551872Y1224143D01*
X560290D01*
X564283Y1228136D01*
Y1231192D01*
G01X542523Y1506600D02*
Y1506202D01*
X543725Y1505000D01*
X545988D01*
X547028Y1503960D01*
X548338D01*
G01X540877Y1526953D02*
X535375D01*
X530807Y1522385D01*
Y1521268D01*
X529346Y1519807D01*
G01Y1515083D02*
X531001Y1514073D01*
G01X529346Y1517445D02*
X530945Y1516336D01*
G01X529346Y1522169D02*
X535071Y1527894D01*
X538487D01*
X539467Y1528874D01*
X540406Y1529263D01*
X543567D01*
X545877Y1526953D01*
G01X547173Y1521750D02*
X546649Y1521745D01*
X545695Y1522688D01*
Y1524012D01*
X545135Y1524572D01*
X542924Y1525488D01*
X542342D01*
X540877Y1526953D01*
G01X532310Y1536640D02*
X531596D01*
X531299Y1536343D01*
X529346D01*
G01X531926Y1534540D02*
X529906D01*
X529346Y1533980D01*
G01Y1531618D02*
X531537D01*
G01X529346Y1529256D02*
X529904Y1528698D01*
X531208D01*
G01X537547Y1539572D02*
X533848D01*
X532943Y1540477D01*
X529992D01*
G01X531339Y1546481D02*
X533520Y1548662D01*
Y1552851D01*
X532751Y1553620D01*
X531580D01*
G01X532553Y1556550D02*
Y1554593D01*
X531580Y1553620D01*
G01X555697Y53543D02*
Y47881D01*
X554984Y47168D01*
Y45312D01*
G01X546248Y53543D02*
X546287Y53504D01*
Y44458D01*
X544721Y42892D01*
G01X550972Y53543D02*
Y42902D01*
G01X558059Y53543D02*
Y43246D01*
X556351Y41538D01*
G01X553335Y53543D02*
Y49158D01*
X553651Y48842D01*
G01X548610Y53543D02*
Y48082D01*
G01X546461Y156667D02*
X551261D01*
G01D02*
Y152742D01*
G01X554196Y184681D02*
Y179881D01*
G01X550196Y184681D02*
X545396D01*
G01X548963Y218441D02*
X546563D01*
G01Y222441D02*
Y218441D01*
G01Y226441D02*
Y222441D01*
G01X551363Y239566D02*
X549449Y237652D01*
X549248D01*
G01D02*
X547334Y239566D01*
X546563D01*
G01X549248Y230441D02*
X546563D01*
G01X561070Y304282D02*
X560182D01*
X558181Y302281D01*
X557243Y300016D01*
Y294693D01*
G01X565908Y378986D02*
X559823D01*
X556248Y382561D01*
Y389786D01*
G01X565908D02*
X556248D01*
G01X553098Y403586D02*
X550573D01*
G01X556248D02*
Y399586D01*
G01D02*
Y394786D01*
G01X573782Y398599D02*
X571040D01*
X567227Y394786D01*
X556248D01*
G01X561048Y412774D02*
X557748D01*
X556248Y414274D01*
G01X565908Y410728D02*
Y410658D01*
X563878Y408628D01*
X553715D01*
G01X565908Y423949D02*
X556248D01*
G01D02*
Y429451D01*
X561024Y434227D01*
X568709D01*
G01X555740Y444165D02*
Y447261D01*
X553575Y449426D01*
Y451000D01*
G01X556981D02*
X560425D01*
G01X553575D02*
X556981D01*
G01X555185Y466240D02*
X553893D01*
X552160Y467973D01*
Y471434D01*
X553058Y472332D01*
G01X558925Y473500D02*
X554226D01*
X553058Y472332D01*
G01X552944Y880671D02*
X554783Y879624D01*
G01X554795Y890238D02*
X556633Y889191D01*
G01X558496Y890238D02*
X560334Y889191D01*
G01X552944Y893427D02*
X554783Y892380D01*
G01X545543Y887049D02*
X547381Y886002D01*
G01X547393Y890238D02*
X549231Y889191D01*
G01X554795Y883860D02*
X556633Y882813D01*
G01X551094Y883860D02*
X552932Y882813D01*
G01X558496Y909371D02*
X560334Y908325D01*
G01X554795Y902994D02*
X556633Y901947D01*
G01X558496Y902994D02*
X560334Y901947D01*
G01X552944Y906182D02*
X554783Y905135D01*
G01X554795Y909371D02*
X556633Y908325D01*
G01X547393Y909371D02*
X549231Y908325D01*
G01X545543Y899805D02*
X547381Y898758D01*
G01X547393Y902994D02*
X549231Y901947D01*
G01X545543Y906182D02*
X547381Y905135D01*
G01X552944Y912560D02*
X554783Y911513D01*
G01X554795Y922127D02*
X556633Y921080D01*
G01X558496Y922127D02*
X560334Y921080D01*
G01X552944Y925316D02*
X554783Y924269D01*
G01X545543Y918938D02*
X547381Y917891D01*
G01X547393Y922127D02*
X549231Y921080D01*
G01X545543Y925316D02*
X547381Y924269D01*
G01X554795Y928505D02*
X556633Y927458D01*
G01X558496Y928505D02*
X560334Y927458D01*
G01X552944Y931694D02*
X554783Y930647D01*
G01X554795Y941261D02*
X556633Y940214D01*
G01X547393Y928505D02*
X549231Y927458D01*
G01X545543Y938072D02*
X547381Y937025D01*
G01X547393Y941261D02*
X549231Y940214D01*
G01X558496Y941261D02*
X560334Y940214D01*
G01X552944Y944450D02*
X554783Y943403D01*
G01X554795Y947639D02*
X556633Y946592D01*
G01X558496Y947639D02*
X560334Y946592D01*
G01X552944Y950828D02*
X554783Y949781D01*
G01X545543Y944450D02*
X547381Y943403D01*
G01X547393Y947639D02*
X549231Y946592D01*
G01X554795Y966773D02*
X556633Y965726D01*
G01X558496Y966773D02*
X560334Y965726D01*
G01X552944Y969962D02*
X554783Y968915D01*
G01X554795Y960395D02*
X556633Y959348D01*
G01X558496Y960395D02*
X560334Y959348D01*
G01X552944Y963584D02*
X554783Y962537D01*
G01X545543Y963584D02*
X547381Y962537D01*
G01X547393Y966773D02*
X549231Y965726D01*
G01X545543Y957206D02*
X547381Y956159D01*
G01X547393Y960395D02*
X549231Y959348D01*
G01X554795Y985907D02*
X556633Y984860D01*
G01X554795Y979529D02*
X556633Y978482D01*
G01X558496Y979529D02*
X560334Y978482D01*
G01X552944Y982718D02*
X554783Y981671D01*
G01X545543Y976340D02*
X547381Y975293D01*
G01X547393Y979529D02*
X549231Y978482D01*
G01X552944Y989096D02*
X554783Y988049D01*
G01X558496Y998663D02*
X560334Y997616D01*
G01X554795Y998663D02*
X556633Y997616D01*
G01X554795Y992285D02*
X556633Y991238D01*
G01X545543Y995474D02*
X547381Y994427D01*
G01X547393Y998663D02*
X549231Y997616D01*
G01X545543Y989096D02*
X547381Y988049D01*
G01X552944Y995474D02*
X554782Y994427D01*
G01X558496Y992285D02*
X560334Y991238D01*
G01X547393Y992285D02*
X549231Y991238D01*
G01X552944Y1001852D02*
X554783Y1000805D01*
G01X558496Y1005041D02*
X560334Y1003994D01*
G01X554795Y1005041D02*
X556633Y1003994D01*
G01X552944Y1008230D02*
X554783Y1007183D01*
G01X545543Y1001852D02*
X547381Y1000805D01*
G01X547393Y1005041D02*
X549231Y1003994D01*
G01X554795Y1011419D02*
X556633Y1010372D01*
G01X555976Y1027009D02*
X557814Y1028056D01*
G01X548574Y1027009D02*
X550412Y1028056D01*
G01X554126Y1030198D02*
X555964Y1031245D01*
G01X555976Y1033387D02*
X557814Y1034434D01*
G01X554126Y1036576D02*
X555964Y1037623D01*
G01X555976Y1039765D02*
X557814Y1040812D01*
G01X554126Y1042954D02*
X555964Y1044001D01*
G01X548574Y1033387D02*
X550412Y1034434D01*
G01X546724Y1036576D02*
X548562Y1037623D01*
G01X548574Y1039765D02*
X550412Y1040812D01*
G01X546724Y1042954D02*
X548562Y1044001D01*
G01X546724Y1030198D02*
X548562Y1031245D01*
G01X554126Y1049332D02*
X555964Y1050379D01*
G01X555976Y1046143D02*
X557814Y1047190D01*
G01X548574Y1058899D02*
X550412Y1059946D01*
G01X546724Y1049332D02*
X548562Y1050379D01*
G01X548574Y1052521D02*
X550412Y1053568D01*
G01X555976Y1052521D02*
X557814Y1053568D01*
G01X546724Y1055710D02*
X548562Y1056757D01*
G01X548574Y1046143D02*
X550412Y1047190D01*
G01X554126Y1074844D02*
X555964Y1075891D01*
G01X554126Y1062088D02*
X555964Y1063135D01*
G01X555976Y1065277D02*
X557814Y1066324D01*
G01X548574Y1071655D02*
X550412Y1072702D01*
G01X546724Y1074844D02*
X548562Y1075891D01*
G01X546724Y1062088D02*
X548562Y1063135D01*
G01X555976Y1078033D02*
X557814Y1079080D01*
G01X554126Y1081222D02*
X555964Y1082269D01*
G01X555976Y1084411D02*
X557814Y1085458D01*
G01X548574Y1078033D02*
X550412Y1079080D01*
G01X546724Y1081222D02*
X548562Y1082269D01*
G01X555976Y1103545D02*
X557814Y1104592D01*
G01X554126Y1093978D02*
X555964Y1095025D01*
G01X555976Y1097167D02*
X557814Y1098214D01*
G01X554126Y1100356D02*
X555964Y1101403D01*
G01X546724Y1100356D02*
X548562Y1101403D01*
G01X548574Y1090789D02*
X550412Y1091836D01*
G01X546724Y1093978D02*
X548562Y1095025D01*
G01X548574Y1097167D02*
X550412Y1098214D01*
G01X554126Y1113112D02*
X555964Y1114159D01*
G01X555976Y1116301D02*
X557814Y1117348D01*
G01X554126Y1119490D02*
X555964Y1120537D01*
G01X548574Y1109923D02*
X550412Y1110970D01*
G01X546724Y1113112D02*
X548562Y1114159D01*
G01X548574Y1116301D02*
X550412Y1117348D01*
G01X546724Y1119490D02*
X548562Y1120537D01*
G01X555976Y1122679D02*
X557814Y1123726D01*
G01X554126Y1132246D02*
X555964Y1133293D01*
G01X548574Y1129057D02*
X550412Y1130103D01*
G01X546724Y1132246D02*
X548562Y1133293D01*
G01X555976Y1135434D02*
X557814Y1136481D01*
G01X554126Y1138623D02*
X555964Y1139670D01*
G01X555976Y1141812D02*
X557814Y1142859D01*
G01X548574Y1135434D02*
X550412Y1136481D01*
G01X546724Y1138623D02*
X548562Y1139670D01*
G01X548574Y1148190D02*
X550412Y1149237D01*
G01X544874Y1160946D02*
X546712Y1161993D01*
G01X554126Y1151379D02*
X555964Y1152426D01*
G01X555976Y1154568D02*
X557814Y1155615D01*
G01X546724Y1151379D02*
X548562Y1152426D01*
G01X548574Y1154568D02*
X550412Y1155615D01*
G01X555976Y1160946D02*
X557814Y1161993D01*
G01X559677Y1160946D02*
Y1168368D01*
X544183Y1183862D01*
Y1206257D01*
X553956Y1216030D01*
X592565D01*
X615218Y1238683D01*
Y1260397D01*
X613408Y1262207D01*
Y1268031D01*
X611551Y1269888D01*
X610551D01*
G01X555091Y1265586D02*
X557315D01*
X557962Y1264939D01*
X564509D01*
G01X548338Y1503960D02*
Y1505420D01*
X547723Y1506035D01*
Y1506797D01*
X547645Y1506875D01*
Y1509085D01*
G01X558623Y1517640D02*
Y1518989D01*
X557992Y1519620D01*
X554213D01*
X553633Y1520200D01*
G01X558623Y1517640D02*
X559859D01*
X560259Y1518040D01*
X561523D01*
G01Y1514420D02*
X558503D01*
X558397Y1514314D01*
G01X550373Y1521750D02*
Y1518850D01*
G01Y1521750D02*
X550709D01*
X552350Y1523391D01*
Y1527709D01*
X551319Y1528740D01*
X547664D01*
X545877Y1526953D01*
G01X547173Y1518850D02*
Y1521750D01*
G01X561523Y1510800D02*
X557623D01*
G01D02*
Y1511218D01*
X554527Y1514314D01*
X553397D01*
G01X558280Y1532851D02*
X557689Y1533442D01*
X554396D01*
X551945Y1532427D01*
X546617D01*
X545730Y1531540D01*
X544100D01*
G01X572232Y53543D02*
Y43871D01*
X573191Y42912D01*
G01X567508Y53543D02*
Y41870D01*
X566771Y41133D01*
G01X560421Y53543D02*
Y50128D01*
X559921Y48920D01*
Y45444D01*
X561721Y41098D01*
Y41024D01*
G01X565146Y53543D02*
Y48021D01*
X565185Y47982D01*
G01X569870Y53543D02*
X570170Y53243D01*
Y48021D01*
X570209Y47982D01*
G01X562784Y53543D02*
Y48891D01*
X562331Y48438D01*
G01X572232Y65157D02*
Y77862D01*
G01X569870Y65157D02*
Y85013D01*
X567521Y87362D01*
G01X567508Y65157D02*
Y81049D01*
G01X565146Y65157D02*
Y81937D01*
X562821Y84262D01*
G01X562784Y65157D02*
Y78299D01*
G01X574595Y65157D02*
Y81188D01*
X572221Y83562D01*
G01X572297Y152080D02*
X567391D01*
X563951Y148640D01*
G01X574428Y164356D02*
X572003D01*
G01X572297Y154640D02*
X564951D01*
X563951Y153640D01*
G01X574428Y169415D02*
X572003D01*
G01X572342Y223921D02*
X570799D01*
X568804Y221926D01*
G01X572342Y225496D02*
X569004D01*
G01X577949Y257171D02*
X574439D01*
X572800Y258810D01*
Y265590D01*
X574150Y266940D01*
Y276590D01*
X577100Y279540D01*
X599860D01*
X601345Y281025D01*
X645093D01*
X655540Y291472D01*
Y311638D01*
X650418Y316760D01*
X628668D01*
X613544Y331884D01*
Y350798D01*
X613565Y350819D01*
G01X574107Y297304D02*
Y297810D01*
X572447Y299470D01*
G01D02*
X572354Y299563D01*
Y300398D01*
X571673Y301079D01*
Y304341D01*
X569763Y306251D01*
X568156D01*
G01X568550Y312156D02*
X569156D01*
X571063Y314063D01*
Y314669D01*
G01D02*
Y317397D01*
G01X565908Y373868D02*
X563026D01*
X562030Y372872D01*
G01X565908Y384668D02*
X563208D01*
X562208Y383668D01*
G01X573782Y403717D02*
X570789D01*
X568559Y405947D01*
Y412434D01*
X567706Y413287D01*
X565908D01*
G01Y403717D02*
X563208D01*
X562208Y404717D01*
G01X565908Y398599D02*
X563208D01*
X562208Y397599D01*
G01X565908Y413287D02*
X561561D01*
X561048Y412774D01*
G01X573388Y415846D02*
X578248D01*
G01X573388Y413287D02*
X575913D01*
G01X573388Y410728D02*
X570863D01*
G01X573388Y423949D02*
X578248D01*
G01X573388Y426508D02*
Y427097D01*
X578267Y431976D01*
G01X565908Y421390D02*
Y423949D01*
G01X571925Y462000D02*
Y466000D01*
G01Y462000D02*
Y458443D01*
G01D02*
Y454500D01*
G01X560425Y451000D02*
Y454713D01*
X564472Y458760D01*
X565815D01*
G01X593596Y479631D02*
X590965Y477000D01*
X586000D01*
X585000Y476000D01*
Y471000D01*
X584000Y470000D01*
X579500D01*
X578000Y471500D01*
X573075D01*
G01X562075Y477500D02*
X564000D01*
X564500Y477000D01*
Y470500D01*
X565500Y469500D01*
X571075D01*
X573075Y471500D01*
G01X576925Y475500D02*
X573075D01*
G01D02*
X565353Y483222D01*
X562332D01*
X560890Y484664D01*
G01X558925Y477500D02*
Y473500D01*
G01X562075D02*
Y468924D01*
X564759Y466240D01*
X565815D01*
G01X571925Y466000D02*
X571685Y466240D01*
X565815D01*
G01X570216Y764437D02*
Y759762D01*
G01Y772262D02*
Y767587D01*
G01X560346Y874293D02*
X562184Y873246D01*
G01X577099Y883489D02*
X581166Y879422D01*
Y845053D01*
X585259Y835170D01*
X638090Y782339D01*
Y781689D01*
X637278Y780878D01*
Y780228D01*
X637739Y779767D01*
X638389D01*
X639201Y780578D01*
X639851D01*
X641845Y778584D01*
X643219D01*
G01X579875Y885368D02*
X583846Y881397D01*
Y845590D01*
X605547Y823889D01*
X608372Y817070D01*
X640165Y785277D01*
X643219D01*
G01X578891Y884368D02*
X582506Y880753D01*
Y845320D01*
X585533Y838012D01*
X591554Y831991D01*
X592204D01*
X593412Y833200D01*
X594062D01*
X594523Y832739D01*
Y832089D01*
X593315Y830880D01*
Y830230D01*
X593776Y829769D01*
X594426D01*
X595634Y830978D01*
X596284D01*
X596745Y830517D01*
Y829867D01*
X595537Y828658D01*
Y828008D01*
X595998Y827547D01*
X596648D01*
X597856Y828756D01*
X598506D01*
X598967Y828295D01*
Y827645D01*
X597759Y826436D01*
Y825786D01*
X598220Y825325D01*
X598870D01*
X600078Y826534D01*
X600728D01*
X601189Y826073D01*
Y825423D01*
X599981Y824214D01*
Y823564D01*
X600442Y823103D01*
X601092D01*
X602300Y824312D01*
X602950D01*
X603411Y823851D01*
Y823201D01*
X602203Y821992D01*
Y821342D01*
X643288Y780257D01*
X647354D01*
G01X581125Y886410D02*
X585186Y882349D01*
Y846147D01*
X611020Y820313D01*
Y819663D01*
X609712Y818354D01*
Y817704D01*
X610173Y817243D01*
X610823D01*
X612131Y818552D01*
X612781D01*
X613242Y818091D01*
Y817441D01*
X611934Y816132D01*
Y815482D01*
X612395Y815021D01*
X613045D01*
X614353Y816330D01*
X615003D01*
X615464Y815869D01*
Y815219D01*
X614156Y813910D01*
Y813260D01*
X614617Y812799D01*
X615267D01*
X616575Y814108D01*
X617225D01*
X617740Y813593D01*
Y809599D01*
X640389Y786950D01*
X647354D01*
G01X560346Y887049D02*
X562184Y886002D01*
G01X565897Y883860D02*
X567735Y882813D01*
G01X580640Y908156D02*
X600629Y888167D01*
Y855963D01*
X601026Y855566D01*
X601676D01*
X602932Y856822D01*
X603582D01*
X604043Y856361D01*
Y855711D01*
X602787Y854455D01*
Y853805D01*
X603248Y853344D01*
X603898D01*
X605154Y854600D01*
X605804D01*
X606265Y854139D01*
Y853489D01*
X605009Y852233D01*
Y851583D01*
X605470Y851122D01*
X606120D01*
X607376Y852378D01*
X608026D01*
X608487Y851917D01*
Y851267D01*
X607231Y850011D01*
Y849361D01*
X607692Y848900D01*
X608342D01*
X609598Y850156D01*
X610248D01*
X610709Y849695D01*
Y849045D01*
X609453Y847789D01*
Y847139D01*
X639524Y817068D01*
X647354D01*
G01X581992Y896595D02*
X592729Y885858D01*
Y849116D01*
X614432Y827413D01*
X617822D01*
X643219Y802016D01*
G01X582425Y899956D02*
X595889Y886492D01*
Y849748D01*
X605810Y839827D01*
X606679D01*
X608142Y841290D01*
X608793D01*
X641381Y808702D01*
X643219D01*
G01X582185Y898300D02*
X594309Y886176D01*
Y849432D01*
X606102Y837639D01*
X606752D01*
X608324Y839211D01*
X608974D01*
X616751Y831434D01*
Y830784D01*
X616290Y830323D01*
X615640D01*
X608974Y836989D01*
X608324D01*
X607863Y836528D01*
Y835878D01*
X614988Y828753D01*
X619434D01*
X644505Y803682D01*
X647354D01*
G01X582385Y901948D02*
X597469Y886864D01*
Y854510D01*
X599547Y852432D01*
Y851782D01*
X597973Y850210D01*
Y849560D01*
X605919Y841614D01*
X606569D01*
X607031Y842076D01*
Y842725D01*
X600196Y849560D01*
Y850210D01*
X600658Y850671D01*
X601308D01*
X641604Y810375D01*
X647354D01*
G01X580164Y906736D02*
X599289Y887611D01*
Y855407D01*
X639301Y815395D01*
X643219D01*
G01X581106Y909586D02*
X601969Y888723D01*
Y860895D01*
X612085Y850779D01*
Y846403D01*
X636400Y822088D01*
X643219D01*
G01X560346Y899805D02*
X562184Y898758D01*
G01X560346Y906182D02*
X562184Y905135D01*
G01X580677Y911091D02*
X581497D01*
X603309Y889279D01*
Y861451D01*
X614938Y849822D01*
Y849172D01*
X613425Y847659D01*
Y847009D01*
X613886Y846548D01*
X614536D01*
X616049Y848061D01*
X616699D01*
X617160Y847600D01*
Y846950D01*
X615647Y845437D01*
Y844787D01*
X616108Y844326D01*
X616758D01*
X618271Y845839D01*
X618921D01*
X619382Y845378D01*
Y844728D01*
X617869Y843215D01*
Y842565D01*
X618330Y842104D01*
X618980D01*
X620493Y843617D01*
X621143D01*
X621604Y843156D01*
Y842506D01*
X620091Y840993D01*
Y840293D01*
X636623Y823761D01*
X647354D01*
G01X578205Y920436D02*
X579332D01*
X579792Y919976D01*
Y919219D01*
X580252Y918759D01*
X580903D01*
X581363Y919219D01*
Y919976D01*
X581823Y920436D01*
X582882D01*
X610929Y892389D01*
Y866672D01*
X638781Y838820D01*
X643069D01*
G01X581725Y923879D02*
X583231D01*
X613645Y893465D01*
Y870043D01*
X614568Y869120D01*
Y868470D01*
X614071Y867973D01*
Y867323D01*
X614532Y866862D01*
X615182D01*
X615679Y867359D01*
X616329D01*
X616790Y866898D01*
Y866248D01*
X616293Y865751D01*
Y865101D01*
X616754Y864640D01*
X617404D01*
X617901Y865137D01*
X618551D01*
X619012Y864676D01*
Y864026D01*
X618515Y863529D01*
Y862879D01*
X619020Y862374D01*
X622400D01*
X639261Y845513D01*
X643219D01*
G01X581682Y922066D02*
X583148D01*
X612269Y892945D01*
Y867228D01*
X619501Y859996D01*
X620151D01*
X621105Y860950D01*
X621755D01*
X622216Y860489D01*
Y859839D01*
X621262Y858885D01*
Y858235D01*
X621723Y857774D01*
X622373D01*
X623327Y858728D01*
X623977D01*
X624438Y858267D01*
Y857617D01*
X623484Y856663D01*
Y856013D01*
X623945Y855552D01*
X624595D01*
X625549Y856506D01*
X626199D01*
X626660Y856045D01*
Y855395D01*
X625706Y854441D01*
Y853791D01*
X626167Y853330D01*
X626817D01*
X627771Y854284D01*
X628421D01*
X628882Y853823D01*
Y853173D01*
X627928Y852219D01*
Y851569D01*
X628389Y851108D01*
X629039D01*
X629993Y852062D01*
X630643D01*
X631104Y851601D01*
Y850951D01*
X630150Y849997D01*
Y849347D01*
X630611Y848886D01*
X631261D01*
X632215Y849840D01*
X632865D01*
X633326Y849379D01*
Y848729D01*
X632372Y847775D01*
Y847125D01*
X632833Y846664D01*
X633483D01*
X634437Y847618D01*
X635087D01*
X635548Y847157D01*
Y846507D01*
X634594Y845553D01*
Y844903D01*
X635055Y844442D01*
X635705D01*
X636659Y845396D01*
X637309D01*
X637770Y844935D01*
Y844285D01*
X636816Y843331D01*
Y842681D01*
X639004Y840493D01*
X647354D01*
G01X581742Y925526D02*
X583480D01*
X615155Y893851D01*
Y874873D01*
X617274Y872754D01*
Y872104D01*
X615702Y870532D01*
Y869882D01*
X621870Y863714D01*
X622520D01*
X622981Y864175D01*
Y864825D01*
X617924Y869882D01*
Y870532D01*
X618385Y870993D01*
X619035D01*
X624623Y865405D01*
Y862047D01*
X638741Y847929D01*
X639335D01*
X639755Y848349D01*
Y849138D01*
X640215Y849598D01*
X640866D01*
X641399Y849065D01*
Y847573D01*
X641786Y847186D01*
X647354D01*
G01X581842Y927326D02*
X584246D01*
X616955Y894617D01*
Y875620D01*
X626423Y866152D01*
Y862806D01*
X637023Y852206D01*
X643219D01*
G01X560346Y918938D02*
X562184Y917891D01*
G01X560346Y925316D02*
X562184Y924269D01*
G01X581792Y930006D02*
X585358D01*
X619635Y895729D01*
Y876732D01*
X637468Y858899D01*
X643219D01*
G01X581882Y928666D02*
X584802D01*
X618295Y895173D01*
Y876176D01*
X628786Y865685D01*
Y865035D01*
X627763Y864013D01*
Y863363D01*
X628224Y862902D01*
X628874D01*
X629897Y863924D01*
X630547D01*
X631008Y863463D01*
Y862813D01*
X629985Y861791D01*
Y861141D01*
X630446Y860680D01*
X631096D01*
X632119Y861702D01*
X632769D01*
X633230Y861241D01*
Y860591D01*
X632207Y859569D01*
Y858919D01*
X632668Y858458D01*
X633318D01*
X634341Y859480D01*
X634991D01*
X635452Y859019D01*
Y858369D01*
X634429Y857347D01*
Y856697D01*
X634890Y856236D01*
X635540D01*
X636563Y857258D01*
X637213D01*
X637674Y856797D01*
Y856147D01*
X636651Y855125D01*
Y854475D01*
X637112Y854014D01*
X637762D01*
X638785Y855036D01*
X639435D01*
X640592Y853879D01*
X647354D01*
G01X581662Y931346D02*
X585914D01*
X620975Y896285D01*
Y879554D01*
X621774Y878755D01*
Y878105D01*
X621291Y877622D01*
Y876972D01*
X621752Y876511D01*
X622402D01*
X622885Y876994D01*
X623535D01*
X623996Y876533D01*
Y875883D01*
X623513Y875400D01*
Y874750D01*
X623974Y874289D01*
X624624D01*
X625107Y874772D01*
X625757D01*
X626218Y874311D01*
Y873661D01*
X625735Y873178D01*
Y872528D01*
X626196Y872067D01*
X626846D01*
X627329Y872550D01*
X627979D01*
X628440Y872089D01*
Y871439D01*
X627957Y870956D01*
Y870306D01*
X628418Y869845D01*
X629068D01*
X629551Y870328D01*
X630201D01*
X630662Y869867D01*
Y869217D01*
X630179Y868734D01*
Y868084D01*
X630640Y867623D01*
X631290D01*
X631773Y868106D01*
X632423D01*
X632884Y867645D01*
Y866995D01*
X632401Y866512D01*
Y865862D01*
X632862Y865401D01*
X633512D01*
X633995Y865884D01*
X634645D01*
X635106Y865423D01*
Y864773D01*
X634623Y864290D01*
Y863640D01*
X635084Y863179D01*
X635734D01*
X636217Y863662D01*
X636867D01*
X637328Y863201D01*
Y862551D01*
X636845Y862068D01*
Y861418D01*
X637306Y860957D01*
X637956D01*
X638439Y861440D01*
X639089D01*
X639957Y860572D01*
X647354D01*
G01X581255Y939266D02*
X588574D01*
X628636Y899204D01*
Y892699D01*
X630191Y891144D01*
Y890494D01*
X628405Y888710D01*
Y888059D01*
X628866Y887598D01*
X629515D01*
X633016Y891096D01*
X633666D01*
X634127Y890635D01*
Y889985D01*
X633063Y888922D01*
Y888272D01*
X639674Y881661D01*
Y879173D01*
X643216Y875631D01*
X643219D01*
G01X580082Y942236D02*
X580650D01*
X581110Y941776D01*
Y941179D01*
X581570Y940719D01*
X582221D01*
X582681Y941179D01*
Y941776D01*
X583141Y942236D01*
X583792D01*
X584252Y941776D01*
Y941179D01*
X584712Y940719D01*
X585363D01*
X585823Y941179D01*
Y941776D01*
X586283Y942236D01*
X586934D01*
X587394Y941776D01*
Y941179D01*
X587854Y940719D01*
X588505D01*
X588965Y941179D01*
Y941776D01*
X589425Y942236D01*
X591944D01*
X596970Y937210D01*
Y936560D01*
X596509Y936099D01*
X595859D01*
X591507Y940451D01*
X590857D01*
X590396Y939990D01*
Y939340D01*
X629976Y899760D01*
Y896711D01*
X636321Y890366D01*
Y889716D01*
X635290Y888686D01*
Y888036D01*
X635751Y887575D01*
X636401D01*
X637432Y888605D01*
X638082D01*
X638543Y888144D01*
Y887494D01*
X637512Y886464D01*
Y885814D01*
X637973Y885353D01*
X638623D01*
X639654Y886383D01*
X640304D01*
X641014Y885673D01*
Y881689D01*
X645399Y877304D01*
X647354D01*
G01X560346Y938072D02*
X562184Y937025D01*
G01X580925Y943576D02*
X592500D01*
X601071Y935005D01*
Y934355D01*
X600610Y933894D01*
X599960D01*
X598405Y935449D01*
X597755D01*
X597294Y934988D01*
Y934338D01*
X631316Y900316D01*
Y897267D01*
X642354Y886229D01*
Y883830D01*
X643219Y882965D01*
G01X581225Y944916D02*
X593056D01*
X611223Y926749D01*
Y926099D01*
X610762Y925638D01*
X610112D01*
X602518Y933232D01*
X601868D01*
X601407Y932771D01*
Y932121D01*
X632656Y900872D01*
Y897845D01*
X643694Y886807D01*
Y884599D01*
X644296Y883997D01*
X647354D01*
G01X581485Y946716D02*
X593802D01*
X613023Y927495D01*
Y923051D01*
X634456Y901618D01*
Y898694D01*
X643473Y889677D01*
G01X581945Y949449D02*
X595425D01*
X623440Y921434D01*
Y916426D01*
X637136Y902730D01*
Y899979D01*
X639479Y897636D01*
X642660Y896318D01*
X643219Y896087D01*
G01X581575Y948066D02*
X594348D01*
X622100Y920314D01*
Y919664D01*
X621639Y919203D01*
X620989D01*
X615474Y924718D01*
X614824D01*
X614363Y924257D01*
Y923607D01*
X635796Y902174D01*
Y899378D01*
X642095Y893079D01*
X643083D01*
X645472Y890690D01*
X647354D01*
G01X581885Y950839D02*
X595931D01*
X616146Y930624D01*
X617015D01*
X618253Y931863D01*
X618999D01*
X619527Y931335D01*
Y930589D01*
X618289Y929350D01*
Y928604D01*
X618817Y928076D01*
X619563D01*
X620801Y929315D01*
X621547D01*
X622075Y928787D01*
Y928041D01*
X620837Y926802D01*
Y926056D01*
X621365Y925528D01*
X622111D01*
X623349Y926767D01*
X624095D01*
X624623Y926239D01*
Y925493D01*
X623385Y924254D01*
Y923508D01*
X624780Y922113D01*
Y916984D01*
X638476Y903288D01*
Y900739D01*
X640587Y898628D01*
X642660Y897769D01*
X643593Y897383D01*
X647354D01*
G01X560346Y944450D02*
X562184Y943403D01*
G01X580762Y964966D02*
X604995D01*
X641789Y928172D01*
G01X581738Y967669D02*
X611099D01*
X613861Y964907D01*
Y962365D01*
X619904Y956322D01*
Y953850D01*
X639088Y934666D01*
X641399Y933708D01*
X642833Y933114D01*
X643219Y932954D01*
G01X580755Y966319D02*
X605538D01*
X606679Y965178D01*
X607329D01*
X608482Y966329D01*
X609133D01*
X609594Y965868D01*
Y965220D01*
X608440Y964066D01*
Y963417D01*
X608901Y962956D01*
X609551D01*
X611410Y964812D01*
X612060D01*
X612521Y964351D01*
Y963703D01*
X610662Y961844D01*
Y961195D01*
X611123Y960734D01*
X611773D01*
X612341Y961301D01*
X612991D01*
X613452Y960840D01*
Y960190D01*
X612884Y959622D01*
Y958973D01*
X613345Y958512D01*
X613995D01*
X614563Y959079D01*
X615213D01*
X615674Y958618D01*
Y957968D01*
X615106Y957400D01*
Y956751D01*
X615567Y956290D01*
X616217D01*
X616785Y956857D01*
X617435D01*
X617896Y956396D01*
Y955746D01*
X617328Y955178D01*
Y954529D01*
X641338Y930519D01*
X641988D01*
X642512Y931043D01*
X643162D01*
X643623Y930582D01*
Y929932D01*
X643099Y929408D01*
Y928758D01*
X644356Y927501D01*
X647354D01*
G01X581125Y969029D02*
X613537D01*
X616773Y965793D01*
Y965143D01*
X615201Y963571D01*
Y962921D01*
X618544Y959578D01*
X619194D01*
X619655Y960039D01*
Y960689D01*
X617423Y962921D01*
Y963571D01*
X617884Y964032D01*
X618534D01*
X621244Y961322D01*
Y954407D01*
X639848Y935803D01*
X641399Y935160D01*
X642833Y934566D01*
X643732Y934194D01*
X647354D01*
G01X582185Y959026D02*
X598254D01*
X617635Y939645D01*
X622079D01*
X636213Y925511D01*
Y924861D01*
X635823Y924471D01*
Y923821D01*
X636284Y923360D01*
X636934D01*
X637324Y923750D01*
X637974D01*
X639555Y922169D01*
Y916214D01*
X639682Y916082D01*
X639667Y915337D01*
X638758Y914466D01*
X638743Y913721D01*
X639261Y913181D01*
X640007Y913166D01*
X640915Y914037D01*
X641660Y914022D01*
X642048Y913617D01*
X642047Y913614D01*
X643219Y912442D01*
G01X581715Y961759D02*
X599313D01*
X599983Y961089D01*
X600633D01*
X601244Y961700D01*
X601894D01*
X602355Y961239D01*
Y960589D01*
X601744Y959978D01*
Y959328D01*
X609120Y951952D01*
X613566D01*
X642235Y923283D01*
Y920965D01*
X643405Y919795D01*
G01X581995Y960389D02*
X598787D01*
X618191Y940985D01*
X618841D01*
X619302Y941446D01*
Y942096D01*
X611947Y949451D01*
Y950101D01*
X612408Y950562D01*
X613058D01*
X640895Y922725D01*
Y917448D01*
X644228Y914115D01*
X647354D01*
G01X581558Y963106D02*
X604309D01*
X605241Y962174D01*
Y961524D01*
X603667Y959952D01*
Y959302D01*
X609677Y953292D01*
X610327D01*
X610789Y953754D01*
Y954403D01*
X605890Y959302D01*
Y959952D01*
X606352Y960413D01*
X607002D01*
X643575Y923840D01*
Y921521D01*
X644288Y920808D01*
X647354D01*
G01X560346Y963584D02*
X562184Y962537D01*
G01X560346Y957206D02*
X562184Y956159D01*
G01X577792Y985166D02*
X586542Y985163D01*
X589903D01*
X591542Y983524D01*
X621428D01*
X642313Y962639D01*
X643219D01*
G01X580443Y976601D02*
X581148D01*
X581608Y977061D01*
Y978372D01*
X582068Y978832D01*
X582719D01*
X583179Y978372D01*
Y977061D01*
X583639Y976601D01*
X584290D01*
X584750Y977061D01*
Y978372D01*
X585210Y978832D01*
X585861D01*
X586321Y978372D01*
Y977061D01*
X586781Y976601D01*
X616477D01*
X631624Y961454D01*
Y959816D01*
X642187Y949253D01*
X643219D01*
G01X580669Y981563D02*
X588269D01*
X590088Y979744D01*
X617126D01*
X617597Y979273D01*
X618247D01*
X618599Y979625D01*
X619249D01*
X619710Y979164D01*
Y978514D01*
X619358Y978162D01*
Y977512D01*
X631973Y964897D01*
X634483D01*
X643015Y956365D01*
G01X581019Y980223D02*
X587713D01*
X589532Y978404D01*
X616570D01*
X632050Y962924D01*
X632644D01*
X633277Y963557D01*
X633927D01*
X634388Y963096D01*
Y962446D01*
X632964Y961022D01*
Y960372D01*
X633425Y959911D01*
X634075D01*
X635499Y961335D01*
X636149D01*
X636610Y960874D01*
Y960224D01*
X635186Y958800D01*
Y958150D01*
X635647Y957689D01*
X636297D01*
X637721Y959113D01*
X638371D01*
X638832Y958652D01*
Y958002D01*
X637408Y956578D01*
Y955928D01*
X637869Y955467D01*
X638519D01*
X639943Y956891D01*
X640593D01*
X641054Y956430D01*
Y955780D01*
X639630Y954356D01*
Y953706D01*
X640091Y953245D01*
X640741D01*
X642165Y954669D01*
X642815D01*
X643276Y954208D01*
Y953558D01*
X641852Y952134D01*
Y951484D01*
X642410Y950926D01*
X647354D01*
G01X580765Y982903D02*
X588825D01*
X590644Y981084D01*
X620668D01*
X621827Y979926D01*
Y979276D01*
X621068Y978517D01*
Y977867D01*
X621529Y977406D01*
X622179D01*
X622938Y978165D01*
X623588D01*
X624049Y977704D01*
Y977054D01*
X623290Y976295D01*
Y975645D01*
X623751Y975184D01*
X624401D01*
X625160Y975943D01*
X625810D01*
X626271Y975482D01*
Y974832D01*
X625512Y974073D01*
Y973423D01*
X625973Y972962D01*
X626623D01*
X627382Y973721D01*
X628032D01*
X628493Y973260D01*
Y972610D01*
X627734Y971851D01*
Y971201D01*
X628195Y970740D01*
X628845D01*
X629604Y971499D01*
X630254D01*
X630715Y971038D01*
Y970388D01*
X629956Y969629D01*
Y968979D01*
X630417Y968518D01*
X631067D01*
X631826Y969277D01*
X632476D01*
X632937Y968816D01*
Y968166D01*
X632178Y967407D01*
Y966757D01*
X632639Y966296D01*
X633289D01*
X633837Y966844D01*
X634432D01*
X641322Y959955D01*
X641971D01*
X642324Y960308D01*
X642974D01*
X643435Y959847D01*
Y959197D01*
X643083Y958844D01*
Y958194D01*
X643658Y957619D01*
X647354D01*
G01X560346Y976340D02*
X562184Y975293D01*
G01X573299Y985907D02*
X574678Y987286D01*
X589676D01*
X592098Y984864D01*
X621985D01*
X642537Y964312D01*
X647354D01*
G01X581355Y996796D02*
X589628D01*
X595260Y991164D01*
X625323D01*
X640462Y976025D01*
X643219D01*
G01X581442Y998136D02*
X590184D01*
X595816Y992504D01*
X628020D01*
X628821Y991703D01*
Y991053D01*
X628401Y990633D01*
Y989983D01*
X628862Y989522D01*
X629512D01*
X629932Y989942D01*
X630582D01*
X631043Y989481D01*
Y988831D01*
X630623Y988411D01*
Y987761D01*
X631084Y987300D01*
X631734D01*
X632154Y987720D01*
X632804D01*
X633265Y987259D01*
Y986609D01*
X632845Y986189D01*
Y985539D01*
X633306Y985078D01*
X633956D01*
X634376Y985498D01*
X635026D01*
X635487Y985037D01*
Y984387D01*
X635067Y983967D01*
Y983317D01*
X635528Y982856D01*
X636178D01*
X636598Y983276D01*
X637248D01*
X637709Y982815D01*
Y982165D01*
X637289Y981745D01*
Y981095D01*
X637750Y980634D01*
X638400D01*
X638820Y981054D01*
X639470D01*
X639931Y980593D01*
Y979943D01*
X639511Y979523D01*
Y978873D01*
X639972Y978412D01*
X640622D01*
X641042Y978832D01*
X641692D01*
X642826Y977698D01*
X647354D01*
G01X581425Y999476D02*
X590740D01*
X596372Y993844D01*
X629584D01*
X643396Y980032D01*
G01X580172Y990586D02*
X589574D01*
X593036Y987124D01*
X622924D01*
X643382Y966666D01*
G01X578592Y992806D02*
X579052Y993266D01*
X589426D01*
X593828Y988864D01*
X625370D01*
X643229Y971005D01*
X647354D01*
G01X560346Y995474D02*
X562184Y994427D01*
G01X560346Y989096D02*
X562184Y988049D01*
G01X581355Y1000816D02*
X591296D01*
X596928Y995184D01*
X630140D01*
X631940Y993384D01*
X632590D01*
X633425Y994219D01*
X634075D01*
X634536Y993758D01*
Y993108D01*
X633701Y992273D01*
Y991623D01*
X634162Y991162D01*
X634812D01*
X635647Y991997D01*
X636297D01*
X636758Y991536D01*
Y990886D01*
X635923Y990051D01*
Y989401D01*
X636384Y988940D01*
X637034D01*
X637869Y989775D01*
X638519D01*
X638980Y989314D01*
Y988664D01*
X638145Y987829D01*
Y987179D01*
X638606Y986718D01*
X639256D01*
X640091Y987553D01*
X640741D01*
X641202Y987092D01*
Y986442D01*
X640367Y985607D01*
Y984957D01*
X640933Y984391D01*
X647354D01*
G01X581385Y1003374D02*
X590634D01*
X597484Y996524D01*
X633667D01*
X640780Y989411D01*
X643219D01*
G01X581385Y1004714D02*
X591190D01*
X598025Y997879D01*
X620735D01*
X621195Y998339D01*
Y999969D01*
X621655Y1000429D01*
X622306D01*
X622766Y999969D01*
Y998339D01*
X623226Y997879D01*
X623877D01*
X624337Y998339D01*
Y999969D01*
X624797Y1000429D01*
X625448D01*
X625908Y999969D01*
Y998339D01*
X626368Y997879D01*
X627019D01*
X627479Y998339D01*
Y999969D01*
X627939Y1000429D01*
X628590D01*
X629050Y999969D01*
Y998339D01*
X629510Y997879D01*
X630161D01*
X630621Y998339D01*
Y999969D01*
X631081Y1000429D01*
X631732D01*
X632192Y999969D01*
Y998339D01*
X632652Y997879D01*
X635046D01*
X641841Y991084D01*
X647354D01*
G01X581315Y1006054D02*
X591746D01*
X598531Y999269D01*
X618415D01*
X621592Y1002446D01*
X633308D01*
X642337Y993417D01*
G01X581125Y1007394D02*
X592302D01*
X598867Y1000829D01*
X613706D01*
X620990Y1003846D01*
X634188D01*
X641930Y996104D01*
X643219D01*
G01X560346Y1001852D02*
X562184Y1000805D01*
G01X565897Y1011419D02*
X567735Y1010372D01*
G01X567078Y1027009D02*
X568916Y1028056D01*
G01X559677Y1027009D02*
X561515Y1028056D01*
G01X582219Y1030858D02*
X592185D01*
X598830Y1037503D01*
X614752D01*
X626044Y1026211D01*
X659858D01*
X661542Y1027895D01*
X663496D01*
G01X581929Y1032198D02*
X591629D01*
X598274Y1038843D01*
X615308D01*
X622910Y1031241D01*
X625622D01*
X626082Y1030781D01*
Y1029289D01*
X626542Y1028829D01*
X627193D01*
X627653Y1029289D01*
Y1030781D01*
X628113Y1031241D01*
X628764D01*
X629224Y1030781D01*
Y1029289D01*
X629684Y1028829D01*
X630335D01*
X630795Y1029289D01*
Y1030781D01*
X631255Y1031241D01*
X647354D01*
G01X581640Y1034878D02*
X590515D01*
X597160Y1041523D01*
X616421D01*
X620010Y1037934D01*
Y1037933D01*
X623688Y1034255D01*
X625107D01*
X625567Y1034715D01*
Y1035452D01*
X626027Y1035912D01*
X626678D01*
X627138Y1035452D01*
Y1034715D01*
X627598Y1034255D01*
X628249D01*
X628709Y1034715D01*
Y1035452D01*
X629169Y1035912D01*
X629820D01*
X630280Y1035452D01*
Y1034715D01*
X630740Y1034255D01*
X631391D01*
X631851Y1034715D01*
Y1035452D01*
X632311Y1035912D01*
X632962D01*
X633422Y1035452D01*
Y1034715D01*
X633882Y1034255D01*
X634533D01*
X634993Y1034715D01*
Y1035452D01*
X635453Y1035912D01*
X636104D01*
X636564Y1035452D01*
Y1034715D01*
X637024Y1034255D01*
X639884D01*
X643563Y1037934D01*
X647354D01*
G01X582453Y1037421D02*
X591082D01*
X596524Y1042863D01*
X616978D01*
X622589Y1037252D01*
X640863D01*
X643219Y1039608D01*
G01X582177Y1038761D02*
X590526D01*
X595968Y1044203D01*
X617534D01*
X623145Y1038592D01*
X624180D01*
X624640Y1039052D01*
Y1039856D01*
X625100Y1040316D01*
X625751D01*
X626211Y1039856D01*
Y1039052D01*
X626671Y1038592D01*
X627322D01*
X627782Y1039052D01*
Y1039856D01*
X628242Y1040316D01*
X628893D01*
X629353Y1039856D01*
Y1039052D01*
X629813Y1038592D01*
X630464D01*
X630924Y1039052D01*
Y1039856D01*
X631384Y1040316D01*
X632035D01*
X632495Y1039856D01*
Y1039052D01*
X632955Y1038592D01*
X637626D01*
X643661Y1044627D01*
X647354D01*
G01X582137Y1045139D02*
X589318D01*
X593742Y1049563D01*
X619760D01*
X622902Y1046421D01*
X636046D01*
X642619Y1052994D01*
X643219D01*
G01X582354Y1043799D02*
X589874D01*
X594298Y1048223D01*
X605401D01*
X605861Y1047763D01*
Y1047349D01*
X606321Y1046889D01*
X606972D01*
X607432Y1047349D01*
Y1047763D01*
X607892Y1048223D01*
X608543D01*
X609003Y1047763D01*
Y1047349D01*
X609463Y1046889D01*
X610114D01*
X610574Y1047349D01*
Y1047763D01*
X611034Y1048223D01*
X611685D01*
X612145Y1047763D01*
Y1047349D01*
X612605Y1046889D01*
X613256D01*
X613716Y1047349D01*
Y1047763D01*
X614176Y1048223D01*
X614827D01*
X615287Y1047763D01*
Y1047349D01*
X615747Y1046889D01*
X616398D01*
X616858Y1047349D01*
Y1047763D01*
X617318Y1048223D01*
X619203D01*
X622345Y1045081D01*
X623750D01*
X624210Y1044621D01*
Y1043619D01*
X624670Y1043159D01*
X625321D01*
X625781Y1043619D01*
Y1044621D01*
X626241Y1045081D01*
X626892D01*
X627352Y1044621D01*
Y1043619D01*
X627812Y1043159D01*
X628463D01*
X628923Y1043619D01*
Y1044621D01*
X629383Y1045081D01*
X630034D01*
X630494Y1044621D01*
Y1043619D01*
X630954Y1043159D01*
X631605D01*
X632065Y1043619D01*
Y1044621D01*
X632525Y1045081D01*
X633176D01*
X633636Y1044621D01*
Y1043619D01*
X634096Y1043159D01*
X634747D01*
X635207Y1043619D01*
Y1044621D01*
X635667Y1045081D01*
X636602D01*
X642841Y1051320D01*
X647354D01*
G01X559677Y1033387D02*
X561515Y1034434D01*
G01X561527Y1036576D02*
X563365Y1037623D01*
G01X559677Y1039765D02*
X561515Y1040812D01*
G01X561527Y1042954D02*
X563365Y1044001D01*
G01X561527Y1030198D02*
X563365Y1031245D01*
G01X581476Y1050175D02*
X588665D01*
X592073Y1053583D01*
X637260D01*
X643219Y1059542D01*
G01X581682Y1047819D02*
X588205D01*
X592629Y1052243D01*
X624593D01*
X625053Y1051783D01*
Y1049561D01*
X625513Y1049101D01*
X634585D01*
X635045Y1049561D01*
Y1050212D01*
X634585Y1050672D01*
X627084D01*
X626624Y1051132D01*
Y1051783D01*
X627084Y1052243D01*
X637816D01*
X643586Y1058013D01*
X647354D01*
G01X559677Y1058899D02*
X561515Y1059946D01*
G01X561527Y1049332D02*
X563365Y1050379D01*
G01X559677Y1052521D02*
X561515Y1053568D01*
G01X561527Y1055710D02*
X563365Y1056757D01*
G01X559677Y1046143D02*
X561515Y1047190D01*
G01X581790Y1072707D02*
X617465D01*
X618327Y1073569D01*
Y1074219D01*
X617911Y1074635D01*
Y1075285D01*
X618372Y1075746D01*
X619022D01*
X619438Y1075330D01*
X620088D01*
X620549Y1075791D01*
Y1076441D01*
X620133Y1076857D01*
Y1077507D01*
X620594Y1077968D01*
X621244D01*
X621660Y1077552D01*
X622310D01*
X622771Y1078013D01*
Y1078663D01*
X622355Y1079079D01*
Y1079729D01*
X622816Y1080190D01*
X623466D01*
X623882Y1079774D01*
X624532D01*
X624993Y1080235D01*
Y1080885D01*
X624577Y1081301D01*
Y1081951D01*
X625038Y1082412D01*
X625688D01*
X626104Y1081996D01*
X626754D01*
X627215Y1082457D01*
Y1083107D01*
X626799Y1083523D01*
Y1084173D01*
X627260Y1084634D01*
X627910D01*
X628326Y1084218D01*
X628976D01*
X629437Y1084679D01*
Y1085329D01*
X629021Y1085745D01*
Y1086395D01*
X629482Y1086856D01*
X630132D01*
X630548Y1086440D01*
X631198D01*
X631659Y1086901D01*
Y1087551D01*
X631243Y1087967D01*
Y1088617D01*
X631704Y1089078D01*
X632354D01*
X632770Y1088662D01*
X633420D01*
X633881Y1089123D01*
Y1089773D01*
X633465Y1090189D01*
Y1090839D01*
X633926Y1091300D01*
X634576D01*
X634992Y1090884D01*
X635642D01*
X636103Y1091345D01*
Y1091995D01*
X635687Y1092411D01*
Y1093061D01*
X636148Y1093522D01*
X636798D01*
X637214Y1093106D01*
X637864D01*
X638325Y1093567D01*
Y1094217D01*
X637909Y1094633D01*
Y1095283D01*
X638370Y1095744D01*
X639020D01*
X639436Y1095328D01*
X640086D01*
X640547Y1095789D01*
Y1096439D01*
X640131Y1096855D01*
Y1097505D01*
X640592Y1097966D01*
X641242D01*
X641658Y1097550D01*
X642308D01*
X642929Y1098171D01*
X647354D01*
G01X581382Y1062001D02*
X629269D01*
X643219Y1075951D01*
G01X582531Y1060449D02*
X597274D01*
X597734Y1059989D01*
Y1059069D01*
X598194Y1058609D01*
X598845D01*
X599305Y1059069D01*
Y1059989D01*
X599765Y1060449D01*
X600416D01*
X600876Y1059989D01*
Y1059069D01*
X601336Y1058609D01*
X601987D01*
X602447Y1059069D01*
Y1059989D01*
X602907Y1060449D01*
X603558D01*
X604018Y1059989D01*
Y1059069D01*
X604478Y1058609D01*
X605129D01*
X605589Y1059069D01*
Y1059989D01*
X606049Y1060449D01*
X606700D01*
X607160Y1059989D01*
Y1059069D01*
X607620Y1058609D01*
X608271D01*
X608731Y1059069D01*
Y1059989D01*
X609191Y1060449D01*
X609842D01*
X610302Y1059989D01*
Y1059069D01*
X610762Y1058609D01*
X611413D01*
X611873Y1059069D01*
Y1059989D01*
X612333Y1060449D01*
X612984D01*
X613444Y1059989D01*
Y1059069D01*
X613904Y1058609D01*
X614555D01*
X615015Y1059069D01*
Y1059989D01*
X615475Y1060449D01*
X616126D01*
X616586Y1059989D01*
Y1059069D01*
X617046Y1058609D01*
X617697D01*
X618157Y1059069D01*
Y1059989D01*
X618617Y1060449D01*
X619268D01*
X619728Y1059989D01*
Y1059069D01*
X620188Y1058609D01*
X620839D01*
X621299Y1059069D01*
Y1059989D01*
X621759Y1060449D01*
X622410D01*
X622870Y1059989D01*
Y1059069D01*
X623330Y1058609D01*
X623981D01*
X624441Y1059069D01*
Y1059989D01*
X624901Y1060449D01*
X625552D01*
X626012Y1059989D01*
Y1059069D01*
X626472Y1058609D01*
X627123D01*
X627583Y1059069D01*
Y1059989D01*
X628043Y1060449D01*
X629615D01*
X643471Y1074305D01*
Y1074306D01*
X643910Y1074745D01*
X647354D01*
G01X582085Y1063919D02*
X629290D01*
X642553Y1077182D01*
Y1077831D01*
X642091Y1078293D01*
X641441D01*
X636991Y1073843D01*
X636341D01*
X635879Y1074305D01*
Y1074954D01*
X642363Y1081438D01*
X647354D01*
G01X559677Y1071655D02*
X561515Y1072702D01*
G01X561527Y1074844D02*
X563365Y1075891D01*
G01X561527Y1062088D02*
X563365Y1063135D01*
G01X582172Y1074047D02*
X614776D01*
X640573Y1099844D01*
X643219D01*
G01X582240Y1075387D02*
X583404D01*
X584246Y1076229D01*
X584975D01*
X585817Y1075387D01*
X586546D01*
X587388Y1076229D01*
X588117D01*
X588959Y1075387D01*
X589688D01*
X590530Y1076229D01*
X591259D01*
X592101Y1075387D01*
X592830D01*
X593672Y1076229D01*
X594401D01*
X595243Y1075387D01*
X595972D01*
X596814Y1076229D01*
X597543D01*
X598385Y1075387D01*
X599114D01*
X599956Y1076229D01*
X600685D01*
X601527Y1075387D01*
X602256D01*
X603098Y1076229D01*
X603827D01*
X604669Y1075387D01*
X605398D01*
X606240Y1076229D01*
X606969D01*
X607811Y1075387D01*
X608540D01*
X609382Y1076229D01*
X610111D01*
X610953Y1075387D01*
X614220D01*
X615032Y1076199D01*
Y1076849D01*
X613795Y1078087D01*
Y1078737D01*
X614256Y1079198D01*
X614906D01*
X616143Y1077960D01*
X616793D01*
X617254Y1078421D01*
Y1079071D01*
X616017Y1080309D01*
Y1080959D01*
X616478Y1081420D01*
X617128D01*
X618365Y1080182D01*
X619015D01*
X643696Y1104863D01*
X647354D01*
G01X581434Y1082311D02*
X598689D01*
X599149Y1081851D01*
Y1081328D01*
X599609Y1080868D01*
X600260D01*
X600720Y1081328D01*
Y1081851D01*
X601180Y1082311D01*
X611030D01*
X625051Y1096332D01*
X628741D01*
X639307Y1106898D01*
Y1110588D01*
X641949Y1113230D01*
X643219D01*
G01X582238Y1079430D02*
X583409D01*
X584290Y1080311D01*
X584980D01*
X585861Y1079430D01*
X586551D01*
X587432Y1080311D01*
X588122D01*
X589003Y1079430D01*
X589693D01*
X590574Y1080311D01*
X591264D01*
X592145Y1079430D01*
X592835D01*
X593716Y1080311D01*
X594406D01*
X595287Y1079430D01*
X595977D01*
X596858Y1080311D01*
X597548D01*
X598429Y1079430D01*
X610046D01*
X616720Y1086104D01*
X617370D01*
X618565Y1084909D01*
X619215D01*
X619676Y1085370D01*
Y1086020D01*
X618481Y1087215D01*
Y1087865D01*
X618942Y1088326D01*
X619592D01*
X620787Y1087131D01*
X621437D01*
X621898Y1087592D01*
Y1088242D01*
X620703Y1089437D01*
Y1090087D01*
X621164Y1090548D01*
X621814D01*
X623009Y1089353D01*
X623659D01*
X624120Y1089814D01*
Y1090464D01*
X622925Y1091659D01*
Y1092309D01*
X623386Y1092770D01*
X624036D01*
X625231Y1091575D01*
X625881D01*
X626342Y1092036D01*
Y1092686D01*
X625147Y1093881D01*
Y1094531D01*
X625608Y1094992D01*
X626258D01*
X627453Y1093797D01*
X628103D01*
X640705Y1106399D01*
Y1110089D01*
X642172Y1111556D01*
X647354D01*
G01X582441Y1083651D02*
X610474D01*
X626129Y1099306D01*
X626779D01*
X627869Y1098215D01*
X628519D01*
X628980Y1098676D01*
Y1099326D01*
X627890Y1100417D01*
Y1101067D01*
X628351Y1101528D01*
X629001D01*
X630091Y1100437D01*
X630741D01*
X631202Y1100898D01*
Y1101548D01*
X630112Y1102639D01*
Y1103289D01*
X630573Y1103750D01*
X631223D01*
X632313Y1102659D01*
X632963D01*
X633424Y1103120D01*
Y1103770D01*
X632334Y1104861D01*
Y1105511D01*
X632795Y1105972D01*
X633445D01*
X634535Y1104881D01*
X635185D01*
X635646Y1105342D01*
Y1105992D01*
X634556Y1107083D01*
Y1107733D01*
X635017Y1108194D01*
X635667D01*
X636757Y1107103D01*
X637407D01*
X637868Y1107564D01*
Y1108214D01*
X636778Y1109305D01*
Y1109955D01*
X645072Y1118249D01*
X647354D01*
G01X559677Y1078033D02*
X561515Y1079080D01*
G01X561527Y1081222D02*
X563365Y1082269D01*
G01X582475Y1098843D02*
X597809D01*
X598443Y1099477D01*
Y1100127D01*
X598079Y1100491D01*
Y1101141D01*
X598540Y1101602D01*
X599190D01*
X600568Y1100224D01*
X601218D01*
X601679Y1100685D01*
Y1101335D01*
X600301Y1102713D01*
Y1103363D01*
X600762Y1103824D01*
X601412D01*
X602790Y1102446D01*
X603440D01*
X603901Y1102907D01*
Y1103557D01*
X602523Y1104935D01*
Y1105585D01*
X602984Y1106046D01*
X603634D01*
X605012Y1104668D01*
X605662D01*
X606123Y1105129D01*
Y1105779D01*
X604745Y1107157D01*
Y1107807D01*
X605206Y1108268D01*
X605856D01*
X607234Y1106890D01*
X607884D01*
X608345Y1107351D01*
Y1108001D01*
X606967Y1109379D01*
Y1110029D01*
X607428Y1110490D01*
X608078D01*
X609456Y1109112D01*
X610106D01*
X610567Y1109573D01*
Y1110223D01*
X609189Y1111601D01*
Y1112251D01*
X610303Y1113365D01*
X610895Y1113364D01*
X611054Y1113205D01*
X611648D01*
X612165Y1113722D01*
X612166Y1114316D01*
X612007Y1114475D01*
Y1115069D01*
X612525Y1115587D01*
X613117Y1115586D01*
X613276Y1115427D01*
X613870D01*
X614387Y1115944D01*
X614388Y1116538D01*
X614229Y1116697D01*
Y1117291D01*
X614747Y1117809D01*
X615339Y1117808D01*
X615498Y1117649D01*
X616092D01*
X616609Y1118166D01*
X616610Y1118760D01*
X616451Y1118919D01*
Y1119513D01*
X616969Y1120031D01*
X617561Y1120030D01*
X617720Y1119871D01*
X618314D01*
X618831Y1120388D01*
X618832Y1120982D01*
X618673Y1121141D01*
Y1121735D01*
X620206Y1123268D01*
X622234D01*
X641580Y1142614D01*
Y1146038D01*
X643909Y1148367D01*
X647354D01*
G01X582089Y1101523D02*
X594668D01*
X620916Y1127771D01*
X621566D01*
X621886Y1127451D01*
X622536D01*
X622997Y1127912D01*
Y1128562D01*
X622677Y1128882D01*
Y1129532D01*
X623138Y1129993D01*
X623788D01*
X624108Y1129673D01*
X624758D01*
X625219Y1130134D01*
Y1130784D01*
X624899Y1131104D01*
Y1131754D01*
X625360Y1132215D01*
X626010D01*
X626330Y1131895D01*
X626980D01*
X627441Y1132356D01*
Y1133006D01*
X627121Y1133326D01*
Y1133976D01*
X627582Y1134437D01*
X628232D01*
X628552Y1134117D01*
X629202D01*
X629663Y1134578D01*
Y1135228D01*
X629343Y1135548D01*
Y1136198D01*
X629804Y1136659D01*
X630454D01*
X630774Y1136339D01*
X631424D01*
X631885Y1136800D01*
Y1137450D01*
X631565Y1137770D01*
Y1138420D01*
X632026Y1138881D01*
X632676D01*
X632996Y1138561D01*
X633646D01*
X634107Y1139022D01*
Y1139672D01*
X633787Y1139992D01*
Y1140642D01*
X634248Y1141103D01*
X634898D01*
X635218Y1140783D01*
X635868D01*
X636329Y1141244D01*
Y1141894D01*
X636009Y1142214D01*
Y1142864D01*
X636470Y1143325D01*
X637120D01*
X637440Y1143005D01*
X638090D01*
X638551Y1143466D01*
Y1144116D01*
X638231Y1144436D01*
Y1145086D01*
X638900Y1145755D01*
Y1148168D01*
X642380Y1151648D01*
Y1152298D01*
X641919Y1152759D01*
X641269D01*
X639677Y1151167D01*
X639027D01*
X638566Y1151628D01*
Y1152278D01*
X641269Y1154981D01*
X641919D01*
X643491Y1153409D01*
X644141D01*
X645792Y1155060D01*
X647354D01*
G01X582170Y1094149D02*
X601627D01*
X643473Y1135995D01*
G01X581445Y1092569D02*
X602247D01*
X603736Y1094058D01*
X604386D01*
X605805Y1092639D01*
X606455D01*
X606916Y1093100D01*
Y1093750D01*
X605497Y1095169D01*
Y1095819D01*
X605958Y1096280D01*
X606608D01*
X608027Y1094861D01*
X608677D01*
X609138Y1095322D01*
Y1095972D01*
X607719Y1097391D01*
Y1098041D01*
X608180Y1098502D01*
X608830D01*
X610249Y1097083D01*
X610899D01*
X611360Y1097544D01*
Y1098194D01*
X609941Y1099613D01*
Y1100263D01*
X610402Y1100724D01*
X611052D01*
X612131Y1099645D01*
X612781D01*
X613242Y1100106D01*
Y1100756D01*
X612163Y1101835D01*
Y1102485D01*
X622101Y1112423D01*
Y1112431D01*
X644652Y1134982D01*
X647354D01*
G01X582667Y1095564D02*
X601146D01*
X628973Y1123391D01*
Y1123426D01*
X631608Y1126061D01*
Y1126710D01*
X631188Y1127130D01*
Y1127780D01*
X631649Y1128241D01*
X632299D01*
X632719Y1127822D01*
X633369D01*
X633830Y1128283D01*
Y1128932D01*
X633410Y1129352D01*
Y1130002D01*
X633871Y1130463D01*
X634521D01*
X634941Y1130044D01*
X635591D01*
X636052Y1130505D01*
Y1131154D01*
X635632Y1131574D01*
Y1132224D01*
X636093Y1132685D01*
X636743D01*
X637163Y1132266D01*
X637813D01*
X638274Y1132727D01*
Y1133376D01*
X637854Y1133796D01*
Y1134446D01*
X638315Y1134907D01*
X638965D01*
X639385Y1134488D01*
X640035D01*
X640496Y1134949D01*
Y1135598D01*
X640076Y1136018D01*
Y1136668D01*
X640537Y1137129D01*
X641187D01*
X641607Y1136710D01*
X642257D01*
X642766Y1137219D01*
Y1139324D01*
X645117Y1141675D01*
X647354D01*
G01X582340Y1100183D02*
X595225D01*
X619860Y1124818D01*
X621888D01*
X640240Y1143170D01*
Y1146597D01*
X643219Y1149576D01*
G01X561527Y1100356D02*
X563365Y1101403D01*
G01X559677Y1090789D02*
X561515Y1091836D01*
G01X561527Y1093978D02*
X563365Y1095025D01*
G01X559677Y1097167D02*
X561515Y1098214D01*
G01X582666Y1114527D02*
X593284D01*
X618380Y1139623D01*
Y1153202D01*
X638644Y1173466D01*
X643219D01*
G01X581218Y1113057D02*
X593710D01*
X622862Y1142209D01*
Y1151074D01*
X622402Y1151534D01*
X621751D01*
X621291Y1151074D01*
Y1143179D01*
X620831Y1142719D01*
X620180D01*
X619720Y1143179D01*
Y1152645D01*
X620180Y1153105D01*
X622402D01*
X622862Y1153565D01*
Y1155288D01*
X639367Y1171793D01*
X647354D01*
G01X582632Y1115867D02*
X592727D01*
X617040Y1140180D01*
Y1153759D01*
X639234Y1175953D01*
Y1176602D01*
X638772Y1177064D01*
X638122D01*
X635280Y1174222D01*
X634630D01*
X634168Y1174683D01*
Y1175333D01*
X638121Y1179286D01*
X638771D01*
X640345Y1177714D01*
X640995D01*
X641767Y1178486D01*
X647354D01*
G01X581310Y1120425D02*
X590947D01*
X612560Y1142038D01*
Y1155752D01*
X615070Y1158262D01*
Y1162574D01*
X639348Y1186852D01*
X643219D01*
G01X581487Y1119017D02*
X591435D01*
X613900Y1141482D01*
Y1155196D01*
X618318Y1159614D01*
Y1160264D01*
X616824Y1161758D01*
Y1162408D01*
X617285Y1162869D01*
X617935D01*
X619429Y1161375D01*
X620079D01*
X620540Y1161836D01*
Y1162486D01*
X619034Y1163992D01*
Y1164642D01*
X619495Y1165103D01*
X620145D01*
X621651Y1163597D01*
X622301D01*
X622762Y1164058D01*
Y1164708D01*
X621256Y1166214D01*
Y1166864D01*
X621717Y1167325D01*
X622367D01*
X623873Y1165819D01*
X624523D01*
X624984Y1166280D01*
Y1166930D01*
X623478Y1168436D01*
Y1169086D01*
X623939Y1169547D01*
X624589D01*
X626095Y1168041D01*
X626745D01*
X627206Y1168502D01*
Y1169152D01*
X625700Y1170658D01*
Y1171308D01*
X626161Y1171769D01*
X626811D01*
X628317Y1170263D01*
X628967D01*
X629428Y1170724D01*
Y1171374D01*
X627922Y1172880D01*
Y1173530D01*
X628383Y1173991D01*
X629033D01*
X629917Y1173107D01*
X630567D01*
X631028Y1173568D01*
Y1174218D01*
X630144Y1175102D01*
Y1175752D01*
X639570Y1185178D01*
X647354D01*
G01X559677Y1109923D02*
X561515Y1110970D01*
G01X561527Y1113112D02*
X563365Y1114159D01*
G01X559677Y1116301D02*
X561515Y1117348D01*
G01X561527Y1119490D02*
X563365Y1120537D01*
G01X581135Y1121818D02*
X590444D01*
X608921Y1140295D01*
Y1141680D01*
X609381Y1142140D01*
X610655D01*
X611115Y1142600D01*
Y1143251D01*
X610655Y1143711D01*
X609381D01*
X608921Y1144171D01*
Y1144822D01*
X609381Y1145282D01*
X610655D01*
X611115Y1145742D01*
Y1146393D01*
X610655Y1146853D01*
X609381D01*
X608921Y1147313D01*
Y1147964D01*
X609381Y1148424D01*
X610655D01*
X611115Y1148884D01*
Y1149535D01*
X610655Y1149995D01*
X609381D01*
X608921Y1150455D01*
Y1151106D01*
X609381Y1151566D01*
X610655D01*
X611115Y1152026D01*
Y1152677D01*
X610655Y1153137D01*
X609381D01*
X608921Y1153597D01*
Y1154248D01*
X609381Y1154708D01*
X610655D01*
X611115Y1155168D01*
Y1155819D01*
X610655Y1156279D01*
X609381D01*
X608921Y1156739D01*
Y1158465D01*
X610035Y1159574D01*
X610684Y1159573D01*
X612147Y1158103D01*
X612797Y1158102D01*
X613260Y1158563D01*
X613261Y1159212D01*
X611798Y1160681D01*
X611799Y1161331D01*
X642471Y1191871D01*
X647354D01*
G01X582337Y1133892D02*
X587525D01*
X598811Y1145178D01*
Y1169829D01*
X611590Y1182608D01*
X614656D01*
X642325Y1210277D01*
X643219D01*
G01X582265Y1132552D02*
X588081D01*
X600151Y1144622D01*
Y1166206D01*
X601459Y1167514D01*
Y1168164D01*
X600575Y1169047D01*
Y1169697D01*
X601036Y1170158D01*
X601686D01*
X602570Y1169275D01*
X603220D01*
X603681Y1169736D01*
Y1170386D01*
X602797Y1171269D01*
Y1171919D01*
X603258Y1172380D01*
X603908D01*
X604792Y1171497D01*
X605442D01*
X605903Y1171958D01*
Y1172608D01*
X605019Y1173491D01*
Y1174141D01*
X605480Y1174602D01*
X606130D01*
X607014Y1173719D01*
X607664D01*
X608125Y1174180D01*
Y1174830D01*
X607241Y1175713D01*
Y1176363D01*
X607702Y1176824D01*
X608352D01*
X609236Y1175941D01*
X609886D01*
X610347Y1176402D01*
Y1177052D01*
X609463Y1177935D01*
Y1178585D01*
X609924Y1179046D01*
X610574D01*
X611458Y1178163D01*
X612108D01*
X612569Y1178624D01*
Y1179274D01*
X611685Y1180157D01*
Y1180807D01*
X612146Y1181268D01*
X612796D01*
X613680Y1180385D01*
X614330D01*
X642477Y1208532D01*
X642651Y1208604D01*
X647354D01*
G01X582470Y1135232D02*
X586969D01*
X597471Y1145734D01*
Y1170385D01*
X612175Y1185089D01*
X612825D01*
X613665Y1184249D01*
X614315D01*
X614776Y1184710D01*
Y1185360D01*
X613936Y1186200D01*
Y1186850D01*
X614397Y1187311D01*
X615047D01*
X615887Y1186471D01*
X616537D01*
X616998Y1186932D01*
Y1187582D01*
X616158Y1188422D01*
Y1189072D01*
X616619Y1189533D01*
X617269D01*
X618109Y1188693D01*
X618759D01*
X619220Y1189154D01*
Y1189804D01*
X618380Y1190644D01*
Y1191294D01*
X618841Y1191755D01*
X619491D01*
X620331Y1190915D01*
X620981D01*
X621442Y1191376D01*
Y1192026D01*
X620602Y1192866D01*
Y1193516D01*
X621063Y1193977D01*
X621713D01*
X622553Y1193137D01*
X623203D01*
X645363Y1215297D01*
X647354D01*
G01X559677Y1129057D02*
X561515Y1130103D01*
G01X561527Y1132246D02*
X563365Y1133293D01*
G01X581545Y1139712D02*
X585081D01*
X592991Y1147622D01*
Y1173707D01*
X625666Y1206382D01*
X630110D01*
X636814Y1213086D01*
Y1217530D01*
X642947Y1223663D01*
G01X581648Y1138372D02*
X585637D01*
X594331Y1147066D01*
Y1173151D01*
X626222Y1205042D01*
X626872D01*
X627333Y1204581D01*
Y1203931D01*
X621630Y1198228D01*
Y1197578D01*
X622091Y1197117D01*
X622741D01*
X638154Y1212530D01*
Y1216232D01*
X638688Y1216766D01*
X639338D01*
X640465Y1215639D01*
X641115D01*
X641576Y1216100D01*
Y1216750D01*
X640449Y1217877D01*
Y1218527D01*
X643911Y1221989D01*
X647354D01*
G01X581443Y1141052D02*
X584279D01*
X591651Y1148424D01*
Y1174541D01*
X626404Y1209294D01*
X627054D01*
X628626Y1207722D01*
X629276D01*
X635474Y1213920D01*
Y1214570D01*
X635013Y1215031D01*
X634363D01*
X629276Y1209944D01*
X628626D01*
X628165Y1210405D01*
Y1211055D01*
X645792Y1228682D01*
X647354D01*
G01X559677Y1135434D02*
X561515Y1136481D01*
G01X561527Y1138623D02*
X563365Y1139670D01*
G01X559677Y1148190D02*
X561515Y1149237D01*
G01X561527Y1164135D02*
Y1177746D01*
X618090Y1234309D01*
Y1261117D01*
X615591Y1263616D01*
Y1282038D01*
G01X565228Y1157757D02*
X567066Y1158804D01*
G01X581480Y1155615D02*
Y1185201D01*
X643219Y1246940D01*
G01X580940Y1151341D02*
X582821Y1153222D01*
Y1178725D01*
X597145Y1193049D01*
Y1198209D01*
X606705Y1207769D01*
X607355D01*
X609430Y1205694D01*
X610080D01*
X610541Y1206155D01*
Y1206805D01*
X608466Y1208880D01*
Y1209530D01*
X608927Y1209991D01*
X609577D01*
X611652Y1207916D01*
X612302D01*
X612763Y1208377D01*
Y1209027D01*
X610688Y1211102D01*
Y1211752D01*
X611149Y1212213D01*
X611799D01*
X613049Y1210963D01*
X613699D01*
X614160Y1211424D01*
Y1212074D01*
X612910Y1213324D01*
Y1213974D01*
X644097Y1245162D01*
X644351Y1245415D01*
X647354D01*
G01X561527Y1151379D02*
X563365Y1152426D01*
G01X565228Y1164135D02*
X567066Y1165182D01*
G01X567078Y1160946D02*
X568916Y1161993D01*
G01X564509Y1268089D02*
X568447D01*
X568451Y1268093D01*
G01D02*
Y1293902D01*
X602484Y1327935D01*
Y1383318D01*
X629081Y1409915D01*
X648836D01*
X673446Y1434525D01*
X675272D01*
G01X571692Y1519807D02*
X568344D01*
X567658Y1519121D01*
Y1517329D01*
X566559Y1516230D01*
X562132D01*
X561523Y1516839D01*
Y1518040D01*
G01Y1514420D02*
Y1513230D01*
X562143Y1512610D01*
X566530D01*
X568296Y1514376D01*
Y1514803D01*
X570938Y1517445D01*
X571692D01*
G01X570980Y1513218D02*
X573054D01*
X573738Y1513902D01*
G01X569722Y1521612D02*
X570346Y1520988D01*
X573738D01*
G01X569321Y1518121D02*
X570316D01*
X570821Y1518626D01*
X573738D01*
G01X561523Y1510800D02*
Y1510198D01*
X563030Y1508691D01*
X567833D01*
X569307Y1510165D01*
Y1514568D01*
X571003Y1516264D01*
X573738D01*
G01Y1535162D02*
X570304D01*
X569768Y1535698D01*
G01X571692Y1536343D02*
X570137Y1537898D01*
X569768D01*
G01X573738Y1532799D02*
X570276D01*
X568021Y1535054D01*
Y1540081D01*
X578680Y1550740D01*
Y1555570D01*
X578944Y1555834D01*
G01X571692Y1531618D02*
X569321D01*
X566520Y1534419D01*
Y1540405D01*
X572959Y1546844D01*
Y1551952D01*
X572023Y1552888D01*
X571372D01*
G01X573738Y1530437D02*
X568042D01*
X564924Y1533555D01*
Y1550552D01*
X564372Y1551104D01*
Y1553688D01*
G01X567214Y1544299D02*
X566406Y1545107D01*
Y1552096D01*
X567198Y1552888D01*
X568172D01*
G01X571372Y1555788D02*
Y1552888D01*
G01Y1555788D02*
X572421D01*
X573303Y1556670D01*
Y1560171D01*
X572395Y1561079D01*
G01X564372Y1553688D02*
X563271D01*
X562690Y1554269D01*
Y1562097D01*
X569920Y1569327D01*
X572243D01*
G01X564372Y1555788D02*
X568172D01*
G01Y1552888D02*
Y1555788D01*
G01X574595Y53543D02*
Y48408D01*
X575331Y47672D01*
G01X579060Y77970D02*
X583030Y74000D01*
X588274D01*
X593925Y68349D01*
Y65157D01*
G01X582193Y90098D02*
X586394D01*
G01D02*
X587371Y89121D01*
Y79471D01*
X586394Y78494D01*
G01X596287Y65157D02*
Y68567D01*
X586394Y78460D01*
Y78494D01*
G01X582193Y86248D02*
X584752D01*
G01X578454Y83064D02*
Y78470D01*
X578954Y77970D01*
X579060D01*
G01X578454Y86214D02*
Y88926D01*
G01X586778Y164356D02*
X589203D01*
G01X586778D02*
Y165356D01*
X585402Y166732D01*
X578954D01*
X577578Y165356D01*
Y164356D01*
G01X586778Y169415D02*
X589203D01*
G01X586778D02*
Y170415D01*
X585402Y171791D01*
X578954D01*
X577578Y170415D01*
Y169415D01*
G01X575462Y193516D02*
Y191806D01*
X575425Y191769D01*
Y189835D01*
G01X578612Y193516D02*
X581490D01*
X582124Y194150D01*
G01X575477Y197481D02*
X575440Y197518D01*
Y200785D01*
G01X578627Y197481D02*
X582002D01*
G01X579428Y223921D02*
X580866D01*
X582766Y222021D01*
Y221421D01*
G01X588215Y214079D02*
X590152D01*
X590954Y213277D01*
G01X574311Y235821D02*
Y233221D01*
X575098Y232434D01*
Y228252D01*
G01X596761Y257431D02*
Y254261D01*
X580321Y237821D01*
X576311D01*
X574311Y235821D01*
G01X579428Y225496D02*
X582766D01*
G01X581099Y261171D02*
Y257171D01*
G01D02*
X583181D01*
X587181Y261171D01*
X588099D01*
G01X581099D02*
Y263680D01*
G01X583035Y366827D02*
X586157D01*
G01X573782Y373868D02*
X577644D01*
X579885Y371627D01*
G01Y366827D02*
Y371627D01*
G01X585585Y374477D02*
Y372052D01*
G01X573782Y384668D02*
X576482D01*
X577482Y383668D01*
G01X585585Y377627D02*
Y382427D01*
G01D02*
X578904D01*
X575463Y378986D01*
X573782D01*
G01X585585Y374477D02*
X589355Y378247D01*
Y385530D01*
X587658Y387227D01*
X585585D01*
G01X590235Y400287D02*
X588710D01*
X587710Y399287D01*
G01X585585Y395177D02*
X580468D01*
X575077Y389786D01*
X573782D01*
G01X585585Y395177D02*
Y390377D01*
G01X583048Y415846D02*
X578248D01*
G01X583048D02*
Y411846D01*
G01X586198D02*
X590998D01*
G01X586198Y427949D02*
X588723D01*
G01X583048D02*
Y423949D01*
G01D02*
X578248D01*
G01X586217Y431976D02*
X588742D01*
G01X583067D02*
X578267D01*
G01X586198Y435949D02*
X588798D01*
G01X586781Y454242D02*
X589023Y452000D01*
X592500D01*
X593781Y453281D01*
Y454242D01*
G01X586500Y464425D02*
Y461075D01*
G01X580075Y475500D02*
Y479500D01*
G01X586500Y464425D02*
X587641D01*
X589507Y462559D01*
G01X593724Y486000D02*
X593000D01*
X589000Y482000D01*
X586507D01*
X584165Y479658D01*
G01X580075Y479500D02*
X584007D01*
X584165Y479658D01*
G01X575216Y759762D02*
Y764437D01*
G01Y772262D02*
Y767587D01*
G01X581585Y1033538D02*
X591072D01*
X597717Y1040183D01*
X615864D01*
X623132Y1032915D01*
X643219D01*
G01X582332Y1040101D02*
X589969D01*
X595411Y1045543D01*
X618090D01*
X621977Y1041656D01*
X636969D01*
X641614Y1046301D01*
X643219D01*
G01X581831Y1058523D02*
X583171Y1057183D01*
X584505D01*
X584965Y1057643D01*
Y1058439D01*
X585425Y1058899D01*
X586076D01*
X586536Y1058439D01*
Y1057643D01*
X586996Y1057183D01*
X587647D01*
X588107Y1057643D01*
Y1058439D01*
X588567Y1058899D01*
X589218D01*
X589678Y1058439D01*
Y1057643D01*
X590138Y1057183D01*
X590789D01*
X591249Y1057643D01*
Y1058439D01*
X591709Y1058899D01*
X592360D01*
X592820Y1058439D01*
Y1057643D01*
X593280Y1057183D01*
X593931D01*
X594391Y1057643D01*
Y1058439D01*
X594851Y1058899D01*
X595502D01*
X595962Y1058439D01*
Y1057643D01*
X596422Y1057183D01*
X628245D01*
X643495Y1072433D01*
G01X581724Y1052855D02*
X587553D01*
X589621Y1054923D01*
X632677D01*
X643494Y1065740D01*
G01X582013Y1071367D02*
X618022D01*
X639806Y1093151D01*
X643219D01*
G01X582373Y1078090D02*
X610602D01*
X615732Y1083220D01*
X619506D01*
X642045Y1105759D01*
Y1108609D01*
X643219Y1109783D01*
G01X582576Y1091135D02*
X607328D01*
X614582Y1098389D01*
Y1103007D01*
X641537Y1129962D01*
X643219D01*
G01X582272Y1097489D02*
X600395D01*
X613566Y1110660D01*
Y1111310D01*
X613194Y1111682D01*
Y1112332D01*
X613655Y1112793D01*
X614305D01*
X614677Y1112421D01*
X615327D01*
X615788Y1112882D01*
Y1113532D01*
X615416Y1113904D01*
Y1114554D01*
X615877Y1115015D01*
X616527D01*
X616899Y1114643D01*
X617549D01*
X618010Y1115104D01*
Y1115754D01*
X617638Y1116126D01*
Y1116776D01*
X618099Y1117237D01*
X618749D01*
X619121Y1116865D01*
X619771D01*
X620232Y1117326D01*
Y1117976D01*
X619860Y1118348D01*
Y1118998D01*
X620321Y1119459D01*
X620971D01*
X621343Y1119087D01*
X621993D01*
X622454Y1119548D01*
Y1120198D01*
X622082Y1120570D01*
Y1121220D01*
X622543Y1121681D01*
X623193D01*
X623565Y1121309D01*
X624215D01*
X624676Y1121770D01*
Y1122420D01*
X624304Y1122792D01*
Y1123442D01*
X624765Y1123903D01*
X625415D01*
X625787Y1123531D01*
X626437D01*
X626898Y1123992D01*
Y1124642D01*
X626526Y1125014D01*
Y1125664D01*
X626987Y1126125D01*
X627637D01*
X628009Y1125753D01*
X628659D01*
X629120Y1126214D01*
Y1126864D01*
X628748Y1127236D01*
Y1127886D01*
X642920Y1142058D01*
Y1145481D01*
X643494Y1146055D01*
G01X582171Y1111717D02*
X594266D01*
X624202Y1141653D01*
Y1154731D01*
X636244Y1166773D01*
X643219D01*
G01X581971Y1117667D02*
X591981D01*
X615240Y1140926D01*
Y1154506D01*
X632368Y1171634D01*
Y1176080D01*
X639793Y1183505D01*
X643219D01*
G01X582249Y1131212D02*
X583600D01*
X584060Y1130752D01*
Y1130349D01*
X584520Y1129889D01*
X585171D01*
X585631Y1130349D01*
Y1130752D01*
X586091Y1131212D01*
X588637D01*
X601491Y1144066D01*
Y1165649D01*
X639426Y1203584D01*
X643219D01*
G01X581506Y1137032D02*
X586193D01*
X595671Y1146510D01*
Y1171131D01*
X620317Y1195777D01*
X623297D01*
X642995Y1215475D01*
Y1219177D01*
X643495Y1219677D01*
G01X582228Y1150617D02*
X584161Y1152550D01*
Y1177878D01*
X607880Y1201597D01*
Y1202247D01*
X605932Y1204194D01*
Y1204844D01*
X606393Y1205305D01*
X607043D01*
X608991Y1203358D01*
X609641D01*
X615686Y1209403D01*
Y1214081D01*
X642000Y1240395D01*
X643219D01*
G01X574480Y1154568D02*
X575511Y1155599D01*
X578225D01*
X580135Y1157509D01*
Y1186451D01*
X629367Y1235683D01*
Y1236333D01*
X628264Y1237435D01*
Y1238085D01*
X628725Y1238546D01*
X629375D01*
X630478Y1237444D01*
X631128D01*
X631589Y1237905D01*
Y1238555D01*
X630486Y1239657D01*
Y1240307D01*
X630947Y1240768D01*
X631597D01*
X632700Y1239666D01*
X633350D01*
X633811Y1240127D01*
Y1240777D01*
X632708Y1241879D01*
Y1242529D01*
X633169Y1242990D01*
X633819D01*
X634922Y1241888D01*
X635572D01*
X636033Y1242349D01*
Y1242999D01*
X634930Y1244101D01*
Y1244751D01*
X635391Y1245212D01*
X636041D01*
X637144Y1244110D01*
X637794D01*
X638255Y1244571D01*
Y1245221D01*
X637152Y1246323D01*
Y1246973D01*
X637613Y1247434D01*
X638263D01*
X638969Y1246729D01*
X639366Y1246332D01*
X640016D01*
X640477Y1246793D01*
Y1247443D01*
X639374Y1248545D01*
Y1249195D01*
X639835Y1249656D01*
X640485D01*
X641040Y1249102D01*
X641557Y1248585D01*
X642269D01*
X645792Y1252108D01*
X647354D01*
G01X596621Y1240366D02*
X579153D01*
X576731Y1242788D01*
X575971Y1244623D01*
Y1255876D01*
X579440Y1259345D01*
Y1290668D01*
X593036Y1304264D01*
X619579D01*
X645126Y1278717D01*
Y1272683D01*
X651308Y1266501D01*
X828246D01*
G01X587596Y1266668D02*
Y1262668D01*
G01D02*
X585591D01*
X584271Y1263988D01*
G01X575649Y1559939D02*
Y1557039D01*
G01D02*
X577739D01*
X578944Y1555834D01*
G01X601012Y53543D02*
X600874Y53405D01*
Y44071D01*
X599284Y42481D01*
G01X608098Y53543D02*
Y48417D01*
X608995Y47520D01*
Y41187D01*
X605784Y37976D01*
Y33857D01*
X604837Y32910D01*
X602837D01*
G01X603374Y53543D02*
Y48333D01*
X603064Y48023D01*
G01X598650Y53543D02*
Y48741D01*
X597956Y48047D01*
G01X596287Y53543D02*
Y50623D01*
X596151Y50487D01*
Y48463D01*
X593996Y46308D01*
X591938D01*
G01X601012Y65157D02*
Y72918D01*
X594747Y79183D01*
Y105477D01*
X596068Y106798D01*
G01X598650Y65157D02*
Y70404D01*
X590501Y78553D01*
Y86909D01*
G01X602280Y90098D02*
X602287Y90091D01*
Y85071D01*
G01X608098Y65157D02*
Y74586D01*
X602287Y80397D01*
Y85071D01*
G01X605736Y65157D02*
Y74385D01*
X601500Y78621D01*
X599248D01*
X598349Y79520D01*
Y93848D01*
X597275Y94922D01*
G01X590501Y86909D02*
Y90098D01*
G01X602280Y93248D02*
Y97762D01*
X599295Y100747D01*
G01D02*
X599580D01*
X602328Y103495D01*
G01X590512D02*
X590501Y103484D01*
Y101767D01*
X591811Y100457D01*
Y97421D01*
G01D02*
X590501Y96111D01*
Y93248D01*
G01X600195Y132270D02*
Y136405D01*
X600192Y136408D01*
G01X617420Y119640D02*
X604790Y132270D01*
X603345D01*
G01X603342Y136408D02*
X606064D01*
X619240Y123232D01*
G01X603344Y145640D02*
X605853D01*
G01X600194D02*
Y149640D01*
G01X589423Y152080D02*
X594329D01*
X597769Y148640D01*
G01X600194Y149640D02*
X598769D01*
X597769Y148640D01*
G01X595394Y144640D02*
Y146621D01*
X592789Y149226D01*
X589423D01*
G01X595394Y144640D02*
X598394Y141640D01*
X600194D01*
G01X600192Y136408D02*
Y141638D01*
X600194Y141640D01*
G01X603344D02*
Y139131D01*
G01X595203Y167856D02*
X592703D01*
X589203Y164356D01*
G01X589423Y154640D02*
X596769D01*
X597769Y153640D01*
G01D02*
X600194D01*
G01X602703Y157640D02*
X602100D01*
X600194Y155734D01*
Y153640D01*
G01X595203Y170415D02*
X592663D01*
X591663Y169415D01*
X589203D01*
G01X608794Y191186D02*
X606384Y188776D01*
X600161D01*
G01X598294Y201336D02*
X596356D01*
X593661Y198641D01*
Y188776D01*
G01X598294Y198186D02*
X597293Y197185D01*
Y193186D01*
G01X594098Y208991D02*
Y213271D01*
X594104Y213277D01*
G01X602293Y206186D02*
Y203787D01*
X602294Y203786D01*
G01Y201336D02*
Y203786D01*
G01X602293Y209336D02*
Y212142D01*
X599974Y214461D01*
G01X598294Y198186D02*
X602294D01*
G01X594104Y217277D02*
Y221277D01*
G01D02*
X594446D01*
X599030Y225861D01*
G01X604717Y223893D02*
X603145D01*
X599030Y219778D01*
Y219777D01*
G01X594104Y213277D02*
Y214231D01*
X599030Y219157D01*
Y219777D01*
G01X599974Y214461D02*
X602530Y217017D01*
Y220777D01*
X603677Y221924D01*
X604717D01*
G01Y225861D02*
X599030D01*
G01X594104Y225277D02*
Y229277D01*
G01X594105Y234277D02*
X600552Y227830D01*
X604717D01*
G01X594104Y229277D02*
Y234276D01*
X594105Y234277D01*
G01X600494Y232821D02*
X605423D01*
X607276Y230968D01*
Y230389D01*
G01X611118Y359462D02*
X617620Y352960D01*
Y330100D01*
X629340Y318380D01*
X651090D01*
X657160Y312310D01*
Y290800D01*
X645765Y279405D01*
X605837D01*
X603620Y277188D01*
Y267200D01*
X601970Y265550D01*
X598749D01*
X596761Y263562D01*
Y257431D01*
G01X601908Y373868D02*
X599925D01*
X598414Y372357D01*
G01X601908Y378986D02*
X595823D01*
X592248Y382561D01*
Y389786D01*
G01X601908Y384668D02*
X599208D01*
X598208Y383668D01*
G01X593385Y400287D02*
Y404287D01*
G01X601908Y389786D02*
X592248D01*
G01X593385Y404287D02*
X598185D01*
G01X603245D02*
X598185D01*
G01X590998Y411846D02*
X594123D01*
X599123Y406846D01*
X603245D01*
G01X593758Y418630D02*
Y415850D01*
G01X604494Y432209D02*
X602790D01*
X600000Y434999D01*
Y446000D01*
G01X599776Y425240D02*
X594251D01*
G01X593758Y421780D02*
Y424747D01*
X594251Y425240D01*
G01X588798Y435949D02*
X594848D01*
G01X593425Y449500D02*
Y445500D01*
G01X600000Y446000D02*
X597075D01*
X596575Y445500D01*
G01X606890Y461348D02*
X604832D01*
X601860Y458376D01*
X599623D01*
G01D02*
X599538Y458461D01*
X593702D01*
G01X593781Y454242D02*
X600000D01*
X604379Y458621D01*
X610879D01*
X613606Y461348D01*
X617204D01*
G01X589507Y462559D02*
X593711Y466763D01*
X597659D01*
X600073Y464349D01*
G01X593578Y468893D02*
Y474353D01*
G01X606890Y468828D02*
X603294D01*
X601992Y470130D01*
X599452D01*
G01D02*
X596759D01*
X595522Y468893D01*
X593578D01*
G01X606890Y465088D02*
X606151Y464349D01*
X600073D01*
G01X593596Y479631D02*
X607532D01*
X607557Y479606D01*
G01X593925Y493500D02*
X593724Y493299D01*
Y486000D01*
G01X597075Y493500D02*
X598500Y492075D01*
Y484500D01*
X597500Y483500D01*
G01X590710Y804192D02*
Y794544D01*
X610211Y775043D01*
X617994Y756252D01*
Y706308D01*
X646446Y677856D01*
Y674643D01*
G01X650228Y674761D02*
Y677253D01*
X619769Y707712D01*
Y756464D01*
X611299Y776913D01*
X593509Y794703D01*
Y803060D01*
X595619Y805170D01*
Y806084D01*
G01X657428Y674761D02*
Y675991D01*
X621464Y711955D01*
Y756882D01*
X612679Y778093D01*
X602966Y787806D01*
Y791613D01*
X602833Y791746D01*
G01X600196Y1270598D02*
Y1266598D01*
G01D02*
Y1262598D01*
G01D02*
X599258D01*
X598112Y1263744D01*
Y1264365D01*
G01X600196Y1278598D02*
Y1274598D01*
G01X596944Y1270115D02*
X597309Y1270480D01*
Y1271711D01*
X600196Y1274598D01*
G01X612823Y53543D02*
X612301Y53021D01*
Y43449D01*
X613025Y42725D01*
G01X610461Y53543D02*
Y48211D01*
X610615Y48057D01*
Y40488D01*
X611364Y39739D01*
X618558D01*
X618732Y39913D01*
G01X617547Y53543D02*
Y47571D01*
X615587Y45611D01*
G01X605736Y53543D02*
Y44378D01*
X606585Y43529D01*
G01X610461Y65157D02*
Y75772D01*
X606150Y80083D01*
Y90065D01*
X606183D01*
Y95873D01*
G01X612823Y65157D02*
Y78472D01*
X610012Y81283D01*
Y100745D01*
X610009Y100748D01*
G01X617547Y65157D02*
Y78024D01*
X614288Y81283D01*
Y90092D01*
X614282D01*
Y95873D01*
G01X618182Y90098D02*
X618039Y89955D01*
Y84584D01*
G01X619910Y65157D02*
Y79412D01*
X618039Y81283D01*
Y84584D01*
G01X618182Y93248D02*
Y100786D01*
G01D02*
Y103421D01*
X618256Y103495D01*
G01X605853Y157640D02*
Y155131D01*
G01X612801Y175534D02*
X608775D01*
X608192Y174951D01*
Y173558D01*
X608775Y172975D01*
X612801D01*
G01Y175534D02*
X618801D01*
G01X612801Y170415D02*
X618801D01*
G01X612801Y167856D02*
X616301D01*
X618801Y165356D01*
G01X667552Y189173D02*
X662700D01*
X661012Y190861D01*
X635810D01*
X635410Y190461D01*
X618774D01*
X616274Y187961D01*
G01X667552Y193110D02*
X662700D01*
X662211Y192621D01*
X636186D01*
X633346Y195461D01*
X618774D01*
X616274Y192961D01*
G01X608794Y198186D02*
Y194336D01*
G01D02*
X605444D01*
X604293Y193185D01*
G01X616274Y202961D02*
X618774Y205461D01*
X630022D01*
X639342Y196141D01*
X657857D01*
X662700Y200984D01*
X667552D01*
G01Y197047D02*
X662700D01*
X660034Y194381D01*
X637764D01*
X631745Y200400D01*
X618713D01*
X616274Y197961D01*
G01X608793Y206186D02*
Y203787D01*
X608794Y203786D01*
G01Y201336D02*
Y203786D01*
G01X608793Y209336D02*
Y210993D01*
X605650Y214136D01*
G01X609245Y219365D02*
Y215890D01*
X611074Y214061D01*
G01X611213Y219365D02*
Y218022D01*
X616274Y212961D01*
G01X620735Y215169D02*
X619743Y216161D01*
X615550D01*
X613182Y218529D01*
Y219365D01*
G01X607276D02*
Y215762D01*
X605650Y214136D01*
G01X611213Y230389D02*
Y234472D01*
X610304Y235381D01*
G01X609245Y230389D02*
Y231240D01*
X604974Y235511D01*
G01X615885Y366827D02*
Y371627D01*
G01X609782Y373868D02*
X613644D01*
X615885Y371627D01*
G01X621585Y382427D02*
X614904D01*
X611463Y378986D01*
X609782D01*
G01Y384668D02*
X612482D01*
X613482Y383668D01*
G01X610725Y401728D02*
X615385D01*
G01D02*
X617985D01*
G01X621585Y395177D02*
X616468D01*
X611077Y389786D01*
X609782D01*
G01X609224Y417760D02*
X615185D01*
X615425Y418000D01*
G01D02*
Y422465D01*
G01X622197Y436116D02*
X618374Y432293D01*
Y426993D01*
X618466Y426901D01*
G01X617000Y435632D02*
X612551Y431183D01*
Y422051D01*
X612000Y421500D01*
X609224D01*
G01X615425Y422465D02*
Y426792D01*
X615316Y426901D01*
G01X616831Y451000D02*
Y447168D01*
X619500Y444499D01*
Y442075D01*
G01D02*
X618000D01*
X617000Y441075D01*
Y435632D01*
G01X608169Y454740D02*
X604140D01*
X603599Y454199D01*
Y444763D01*
X605769Y442593D01*
G01X616219Y475866D02*
X612922D01*
X611888Y474832D01*
Y462388D01*
X610848Y461348D01*
X606890D01*
G01X617204D02*
X622800D01*
G01X617204Y468828D02*
X624609D01*
G01X607557Y479606D02*
X626581D01*
X627364Y478823D01*
G01X662628Y674761D02*
X661252D01*
X623199Y712814D01*
Y757448D01*
X614149Y779297D01*
X605338Y788108D01*
Y793184D01*
X603743Y794779D01*
Y794963D01*
G01X619238Y1371182D02*
X610856D01*
X608148Y1373890D01*
G01X624634Y48104D02*
Y53543D01*
G01X622272D02*
Y60203D01*
X622207Y60268D01*
Y60573D01*
G01X619910Y53543D02*
Y49540D01*
X619563Y49193D01*
G01X622272Y65157D02*
Y95832D01*
X622156Y95948D01*
G01X624634Y65157D02*
Y77528D01*
X626208Y79102D01*
Y100861D01*
G01X621310Y175534D02*
X618801D01*
G01X625310D02*
X621310D01*
G01X625310Y178684D02*
Y180566D01*
X626824Y182080D01*
G01X667552Y187204D02*
X662996D01*
X660219Y189981D01*
X637122D01*
X635102Y187961D01*
X621274D01*
G01X667552Y191142D02*
X662700D01*
X662101Y191741D01*
X635390D01*
X634990Y191341D01*
X622894D01*
X621274Y192961D01*
G01Y207961D02*
X629191D01*
X640131Y197021D01*
X656768D01*
X662700Y202953D01*
X667552D01*
G01X621274Y202961D02*
X630853D01*
X638553Y195261D01*
X658945D01*
X662700Y199016D01*
X667552D01*
G01Y195079D02*
X662700D01*
X661122Y193501D01*
X636975D01*
X632515Y197961D01*
X621274D01*
G01X631505Y286780D02*
Y284355D01*
G01X618705Y295880D02*
X622705D01*
G01D02*
X626705D01*
G01D02*
Y299730D01*
G01X631505Y289930D02*
Y294730D01*
G01X636305Y297171D02*
X633946D01*
X631505Y294730D01*
G01X626705Y292730D02*
Y285305D01*
G01X618705Y292730D02*
Y285305D01*
G01X622705Y292730D02*
Y285305D01*
G01X636305Y299730D02*
X631505D01*
G01D02*
X626705D01*
G01X672425Y413362D02*
X672277Y413510D01*
Y415071D01*
X671606Y415742D01*
X668200D01*
X667856Y415398D01*
X660898D01*
X655500Y410000D01*
X634000D01*
X632110Y408110D01*
Y341716D01*
X631694Y341300D01*
G01X672425Y421862D02*
X671085Y420522D01*
X669290D01*
X668648Y419880D01*
X659010D01*
X651630Y412500D01*
X633500D01*
X629939Y408939D01*
Y347313D01*
X626555Y343929D01*
G01X621585Y374477D02*
Y331358D01*
G01X624133Y346520D02*
Y373456D01*
X626368Y375691D01*
Y387931D01*
X624968Y389331D01*
Y395532D01*
X621000Y399500D01*
Y426500D01*
X624953Y430453D01*
Y447546D01*
X637943Y460536D01*
Y466023D01*
X636309Y467657D01*
Y497561D01*
X635906Y497964D01*
G01X619035Y366827D02*
Y369542D01*
G01X626596Y360196D02*
Y371849D01*
X627809Y373062D01*
Y388910D01*
X626556Y390163D01*
Y396444D01*
X622500Y400500D01*
Y425500D01*
X626480Y429480D01*
Y447019D01*
X639629Y460168D01*
Y472988D01*
X640546Y473905D01*
X643086D01*
G01X621585Y377627D02*
Y382427D01*
G01Y374477D02*
X624803Y377695D01*
Y386082D01*
X623658Y387227D01*
X621585D01*
G01Y395177D02*
Y390377D01*
G01X624760Y416441D02*
X626672D01*
X627297Y417066D01*
Y418389D01*
X626686Y419000D01*
G01X638000Y418575D02*
X637575Y419000D01*
X632240D01*
G01X626686D02*
X624760D01*
G01X627925Y427000D02*
Y421966D01*
G01D02*
Y420239D01*
X626686Y419000D01*
G01X638000Y422425D02*
X637134Y421559D01*
X632240D01*
G01X629428Y437881D02*
Y439051D01*
X632281Y441904D01*
G01X632578Y437881D02*
Y438773D01*
X633833Y440028D01*
X643909D01*
X646075Y437862D01*
G01X622800Y461348D02*
X629991D01*
X630084Y461441D01*
G01X629846Y474020D02*
Y468868D01*
X629834Y468856D01*
G01X624609Y468828D02*
X629806D01*
X629834Y468856D01*
G01X705158Y645357D02*
X704142D01*
X684426Y665073D01*
X674255Y669286D01*
X668935Y674606D01*
Y679119D01*
X630500Y717554D01*
Y760281D01*
X629754Y761027D01*
X627181Y767239D01*
Y772999D01*
X629550Y775368D01*
X635807D01*
X640271Y770904D01*
Y763488D01*
G01X660175Y679517D02*
X624894Y714798D01*
Y758061D01*
X619315Y771530D01*
Y778996D01*
X618645Y779666D01*
Y783582D01*
G01X717176Y646147D02*
X714995Y643966D01*
X709548D01*
X687359Y666155D01*
X675935Y670887D01*
X671055Y675767D01*
Y680074D01*
X632620Y718509D01*
Y761528D01*
X631386Y762762D01*
X629310Y767773D01*
Y771112D01*
X631557Y773359D01*
G01X704710Y668000D02*
X688446D01*
X677136Y672685D01*
X673175Y676646D01*
Y680953D01*
X634740Y719388D01*
Y762500D01*
X633252Y763988D01*
X631741Y767636D01*
Y770318D01*
G01X624795Y1373257D02*
Y1373149D01*
X622828Y1371182D01*
X622388D01*
G01X624976Y1378313D02*
Y1378544D01*
X624556Y1378964D01*
X622413D01*
G01X629246Y1376194D02*
X626286D01*
X624945Y1377535D01*
Y1378282D01*
X624976Y1378313D01*
G01X626295Y1386882D02*
X628194Y1388781D01*
Y1395604D01*
G01X626295Y1386882D02*
X627481Y1385696D01*
Y1381109D01*
X629246Y1379344D01*
G01X630195Y1384263D02*
Y1386882D01*
G01X631608Y1381706D02*
Y1382850D01*
X630195Y1384263D01*
G01X634095Y1386882D02*
X632703Y1385490D01*
Y1383042D01*
X633183Y1382562D01*
Y1381706D01*
G01X624795Y1373257D02*
X624679D01*
X622854Y1375082D01*
X622388D01*
G01X629246Y1374619D02*
X626157D01*
X624795Y1373257D01*
G01X625195Y1383457D02*
X623006D01*
X622413Y1382864D01*
G01X629246Y1377769D02*
X627539D01*
X627095Y1378213D01*
Y1378755D01*
X625195Y1380655D01*
Y1383457D01*
G01X622352Y1386732D02*
X621994Y1386374D01*
Y1383283D01*
X622413Y1382864D01*
G01X622352Y1390732D02*
X623176Y1389908D01*
X626171D01*
X626295Y1390032D01*
G01X622352Y1393285D02*
Y1390732D01*
G01X630195Y1390032D02*
Y1392226D01*
X630523Y1392554D01*
G01D02*
Y1400902D01*
X630000Y1401425D01*
G01Y1404575D02*
X631860Y1406435D01*
X653941D01*
X685260Y1437754D01*
Y1446617D01*
X689152Y1450509D01*
X701432D01*
X709686Y1458763D01*
X731153D01*
X734218Y1461828D01*
X777792D01*
X780132Y1459488D01*
X785470D01*
X789481Y1463499D01*
X862194D01*
X868801Y1456892D01*
X889754D01*
X908807Y1437839D01*
X980615D01*
X997651Y1454875D01*
X1111814D01*
X1120621Y1463682D01*
X1145317D01*
X1148968Y1460031D01*
X1166126D01*
X1169086Y1457071D01*
X1176500D01*
G01X718129Y1624330D02*
Y1621522D01*
X716699Y1620092D01*
X712713D01*
X707417Y1625388D01*
X693653D01*
X691700Y1627341D01*
X688328D01*
X688068Y1627081D01*
X684275D01*
X682979Y1625785D01*
X674810D01*
X670351Y1630244D01*
X662854D01*
X648845Y1644253D01*
X638863D01*
X633917Y1649199D01*
Y1664754D01*
X629808Y1668863D01*
G01X642784Y53543D02*
Y45322D01*
X642157Y44695D01*
G01X645146Y53543D02*
Y47097D01*
X646042Y46201D01*
Y41545D01*
G01X640421Y53543D02*
Y49738D01*
X639876Y49193D01*
G01X647508Y53543D02*
Y48085D01*
X647987Y47606D01*
G01X642784Y65157D02*
Y67089D01*
X643140Y67445D01*
Y71209D01*
X645102Y73171D01*
Y79602D01*
X641703Y83001D01*
Y85197D01*
X646388Y89882D01*
G01X647508Y65157D02*
Y71803D01*
X647100Y72211D01*
Y81706D01*
X644202Y84604D01*
G01X640421Y65157D02*
Y67524D01*
X641719Y68822D01*
Y72018D01*
X643325Y73624D01*
Y77652D01*
X642541Y78436D01*
G01X649870Y65157D02*
Y72229D01*
X649036Y73063D01*
Y82697D01*
X647938Y83795D01*
G01X634914Y128047D02*
Y121280D01*
G01X638654Y128047D02*
Y130956D01*
X642686Y134988D01*
X645752D01*
G01X642301Y149976D02*
X646231D01*
G01X642394Y137495D02*
Y144262D01*
G01D02*
Y149883D01*
X642301Y149976D01*
G01X646231Y153126D02*
Y156604D01*
X641006Y161829D01*
G01X646239Y161862D02*
X643800D01*
G01X646291Y174201D02*
Y170105D01*
X646239Y170053D01*
G01D02*
X641588D01*
X640923Y169388D01*
G01X643785Y299730D02*
Y302289D01*
G01D02*
X648585D01*
G01X637314Y393680D02*
X641170D01*
X645715Y389135D01*
Y370973D01*
X660380Y356308D01*
X735329D01*
X741454Y362433D01*
Y370284D01*
X743252Y372082D01*
X762298D01*
X764331Y374115D01*
Y374401D01*
G01X771512Y386862D02*
X772250Y386124D01*
Y379851D01*
X770179Y377780D01*
Y373310D01*
X767719Y370850D01*
X746532D01*
X745464Y369782D01*
Y362849D01*
X737503Y354888D01*
X658928D01*
X644305Y369511D01*
Y387611D01*
X642617Y389299D01*
G01X640784Y395957D02*
X647085Y389656D01*
Y371735D01*
X660534Y358286D01*
X725041D01*
X725541Y358786D01*
Y370463D01*
X724731Y371273D01*
Y384865D01*
X725634Y385768D01*
Y387990D01*
X724639Y388985D01*
X722605D01*
X721500Y390090D01*
Y392363D01*
X720576Y393287D01*
X719500D01*
G01X695500Y386862D02*
X693514Y388848D01*
X675500D01*
X675304Y388652D01*
X670583D01*
X661122Y398113D01*
X645935D01*
X644990Y399058D01*
X639699D01*
X634105Y404652D01*
G01X645655Y401580D02*
X649027D01*
X650620Y399987D01*
X653523D01*
G01X652027Y415930D02*
X649495D01*
X646925Y418500D01*
G01D02*
X646500Y418925D01*
X642500D01*
G01D02*
X642150Y418575D01*
X638000D01*
G01X651279Y404458D02*
X646590D01*
X645599Y405449D01*
G01X656425Y429862D02*
X644654D01*
X642406Y427614D01*
G01X652763Y427866D02*
X649078D01*
X646925Y425713D01*
Y422500D01*
G01X642500Y422075D02*
X642150Y422425D01*
X638000D01*
G01X646925Y422500D02*
X646500Y422075D01*
X642500D01*
G01X642925Y437862D02*
X642596Y438191D01*
X639211D01*
G01X646075Y442362D02*
X647685D01*
X648719Y441328D01*
X662406D01*
X665440Y444362D01*
X668000D01*
X670000Y442362D01*
G01X646075Y433862D02*
X648135D01*
X648465Y433532D01*
X651432D01*
G01X651132Y436517D02*
X649787Y437862D01*
X646075D01*
G01X642925Y453862D02*
Y453541D01*
X641745Y452361D01*
X639313D01*
G01X646075Y449862D02*
X650875D01*
G01X646075Y453862D02*
X648500D01*
G01X646199Y461853D02*
X646455D01*
X647947Y463345D01*
X654422D01*
X654761Y463684D01*
X657649D01*
X659515Y461818D01*
G01X646086Y457746D02*
X649294D01*
X650800Y456240D01*
G01X643066Y469863D02*
Y467645D01*
X644026Y466685D01*
X649838D01*
X650584Y465939D01*
X651072D01*
G01X646236Y473905D02*
X646257Y473884D01*
X651114D01*
G01X646216Y469863D02*
X651016D01*
G01X646075Y488000D02*
X647240D01*
X649500Y490260D01*
G01X642925Y488000D02*
Y496575D01*
X642000Y497500D01*
Y499000D01*
X641000Y500000D01*
X639500D01*
X637522Y501978D01*
G01D02*
X634244Y505256D01*
Y507463D01*
G01D02*
X634260Y507479D01*
X639504D01*
G01X646984Y510038D02*
X648158D01*
X648196Y510000D01*
X649837D01*
X651908Y507929D01*
G01X639504Y510038D02*
X639542Y510000D01*
X642000D01*
X643132Y511132D01*
Y518565D01*
X643313Y518746D01*
G01X646925Y519500D02*
X644067D01*
X643313Y518746D01*
G01X646984Y512597D02*
X649166D01*
X650661Y514092D01*
X651908D01*
G01X636551Y767900D02*
Y764419D01*
X636860Y764110D01*
Y721337D01*
X675295Y682902D01*
Y677525D01*
X678335Y674485D01*
X686868Y670949D01*
X715803D01*
G01X647354Y766871D02*
X642804D01*
G01X647354Y763525D02*
X642804D01*
G01X638847Y1389887D02*
X635842Y1386882D01*
X634095D01*
G01Y1390032D02*
Y1392704D01*
X634767Y1393376D01*
X635849D01*
G01D02*
X635000Y1394225D01*
Y1401425D01*
G01Y1404575D02*
X653995D01*
X686657Y1437237D01*
Y1445956D01*
X689515Y1448814D01*
X702354D01*
X710936Y1457396D01*
X735357D01*
X738037Y1460076D01*
X776481D01*
X779035Y1457522D01*
X786534D01*
X791028Y1462016D01*
X860966D01*
X868277Y1454705D01*
X889377D01*
X907991Y1436091D01*
X980799D01*
X998243Y1453535D01*
X1065783D01*
X1069832Y1449486D01*
X1108989D01*
X1121677Y1462174D01*
X1144222D01*
X1147782Y1458614D01*
X1165607D01*
X1169121Y1455100D01*
X1178200D01*
X1180200Y1457100D01*
G01X670839Y1620863D02*
X669576D01*
X659244Y1631195D01*
X656526D01*
X648760Y1638961D01*
X643970D01*
X643128Y1639803D01*
G01X644284Y1658333D02*
Y1655507D01*
X642716Y1653939D01*
G01D02*
X644549Y1652106D01*
Y1650850D01*
G01X639284Y1658333D02*
Y1656197D01*
X637218Y1654131D01*
G01X639800Y1650850D02*
Y1653380D01*
X639049Y1654131D01*
X637218D01*
G01X644549Y1648750D02*
Y1646847D01*
X644905Y1646491D01*
G01X639800Y1646650D02*
Y1648750D01*
G01X643041Y1682883D02*
X644284Y1681640D01*
Y1678805D01*
G01X643455Y1685970D02*
X643041Y1685556D01*
Y1682883D01*
G01X653225Y1698400D02*
X644136D01*
X641437Y1695701D01*
Y1692156D01*
G01D02*
Y1690052D01*
X637932Y1686547D01*
X634516D01*
G01X653225Y1702400D02*
X645542D01*
X638878Y1695736D01*
Y1692156D01*
G01D02*
X633333D01*
G01X652800Y1691225D02*
X647825Y1696200D01*
X644597D01*
X643997Y1695600D01*
Y1692156D01*
G01X641437Y1709734D02*
Y1706473D01*
X643620Y1704290D01*
X660161D01*
X660654Y1704783D01*
G01X651143Y1706162D02*
X651049Y1706068D01*
X644582D01*
X643997Y1706653D01*
Y1709734D01*
G01X644975Y1728000D02*
X648825D01*
G01X644975Y1725236D02*
Y1728000D01*
G01X648825Y1722138D02*
X644975D01*
G01Y1717138D02*
X648825D01*
G01X644975Y1733000D02*
X648825D01*
G01X652232Y53543D02*
Y49132D01*
X654582Y46782D01*
Y45448D01*
G01X649870Y53543D02*
Y49177D01*
X651042Y48005D01*
Y41545D01*
G01X664043Y65157D02*
Y70840D01*
X662425Y74738D01*
X661601Y75562D01*
G01X650846Y74074D02*
X651197Y74425D01*
Y78359D01*
X653821Y80983D01*
Y84187D01*
G01X652232Y65157D02*
Y72688D01*
X650846Y74074D01*
G01X656957Y65157D02*
Y69206D01*
X656501Y69662D01*
G01X654595Y65157D02*
Y74596D01*
X654001Y75190D01*
Y75966D01*
X657166Y79131D01*
G01X659319Y65157D02*
Y72386D01*
X656427Y75278D01*
Y75431D01*
G01X661681Y65157D02*
X661433Y65405D01*
Y69507D01*
X661588Y69662D01*
G01X673492Y65157D02*
Y71151D01*
X670841Y73802D01*
Y85892D01*
X668271Y88462D01*
X658243D01*
X658228Y88447D01*
G01X667552Y155708D02*
X663708D01*
X659640Y151640D01*
Y145976D01*
X654400Y140736D01*
Y136981D01*
X651391Y133972D01*
G01X667552Y179330D02*
X673061D01*
X679260Y173131D01*
Y166070D01*
X672630Y159440D01*
X666194D01*
X658760Y152006D01*
Y146341D01*
X651391Y138972D01*
G01X667552Y177362D02*
X673783D01*
X678380Y172765D01*
Y166435D01*
X672265Y160320D01*
X665829D01*
X657880Y152371D01*
Y150461D01*
X651391Y143972D01*
G01Y148972D02*
X655145D01*
X657000Y150827D01*
Y152736D01*
X665464Y161200D01*
X671900D01*
X677500Y166800D01*
Y172400D01*
X674507Y175393D01*
X667552D01*
G01Y169488D02*
X659987D01*
X654471Y163972D01*
G01X649389Y161862D02*
X652361D01*
X654471Y163972D01*
G01X654371Y158572D02*
X663318Y167519D01*
X667552D01*
G01X654391Y152972D02*
X657531Y156112D01*
Y158768D01*
X664314Y165551D01*
X667552D01*
G01X649389Y166053D02*
Y170053D01*
G01X667552Y171456D02*
X656416D01*
X654157Y169197D01*
G01X649389Y170053D02*
X653301D01*
X654157Y169197D01*
G01X654326Y174437D02*
X655338Y173425D01*
X667552D01*
G01X653700Y179962D02*
X654481D01*
X655818Y181299D01*
X667552D01*
G01X654311Y186192D02*
X650626D01*
X649296Y184862D01*
G01X667552Y185236D02*
X655267D01*
X654311Y186192D01*
G01X649871Y181942D02*
X651197Y183268D01*
X667552D01*
G01Y216732D02*
X671232D01*
X672200Y217700D01*
Y221410D01*
X657847Y235763D01*
Y253062D01*
X656318Y254591D01*
G01X667552Y214764D02*
X671264D01*
X672400Y215900D01*
X674500D01*
X676158Y217558D01*
Y219330D01*
X675453Y220035D01*
X673740Y221180D01*
X659096Y235824D01*
Y260518D01*
X656128Y263486D01*
G01X648585Y302289D02*
Y307089D01*
G01X659000Y370677D02*
Y363892D01*
X659326Y363566D01*
G01X664648Y363261D02*
X659631D01*
X659326Y363566D01*
G01X662740Y380323D02*
Y389835D01*
X662575Y390000D01*
G01X653523Y399987D02*
X654798Y401262D01*
X666948D01*
G01X649888Y395717D02*
X650465D01*
X651127Y396379D01*
X660570D01*
X662575Y394374D01*
Y390000D01*
G01X659425D02*
X655575D01*
G01X652954Y394284D02*
X653942Y393296D01*
X654875D01*
X655575Y392596D01*
Y390000D01*
G01X666885Y405180D02*
X652001D01*
X651279Y404458D01*
G01X659575Y425862D02*
X659483Y425770D01*
Y424592D01*
X661255Y422820D01*
X663728D01*
G01X656425Y425862D02*
Y423804D01*
X657535Y422694D01*
G01X651432Y433532D02*
X651762Y433862D01*
X656425D01*
G01X659575Y429862D02*
X661185D01*
X661203Y429844D01*
X662000D01*
G01X652763Y427866D02*
X663209D01*
X664083Y428740D01*
Y431083D01*
X665000Y432000D01*
X671925D01*
X672425Y432500D01*
Y433862D01*
G01X697331Y448240D02*
X694600D01*
X693170Y449670D01*
X678780D01*
X677084Y447974D01*
X671376D01*
X670510Y448840D01*
X666710D01*
X666112Y448242D01*
X663392D01*
X662483Y447333D01*
X653404D01*
X650875Y449862D01*
G01X659575Y433862D02*
X662000D01*
G01X697331Y441940D02*
X695050D01*
X693530Y443460D01*
X679506D01*
X675890Y439844D01*
X659647D01*
X657622Y437819D01*
G01X697331Y435641D02*
X694617D01*
X689598Y440660D01*
X681170D01*
X676390Y435880D01*
X651769D01*
X651132Y436517D01*
G01X672425Y449862D02*
X672516Y449953D01*
Y451556D01*
X672210Y451862D01*
X663162D01*
X662000Y450700D01*
Y449862D01*
G01X659575Y453862D02*
Y454438D01*
X660999Y455862D01*
X663982D01*
X666000Y453844D01*
G01X659515Y461818D02*
X662299D01*
X662570Y461547D01*
G01X659498Y457755D02*
X662570D01*
G01X659498D02*
X657343Y455600D01*
X651440D01*
X650800Y456240D01*
G01X659575Y469862D02*
Y471234D01*
X660195Y471854D01*
X666919D01*
G01X659575Y473862D02*
Y478662D01*
G01D02*
X661053D01*
X662000Y477715D01*
Y473862D01*
G01Y465862D02*
X664000Y467862D01*
X671499D01*
X672425Y466936D01*
Y465862D01*
G01X651016Y469863D02*
X652845Y468034D01*
X661172D01*
X662000Y468862D01*
Y469862D01*
G01X650490Y486941D02*
Y484280D01*
X652380Y482390D01*
G01X653640Y486941D02*
X656909D01*
X657520Y486330D01*
G01X672341Y474268D02*
X669739D01*
X665862Y478145D01*
X665179D01*
X660215Y483109D01*
G01X656000Y509925D02*
X653904D01*
X651908Y507929D01*
G01X650075Y519500D02*
Y522575D01*
X651240Y523740D01*
X663382D01*
G01X656000Y517925D02*
Y513075D01*
G01D02*
X654214D01*
X653197Y514092D01*
X651908D01*
G01X648144Y1368320D02*
X649154D01*
X650495Y1366979D01*
Y1364516D01*
X651973Y1363038D01*
G01D02*
X655291D01*
X655647Y1363394D01*
G01X668206Y1505139D02*
X664686Y1508659D01*
X661560D01*
X658518Y1505617D01*
X655003D01*
X653330Y1507290D01*
Y1509459D01*
G01X654511Y1511505D02*
X655334Y1512328D01*
X655812D01*
X656413Y1512929D01*
X657530D01*
X660581Y1509878D01*
X668047D01*
X668946Y1508979D01*
G01X657408Y1519807D02*
X661316Y1523715D01*
Y1526889D01*
X663980Y1529553D01*
Y1531670D01*
X664745Y1532435D01*
X684488D01*
X686211Y1534158D01*
G01X657408Y1515083D02*
X659063Y1514073D01*
G01X657408Y1517445D02*
X659007Y1516336D01*
G01X657408Y1522169D02*
X658068D01*
X660436Y1524537D01*
Y1527265D01*
X663012Y1529841D01*
Y1532077D01*
X664250Y1533315D01*
X678377D01*
X679792Y1534730D01*
Y1536622D01*
G01X657408Y1536343D02*
X659061D01*
X659358Y1536640D01*
G01X657408Y1533980D02*
X657968Y1534540D01*
X659358D01*
G01X657408Y1531618D02*
X659359D01*
G01X657408Y1529256D02*
X657966Y1528698D01*
X659270D01*
G01X655363Y1532799D02*
X658244D01*
X658525Y1533080D01*
X661020D01*
X662353Y1534413D01*
G01X655363Y1530437D02*
X658216D01*
X658495Y1530158D01*
X660877D01*
G01X658054Y1540477D02*
Y1542419D01*
X662081Y1546446D01*
X663389Y1546988D01*
X666092Y1549691D01*
Y1553650D01*
G01X657430Y1555228D02*
Y1545441D01*
X654511Y1542522D01*
Y1538431D01*
G01X660615Y1553650D02*
X659457D01*
X658905Y1553098D01*
Y1547146D01*
X659532Y1546519D01*
G01X653330Y1540477D02*
Y1543895D01*
X655938Y1546503D01*
Y1552811D01*
X655099Y1553650D01*
X654255D01*
G01X660615Y1558650D02*
X658475D01*
X657430Y1557605D01*
Y1555228D01*
G01X660615Y1556550D02*
Y1553650D01*
G01X654255D02*
Y1556550D01*
G01D02*
X650995D01*
G01X663003Y1651250D02*
Y1651867D01*
X660389Y1654481D01*
G01D02*
X663003Y1657095D01*
Y1658515D01*
X662971Y1658547D01*
G01X663431Y1645780D02*
X663003Y1646208D01*
Y1649150D01*
G01X653154Y1683265D02*
X655775Y1685886D01*
Y1687400D01*
G01X656375Y1698400D02*
X659837D01*
G01X653225D02*
Y1696968D01*
X652800Y1696543D01*
Y1694375D01*
G01D02*
X656800D01*
G01X656375Y1702400D02*
X659351D01*
X662197Y1699554D01*
X667464D01*
X671001Y1696017D01*
G01X652800Y1691225D02*
X650158Y1688583D01*
Y1687189D01*
G01D02*
X652414D01*
X652625Y1687400D01*
G01X657173Y1717056D02*
X656059D01*
X654183Y1715180D01*
X650783D01*
X648825Y1717138D01*
G01X657173Y1717056D02*
X659557Y1714672D01*
G01X656375Y1712084D02*
X662425D01*
G01D02*
Y1708184D01*
G01X660654Y1704783D02*
X662425Y1706554D01*
Y1708184D01*
G01X653225D02*
Y1712084D01*
G01Y1708184D02*
X653165D01*
X651143Y1706162D01*
G01X656375Y1708184D02*
X657412Y1707147D01*
X658759D01*
G01X648825Y1733000D02*
X650714Y1731111D01*
X655306D01*
X656140Y1730277D01*
X657173D01*
G01D02*
X660930D01*
G01X657173Y1727718D02*
X655087Y1725632D01*
X651193D01*
X648825Y1728000D01*
G01X657173Y1719615D02*
X656589Y1720199D01*
X650764D01*
X648825Y1722138D01*
G01X657173Y1719615D02*
X661331D01*
X662120Y1720404D01*
G01X678217Y53543D02*
Y51299D01*
X677651Y50733D01*
Y41194D01*
X674647Y38190D01*
G01X678217Y65157D02*
X677981Y65393D01*
Y73802D01*
X676891Y74892D01*
Y80771D01*
X675509Y82153D01*
Y88173D01*
G01X675854Y65157D02*
Y72704D01*
X674036Y74522D01*
G01X671130Y65157D02*
Y70655D01*
X667941Y73844D01*
Y80142D01*
G01X668768Y65157D02*
Y70159D01*
X666055Y72872D01*
X664729Y76073D01*
Y83391D01*
X666200Y84862D01*
G01X680623Y111960D02*
X675242D01*
G01D02*
Y107861D01*
X675843Y107260D01*
G01X673861Y121202D02*
X675111Y122452D01*
X683011D01*
X683529Y121934D01*
Y119868D01*
G01X678226Y215771D02*
X676555Y214100D01*
X672999D01*
X671694Y212795D01*
X667552D01*
G01X663915Y234476D02*
X665936Y232455D01*
X702361D01*
X710146Y224670D01*
Y221862D01*
G01X667798Y363261D02*
X668037Y363500D01*
X680828D01*
G01X676800Y371787D02*
Y369362D01*
G01X672800Y371787D02*
Y369362D01*
G01Y374937D02*
Y382362D01*
G01X676800Y374937D02*
Y377300D01*
X676000Y378100D01*
G01X675500Y396437D02*
Y398862D01*
G01Y393287D02*
Y390862D01*
G01X675620Y401567D02*
X677108D01*
X678567Y403026D01*
X681071D01*
X688465Y410420D01*
X689269D01*
G01X666948Y401262D02*
X668734D01*
X669053Y401581D01*
X670846D01*
X670860Y401567D01*
X672470D01*
G01X675575Y417862D02*
X677182D01*
X680400Y421080D01*
X683500D01*
G01X672425Y417862D02*
X670846D01*
X670018Y418690D01*
G01X672470Y409320D02*
X672562Y409412D01*
Y413225D01*
X672425Y413362D01*
G01X680200Y417110D02*
X676452Y413362D01*
X675575D01*
G01X666885Y405180D02*
X667193Y405488D01*
X672470D01*
G01X675620D02*
X677392D01*
X678068Y406164D01*
X680263D01*
X685799Y411700D01*
X689198Y413108D01*
X694299D01*
G01X680200Y425280D02*
Y424380D01*
X677682Y421862D01*
X675575D01*
G01X700481Y426192D02*
X699440D01*
X697842Y424594D01*
X694866D01*
X692010Y427450D01*
X682820D01*
X681033Y428190D01*
X678990D01*
X677200Y426400D01*
Y424410D01*
X676780Y423990D01*
X671707D01*
X668882Y422820D01*
X663728D01*
G01X675575Y425862D02*
Y427655D01*
X676000Y428080D01*
X676455D01*
X678735Y430360D01*
X683400D01*
G01X672425Y425862D02*
X672516Y425953D01*
Y427556D01*
X672210Y427862D01*
X668000D01*
X666000Y425862D01*
G01X672425Y429862D02*
X672407Y429844D01*
X670020D01*
X670000Y429864D01*
G01X680266Y434313D02*
X675815Y429862D01*
X675575D01*
G01X672425Y442362D02*
X670000D01*
G01X683400Y445830D02*
X679511D01*
X676043Y442362D01*
X675575D01*
G01X670000Y437844D02*
X676144D01*
X680390Y442090D01*
X692700D01*
X694385Y440405D01*
X698946D01*
X700481Y441940D01*
G01X675575Y433862D02*
X676548D01*
X681006Y438320D01*
X683300D01*
G01X697331Y445090D02*
X695690D01*
X692630Y448150D01*
X679600D01*
X677650Y446200D01*
X670162D01*
X670000Y446362D01*
G01X675575Y449862D02*
X677787Y452074D01*
X680250D01*
G01X666000Y457862D02*
X668000Y459862D01*
X671499D01*
X672425Y458936D01*
Y457862D01*
G01Y453862D02*
X672407Y453844D01*
X670000D01*
G01X666000Y461862D02*
X668000Y463862D01*
X671499D01*
X672425Y462936D01*
Y461862D01*
G01X680250Y459812D02*
X677525D01*
X675575Y457862D01*
G01Y453862D02*
Y454646D01*
X678049Y457120D01*
X682262D01*
X683450Y455932D01*
G01Y463812D02*
X677525D01*
X675575Y461862D01*
G01X666919Y471854D02*
X667970D01*
X670000Y469824D01*
G01X680250Y467712D02*
X677425D01*
X675575Y465862D01*
G01X672425Y477862D02*
X670000D01*
G01X675575D02*
X678000D01*
G01X675491Y474268D02*
X677837D01*
X681772Y478203D01*
Y485623D01*
X685380Y489231D01*
X688205D01*
X690452Y486984D01*
G01X672425Y482862D02*
X670000D01*
G01X675575D02*
X678000D01*
G01X664530Y486941D02*
X667814D01*
X668660Y486095D01*
G01D02*
X669508Y485247D01*
X673912D01*
X675607Y486942D01*
G01D02*
Y488084D01*
X678766Y491243D01*
X680187D01*
G01X675864Y495084D02*
X680639D01*
X681213Y495658D01*
G01X664392Y495126D02*
Y496317D01*
X665934Y497859D01*
X673089D01*
X675864Y495084D01*
G01X677861Y504895D02*
Y501719D01*
X679012Y500568D01*
X682915D01*
G01X669861Y504895D02*
X676756Y498000D01*
X681578D01*
X683149Y496429D01*
Y491497D01*
X681227Y489575D01*
Y488419D01*
G01X665425Y537000D02*
Y533500D01*
G01Y529500D02*
X663382Y527457D01*
Y523740D01*
G01X665425Y533500D02*
Y529500D01*
G01X681352Y681305D02*
Y685682D01*
X663580Y703454D01*
Y731509D01*
G01X686509Y677440D02*
X688614Y679545D01*
Y686479D01*
X670791Y704302D01*
Y730660D01*
X673287Y733156D01*
G01X663496Y766871D02*
X668046D01*
G01X677055D02*
X672505D01*
G01X677055Y763525D02*
X672505D01*
G01X663496Y770218D02*
X668046D01*
G01X1605801Y1286168D02*
X1604723D01*
X1599808Y1291083D01*
Y1298613D01*
X1596430Y1301991D01*
Y1354132D01*
X1602968Y1360670D01*
Y1383585D01*
X1565426Y1421127D01*
X1427401D01*
X1374153Y1474375D01*
X1174521D01*
X1167247Y1481649D01*
X1112866D01*
X1095778Y1464561D01*
X976835D01*
X963593Y1451319D01*
X903309D01*
X883395Y1471233D01*
X729472D01*
X722940Y1464701D01*
X690019D01*
X679962Y1454644D01*
Y1435483D01*
X676401Y1431922D01*
X673671D01*
G01X672099Y1508335D02*
Y1505135D01*
G01X668946Y1508979D02*
X671455D01*
X672099Y1508335D01*
G01X663815Y1553650D02*
X666092D01*
G01X667971Y1654404D02*
Y1658547D01*
G01X667985Y1651114D02*
X667971Y1651128D01*
Y1654404D01*
G01X667985Y1649014D02*
X669178Y1647821D01*
Y1646627D01*
G01D02*
Y1644953D01*
X666729Y1642504D01*
G01X663439D02*
Y1645357D01*
X663431Y1645365D01*
Y1645780D01*
G01X667971Y1679019D02*
Y1685417D01*
G01D02*
Y1686148D01*
X667312Y1686807D01*
Y1689063D01*
G01X665575Y1708184D02*
X667701Y1706058D01*
Y1705043D01*
G01X664653Y1730277D02*
Y1732836D01*
G01Y1719615D02*
Y1722174D01*
G01D02*
X666018Y1723539D01*
X669555D01*
G01D02*
X670920Y1722174D01*
X673113D01*
G01X664653Y1732836D02*
X669513D01*
G01D02*
X673113D01*
G01X685303Y53543D02*
Y49595D01*
X684881Y49173D01*
Y46112D01*
X683441Y44672D01*
Y42399D01*
X683983Y41857D01*
X684611D01*
G01X680579Y53543D02*
Y51459D01*
X679836Y50716D01*
X679411Y49692D01*
Y39643D01*
X680864Y38190D01*
G01X690028Y53543D02*
Y40043D01*
X687835Y37850D01*
G01X682941Y53543D02*
Y50471D01*
X682241Y49771D01*
Y46841D01*
X682261Y46821D01*
X682290D01*
X682291Y46822D01*
G01X692390Y46939D02*
Y53543D01*
G01X687665D02*
Y47760D01*
X687345Y47440D01*
Y46940D01*
G01X692390Y65157D02*
Y72692D01*
G01X690028Y65157D02*
Y70142D01*
G01X687665Y65157D02*
Y73202D01*
G01X685303Y65157D02*
Y69544D01*
X685781Y70022D01*
G01X680579Y65157D02*
Y79229D01*
X680580Y79230D01*
G01X686211Y91492D02*
X690702D01*
G01D02*
X690878Y91668D01*
G01X690134Y111960D02*
X684643D01*
G01D02*
X680623D01*
G01X690134Y115896D02*
X686919D01*
X686891Y115868D01*
G01D02*
X683528D01*
G01X684800Y371787D02*
Y369362D01*
G01X680800Y371787D02*
Y369362D01*
G01X689440Y366479D02*
X693367D01*
G01X690800Y376787D02*
X693075D01*
X695500Y374362D01*
G01X690800Y379937D02*
X693075D01*
X695500Y382362D01*
G01X680800Y374937D02*
Y380280D01*
G01X684800Y374937D02*
Y377420D01*
X685200Y377820D01*
G01X687500Y393287D02*
X691500D01*
G01X687500D02*
Y390680D01*
G01X691500Y396437D02*
X692110Y397047D01*
Y403570D01*
X694600Y406060D01*
G01X683500Y396437D02*
Y401654D01*
X684114Y402268D01*
X684794D01*
G01X679500Y396437D02*
Y400310D01*
X679940Y400750D01*
Y400933D01*
G01X683500Y393287D02*
Y390862D01*
G01X679500Y393287D02*
Y390862D01*
G01X700481Y423043D02*
Y421963D01*
X698902Y420384D01*
Y419256D01*
X695509Y415863D01*
X689700D01*
X688453Y417110D01*
X680200D01*
G01X683500Y421080D02*
X694396D01*
X695274Y421444D01*
X698022D01*
X698942Y422364D01*
Y423914D01*
X699692Y424664D01*
X702102D01*
X703630Y426192D01*
G01X697331Y423043D02*
X697322Y423034D01*
X694106D01*
X691860Y425280D01*
X680200D01*
G01X683400Y430360D02*
X691590D01*
X695758Y426192D01*
X697331D01*
G01Y429342D02*
X694989D01*
X690018Y434313D01*
X680266D01*
G01X700481Y445090D02*
X698921Y443530D01*
X695430D01*
X693130Y445830D01*
X683400D01*
G01X683300Y438320D02*
X689270D01*
X693728Y433862D01*
X695171D01*
X695423Y434114D01*
X698954D01*
X700481Y435641D01*
G01X680250Y452074D02*
X687957D01*
X688867Y452984D01*
X705185D01*
X706780Y451389D01*
G01X697331Y460838D02*
X694258D01*
X691642Y463454D01*
Y465144D01*
X691572Y465214D01*
G01X700481Y454539D02*
X698986Y456034D01*
X689357D01*
X685579Y459812D01*
X680250D01*
G01X683450Y455932D02*
X686640D01*
X688033Y454539D01*
X697331D01*
G01Y457688D02*
X690311D01*
X684187Y463812D01*
X683450D01*
G01X700481Y457688D02*
X698885Y459284D01*
X692287D01*
X683859Y467712D01*
X680250D01*
G01X687612Y471850D02*
X691377D01*
X693512Y469715D01*
Y463884D01*
X695002Y462394D01*
X698925D01*
X700481Y460838D01*
G01Y473436D02*
X698903Y475014D01*
X693497D01*
X686649Y481862D01*
X684800D01*
G01X697331Y473436D02*
X691900D01*
X687474Y477862D01*
X684800D01*
G01X700481Y476586D02*
X698913Y478154D01*
X696312D01*
X687472Y486994D01*
G01X697331Y476586D02*
X694985D01*
X685629Y485942D01*
X684680D01*
G01X681227Y488419D02*
X682473D01*
X685142Y491088D01*
X690021D01*
X692457Y488652D01*
Y484610D01*
X697331Y479736D01*
G01X692500Y507787D02*
X694549Y505738D01*
Y499912D01*
G01X688500Y535514D02*
X690203Y533811D01*
Y498158D01*
X698059Y490302D01*
X700867Y489139D01*
X702052Y487954D01*
Y484463D01*
X703630Y482885D01*
G01X687310Y507787D02*
Y500453D01*
G01X870591Y785437D02*
Y779699D01*
X876225Y774065D01*
Y672370D01*
X852437Y648582D01*
Y641146D01*
X796845Y585554D01*
X739590Y561839D01*
X713003D01*
X701050Y556888D01*
X691571Y547409D01*
Y513477D01*
X692500Y512548D01*
Y510937D01*
G01X687310D02*
Y522141D01*
G01X688500Y540287D02*
Y535514D01*
G01X868496Y776516D02*
X875105Y769907D01*
Y673322D01*
X850948Y649165D01*
Y641333D01*
X796734Y587119D01*
X739042Y563222D01*
X712391D01*
X699507Y557885D01*
X688500Y546878D01*
Y543437D01*
G01X697392Y588934D02*
Y587653D01*
X695820Y586081D01*
X691682D01*
G01X691417Y680382D02*
Y724299D01*
X697571Y730453D01*
G01X683391Y1420531D02*
Y1429399D01*
X689746Y1435754D01*
Y1443463D01*
X691221Y1444938D01*
X702850D01*
X712468Y1454556D01*
X788395D01*
X792950Y1459111D01*
X858471D01*
X874057Y1443525D01*
Y1440727D01*
X879997Y1434787D01*
X888742D01*
X893850Y1429679D01*
Y1321629D01*
X888230Y1316009D01*
Y1298010D01*
X859138Y1268918D01*
Y874715D01*
X885690Y848163D01*
Y809042D01*
X898545Y796187D01*
Y648448D01*
X878937Y628840D01*
Y584769D01*
X886404Y577302D01*
Y546925D01*
X888808Y544521D01*
Y488620D01*
X876758Y476570D01*
Y465733D01*
X884134Y458357D01*
Y378691D01*
X866922Y361479D01*
X839317D01*
X823152Y345314D01*
X802251D01*
X797351Y340414D01*
X783261D01*
X781812Y341863D01*
G01X779118Y341749D02*
X781873Y338994D01*
X797941D01*
X802841Y343894D01*
X823741D01*
X839883Y360036D01*
X867488D01*
X885694Y378242D01*
Y458942D01*
X878249Y466387D01*
Y475346D01*
X890228Y487325D01*
Y551165D01*
X889895Y551498D01*
Y575820D01*
X880357Y585358D01*
Y628251D01*
X899965Y647859D01*
Y796777D01*
X887110Y809632D01*
Y849052D01*
X860558Y875604D01*
Y1244400D01*
X864377Y1248219D01*
Y1252841D01*
X863487Y1253731D01*
Y1271258D01*
X889790Y1297561D01*
Y1315560D01*
X895270Y1321040D01*
Y1433658D01*
X890220Y1438708D01*
X885567D01*
X884920Y1438061D01*
X882398D01*
X880199Y1440260D01*
Y1443169D01*
X876642Y1446726D01*
X873733D01*
X859928Y1460531D01*
X791559D01*
X787004Y1455976D01*
X711867D01*
X702387Y1446496D01*
X690770D01*
X688176Y1443902D01*
Y1436390D01*
X681289Y1429503D01*
Y1418291D01*
G01X691943Y1441626D02*
X693513Y1443196D01*
X703259D01*
X711929Y1451866D01*
X788993D01*
X794818Y1457691D01*
X857305D01*
X871794Y1443202D01*
Y1440581D01*
X879008Y1433367D01*
X887156D01*
X892430Y1428093D01*
Y1322218D01*
X886810Y1316598D01*
Y1298600D01*
X857718Y1269508D01*
Y824011D01*
X859472Y822257D01*
X864584D01*
X875649Y811192D01*
Y800446D01*
X881823Y794272D01*
Y786068D01*
X883945Y783946D01*
Y661006D01*
X878871Y655932D01*
Y646065D01*
X865923Y633117D01*
Y574772D01*
X873016Y567679D01*
Y540875D01*
X875207Y538684D01*
Y493992D01*
X863184Y481969D01*
Y454196D01*
X872636Y444744D01*
Y422636D01*
X871600Y421600D01*
X864820D01*
X860530Y417310D01*
Y414560D01*
X853970Y408000D01*
X852000D01*
G01X679792Y1536622D02*
Y1540879D01*
X681212Y1542299D01*
X685690D01*
X686211Y1541778D01*
Y1540720D01*
G01Y1534158D02*
Y1537520D01*
G01Y1540720D02*
X689111D01*
G01X686211Y1537520D02*
X689111D01*
G01X702303Y1623062D02*
X700044Y1620803D01*
X695069D01*
X693243Y1622629D01*
X690745D01*
X689897Y1621781D01*
G01X702566Y1616656D02*
X700351Y1618871D01*
X693738D01*
X692572Y1620037D01*
X692209D01*
G01X680868Y1639704D02*
Y1635854D01*
X680880Y1635842D01*
G01D02*
X683941D01*
X685578Y1637479D01*
G01D02*
X688716D01*
X689781Y1638544D01*
Y1640773D01*
G01X683067Y1641758D02*
X683594Y1641231D01*
X687318D01*
X689419Y1643332D01*
X689781D01*
G01X680880Y1647842D02*
Y1643916D01*
X680868Y1643904D01*
G01X683067Y1641758D02*
X680921Y1643904D01*
X680868D01*
G01X699476Y53543D02*
Y56131D01*
X703042Y59697D01*
X709083D01*
X715256Y65870D01*
Y72526D01*
X714096Y73686D01*
G01X697114Y53543D02*
Y56221D01*
X702232Y61339D01*
X708011D01*
X712542Y65870D01*
Y68366D01*
X712717Y68541D01*
G01X704201Y53543D02*
Y55559D01*
X705472Y56830D01*
X711821D01*
X719154Y64163D01*
Y68258D01*
X719416Y68520D01*
Y68738D01*
G01X701839Y53543D02*
Y55999D01*
X704114Y58274D01*
X710901D01*
X717096Y64469D01*
Y71716D01*
X719416Y74036D01*
G01X694752Y53543D02*
Y50058D01*
X697678Y47132D01*
G01X704201Y65157D02*
Y72112D01*
G01X699476Y65157D02*
Y69982D01*
G01X701839Y65157D02*
Y71974D01*
X701363Y72450D01*
X701081D01*
G01X694752Y65157D02*
Y70212D01*
G01X697114Y65157D02*
Y72049D01*
X696701Y72462D01*
G01X707457Y119341D02*
Y120637D01*
X708953Y122133D01*
Y128093D01*
G01X699398Y123668D02*
X699583Y123483D01*
Y119440D01*
G01X697615D02*
Y121316D01*
X697115Y121816D01*
Y124483D01*
X696554Y125044D01*
G01X701551Y119440D02*
Y122428D01*
X704709Y125586D01*
G01X700963Y128153D02*
X699583Y126773D01*
Y124824D01*
X699398Y124639D01*
Y123668D01*
G01X694453Y128093D02*
Y126137D01*
X695546Y125044D01*
X696554D01*
G01X704709Y125586D02*
X704953Y125830D01*
Y128093D01*
G01X697277Y154724D02*
X708239D01*
X710451Y152512D01*
G01X697277Y156693D02*
X701903D01*
X704390Y159180D01*
Y161180D01*
X706222Y163012D01*
X710799D01*
G01X697277Y221653D02*
X709937D01*
X710146Y221862D01*
G01X866168Y374774D02*
X863242Y371848D01*
X829663D01*
X812589Y354774D01*
X798021D01*
X797256Y354009D01*
X788296D01*
X787531Y354774D01*
X745149D01*
X742921Y352546D01*
X707561D01*
X699813Y344798D01*
G01X707545Y366396D02*
X711419D01*
X711458Y366435D01*
G01X707545Y366396D02*
Y368817D01*
X707500Y368862D01*
G01X693367Y366479D02*
X695505Y368617D01*
X696391D01*
G01X699520Y366479D02*
X703520D01*
G01D02*
X705537Y368496D01*
Y370616D01*
X706037Y371116D01*
X709521D01*
X711363Y369274D01*
G01X700300Y376787D02*
Y375162D01*
X699500Y374362D01*
G01X704300Y376787D02*
Y375162D01*
X703500Y374362D01*
G01X700300Y379937D02*
Y382502D01*
G01X708300Y379937D02*
Y381562D01*
X707500Y382362D01*
G01X704300Y379937D02*
Y382490D01*
X700000Y386790D01*
G01X708300Y376787D02*
Y375162D01*
X707500Y374362D01*
G01X699500Y393287D02*
Y390862D01*
G01X695500Y393287D02*
Y390862D01*
G01X707500Y393287D02*
Y390862D01*
G01X703500Y396437D02*
X705340Y398277D01*
Y402018D01*
X704000Y403358D01*
Y406000D01*
G01X699500Y396437D02*
X699770Y396707D01*
Y401510D01*
X699945Y401685D01*
Y402495D01*
G01D02*
X699770Y402670D01*
Y409138D01*
X705152Y414520D01*
Y421415D01*
X706780Y423043D01*
G01X695500Y396437D02*
Y397929D01*
X694530Y398899D01*
Y400570D01*
X695039Y401079D01*
X695040D01*
G01D02*
Y401770D01*
X697510Y404240D01*
Y409210D01*
X703630Y415330D01*
Y419893D01*
G01X708218Y401233D02*
X706642Y402809D01*
Y410990D01*
X708372Y412720D01*
Y421485D01*
X709930Y423043D01*
G01X707500Y396437D02*
X708218Y397155D01*
Y401233D01*
G01X703500Y393287D02*
Y390862D01*
G01X704000Y406000D02*
Y410644D01*
X706780Y413424D01*
Y419893D01*
G01X694600Y406060D02*
Y409300D01*
X700481Y415181D01*
Y419893D01*
G01X706780Y426192D02*
X705245Y424657D01*
G01X706780Y429342D02*
X705245Y427807D01*
G01X703630Y429342D02*
X702095Y427807D01*
G01X706780Y432492D02*
X705245Y430957D01*
G01X700481Y429342D02*
X698946Y427807D01*
G01X700481Y432492D02*
X698946Y430957D01*
G01X697331Y432492D02*
X695796Y430957D01*
G01X703630Y432492D02*
X702095Y430957D01*
G01X706780Y448240D02*
X705245Y446705D01*
G01X703630Y448240D02*
X702095Y446705D01*
G01X706780Y445090D02*
X705245Y443555D01*
G01X703630Y441940D02*
X702095Y440405D01*
G01X703630Y445090D02*
X702095Y443555D01*
G01X706780Y441940D02*
X705245Y440405D01*
G01X703630Y435641D02*
X702095Y434106D01*
G01X706780Y438791D02*
X705245Y437256D01*
G01X700481Y448240D02*
X698946Y446705D01*
G01X706780Y435641D02*
X705245Y434106D01*
G01X697331Y438791D02*
X695796Y437256D01*
G01X706780Y457688D02*
X705245Y459223D01*
G01X703630Y457688D02*
X702095Y459223D01*
G01X706780Y460838D02*
X705245Y462373D01*
G01X703630Y460838D02*
X702095Y462373D01*
G01X706780Y454539D02*
X705245Y456074D01*
G01X700481Y451389D02*
X698946Y449854D01*
G01X697331Y451389D02*
X695796Y449854D01*
G01X706780Y467137D02*
X705245Y468672D01*
G01X700481Y470287D02*
X698946Y471822D01*
G01X703630Y463988D02*
X702095Y465523D01*
G01X697331Y470287D02*
X695796Y471822D01*
G01X706780Y470287D02*
X705245Y471822D01*
G01X697331Y463988D02*
X695796Y465523D01*
G01X703630Y476586D02*
X702095Y478121D01*
G01X706780Y473436D02*
X705245Y474971D01*
G01X706780Y463988D02*
X705245Y465523D01*
G01X703630Y470287D02*
X702095Y471822D01*
G01X697331Y467137D02*
X695796Y468672D01*
G01X700481Y463988D02*
X698946Y465523D01*
G01X706780Y476586D02*
X705245Y478121D01*
G01X703630Y473436D02*
X702095Y474971D01*
G01X694549Y499912D02*
Y497027D01*
X703630Y487946D01*
Y486035D01*
G01X697359Y504128D02*
Y497062D01*
X705232Y489189D01*
Y484433D01*
X706780Y482885D01*
G01X700278Y499958D02*
Y498302D01*
X704500Y494080D01*
Y491167D01*
X706780Y488887D01*
Y486035D01*
G01X700481D02*
X698946Y487570D01*
G01X700481Y479736D02*
X698946Y481271D01*
G01X700481Y482885D02*
X698946Y484420D01*
G01X706780Y479736D02*
X705245Y481271D01*
G01X703630Y479736D02*
X702095Y481271D01*
G01X697331Y482885D02*
X695796Y484420D01*
G01X709930Y486035D02*
Y487787D01*
X707080Y490637D01*
Y499060D01*
X706041Y500099D01*
G01X696500Y507787D02*
Y504987D01*
X697359Y504128D01*
G01X700500Y507787D02*
Y505457D01*
X700278Y505235D01*
Y499958D01*
G01X704666Y507742D02*
Y501474D01*
X706041Y500099D01*
G01X696500Y510937D02*
Y518694D01*
X694111Y521083D01*
Y537881D01*
G01X700500Y510937D02*
X699431Y512006D01*
Y513344D01*
G01X703774Y513463D02*
Y518804D01*
X701961Y520617D01*
Y522824D01*
X703424Y524287D01*
X704500D01*
G01X696500D02*
X696020Y523807D01*
Y521844D01*
G01X700500Y524287D02*
Y522460D01*
X699800Y521760D01*
G01X708500Y510937D02*
X707323D01*
X705783Y512477D01*
Y521852D01*
X706500Y522569D01*
Y532410D01*
X707952Y533862D01*
X708500D01*
G01X700461Y517157D02*
X697833Y519785D01*
Y522836D01*
X698628Y523631D01*
Y531805D01*
X696829Y533604D01*
G01X704666Y510892D02*
X703445D01*
X701568Y512769D01*
Y516050D01*
X700461Y517157D01*
G01X704500Y527437D02*
Y529862D01*
G01X700790Y537732D02*
Y527727D01*
X700500Y527437D01*
G01Y540287D02*
X700790Y539997D01*
Y537732D01*
G01X704500Y540287D02*
Y537862D01*
G01X696283Y540712D02*
Y538381D01*
X696740Y537924D01*
Y537855D01*
X697018Y537577D01*
G01X704500Y550287D02*
Y545862D01*
G01D02*
Y543437D01*
G01X694996Y577506D02*
Y575081D01*
G01X704056Y580656D02*
Y583081D01*
G01X708056Y580656D02*
X704056D01*
G01X694996D02*
X698996D01*
G01D02*
Y583081D01*
G01X702806Y588934D02*
Y587214D01*
X704056Y585964D01*
Y583081D01*
G01X700246Y588934D02*
Y587262D01*
X698996Y586012D01*
Y583081D01*
G01X702806Y606060D02*
Y613264D01*
G01X700246Y606060D02*
Y609889D01*
X696928Y613207D01*
G01X702645Y618536D02*
X702806Y618375D01*
Y613264D01*
G01X702645Y618536D02*
X709175D01*
X710469Y619830D01*
X729408D01*
X817453Y656301D01*
X818713Y657561D01*
X850992Y735485D01*
Y794198D01*
X862839Y806045D01*
X865569D01*
G01X696928Y613207D02*
X698654Y614933D01*
Y618527D01*
X698645Y618536D01*
G01D02*
X697325D01*
X695989Y619872D01*
Y622850D01*
X698001Y624862D01*
X709000D01*
X712352Y621510D01*
X728712D01*
X817575Y658319D01*
X849652Y735755D01*
Y795234D01*
X862963Y808545D01*
X865569D01*
G01X705158Y645357D02*
X708741Y641774D01*
X716280D01*
X719145Y644639D01*
Y646147D01*
G01X714129Y667392D02*
X713521Y668000D01*
X704710D01*
G01X700205Y733211D02*
Y728702D01*
X694812Y723309D01*
Y680188D01*
G01X701386Y679683D02*
Y684892D01*
X723814Y707320D01*
Y736782D01*
G01X725712Y734135D02*
Y706109D01*
X703584Y683981D01*
Y676544D01*
G01X705697Y679533D02*
Y683105D01*
X727576Y704984D01*
Y736756D01*
G01X693197Y766871D02*
X697747D01*
G01X706756D02*
X702206D01*
G01X706756Y763525D02*
X702206D01*
G01X693197Y770218D02*
X697747D01*
G01X695162Y1441350D02*
X702901D01*
X712537Y1450986D01*
X789465D01*
X795290Y1456811D01*
X856439D01*
X870436Y1442814D01*
Y1437362D01*
X881241Y1426557D01*
Y1320605D01*
X876126Y1315490D01*
Y1295953D01*
X851451Y1271278D01*
Y820587D01*
X860782Y811256D01*
X866736D01*
X868999Y808993D01*
Y794421D01*
X873418Y790002D01*
Y779722D01*
X877345Y775795D01*
Y671427D01*
X856446Y650528D01*
Y643385D01*
X811163Y598102D01*
Y590863D01*
X792782Y572482D01*
Y565323D01*
G01X701090Y1531700D02*
X707050D01*
G01X701090Y1536250D02*
X709150D01*
G01X701090Y1551700D02*
X703290D01*
G01X709150D02*
X708384D01*
X706903Y1550219D01*
X704771D01*
X703290Y1551700D01*
G01X701090Y1548400D02*
X707050D01*
G01X701090Y1541800D02*
X707050D01*
G01X709150Y1545100D02*
X703290D01*
G01X705075Y1600500D02*
X705500D01*
X707500Y1598500D01*
Y1597057D01*
X709836Y1594721D01*
G01X705075Y1608500D02*
Y1604500D01*
G01D02*
X706092D01*
X709382Y1601210D01*
G01X713718Y1610235D02*
Y1616735D01*
X709650Y1620803D01*
X704562D01*
X702303Y1623062D01*
G01X702566Y1616656D02*
X709020Y1610202D01*
Y1609101D01*
G01X699153Y1623062D02*
X696331D01*
X695933Y1623460D01*
G01X705716Y1616656D02*
X708013D01*
X709260Y1617903D01*
G01X711269Y1643326D02*
Y1640034D01*
X707240Y1636005D01*
X699858D01*
X697950Y1634097D01*
G01D02*
X696030Y1632177D01*
Y1630852D01*
G01X699799Y1630768D02*
X703799D01*
G01X707997D02*
X703799D01*
G01X697261Y1645891D02*
Y1643332D01*
G01X705688Y1647367D02*
X702160D01*
G01D02*
X698737D01*
X697261Y1645891D01*
G01X696842Y1670408D02*
X694281D01*
X693608Y1671081D01*
G01X699992Y1670408D02*
X702920D01*
X704019Y1671507D01*
G01X696880Y1674429D02*
X693969D01*
X693480Y1673940D01*
G01X709523Y1674429D02*
X700030D01*
G01X704019Y1671507D02*
X712254D01*
X714221Y1669540D01*
Y1666358D01*
G01X699914Y1678474D02*
Y1681996D01*
G01X719339Y1666358D02*
Y1669150D01*
X710015Y1678474D01*
X704659D01*
G01D02*
X699914D01*
G01X726228Y53543D02*
Y48757D01*
X723333Y45862D01*
X719821D01*
G01X721504Y65157D02*
Y62065D01*
X720301Y60862D01*
X718478D01*
X714322Y56706D01*
Y56286D01*
G01X721504Y53543D02*
Y51745D01*
X716429Y46670D01*
X714471D01*
G01X753501Y151312D02*
Y148956D01*
X748545Y144000D01*
X742500D01*
X739456Y140956D01*
X728809D01*
X725765Y144000D01*
X723500D01*
X720500Y141000D01*
X715779D01*
X711110Y136331D01*
Y131670D01*
X710683Y131243D01*
X708953D01*
G01Y128093D02*
X712341D01*
G01X710451Y152512D02*
Y157436D01*
X710125Y157762D01*
G01X720300Y379937D02*
X722078Y378159D01*
Y370315D01*
X723531Y368862D01*
G01X723500Y366437D02*
X723290D01*
X721031Y368696D01*
X719666D01*
X719500Y368862D01*
G01X715395Y366427D02*
X719324D01*
X719334Y366437D01*
G01X715395Y366427D02*
Y368757D01*
X715500Y368862D01*
G01X716300Y376787D02*
Y375162D01*
X715500Y374362D01*
G01X720300Y376787D02*
Y375162D01*
X719500Y374362D01*
G01X712300Y379937D02*
Y381562D01*
X711500Y382362D01*
G01X719640Y386862D02*
X716300Y383522D01*
Y379937D01*
G01X715500Y393287D02*
X714926D01*
X713500Y391861D01*
Y388862D01*
X715500Y386862D01*
G01X712300Y376787D02*
Y375162D01*
X711500Y374362D01*
G01Y405673D02*
Y396437D01*
G01X715500D02*
Y401378D01*
G01D02*
Y412571D01*
X713079Y414992D01*
Y419893D01*
G01X719500Y396437D02*
Y406062D01*
G01X711500Y393287D02*
Y390862D01*
G01X709930Y419893D02*
Y415097D01*
X711500Y413527D01*
Y405673D01*
G01X723500Y401062D02*
Y409660D01*
X716229Y416931D01*
Y419893D01*
G01X719500Y406062D02*
Y411238D01*
X714652Y416086D01*
Y421466D01*
X716229Y423043D01*
G01X722528Y419893D02*
X720993Y418358D01*
G01X719378Y419893D02*
X717843Y418358D01*
G01X719378Y423043D02*
X717843Y421508D01*
G01X722528Y432492D02*
X720993Y430957D01*
G01X713079Y432492D02*
X711544Y430957D01*
G01X716229Y432492D02*
X714694Y430957D01*
G01X719378Y432492D02*
X717843Y430957D01*
G01X722528Y423043D02*
X720993Y421508D01*
G01X709930Y429342D02*
X708395Y427807D01*
G01X709930Y426192D02*
X708395Y424657D01*
G01X722528Y426192D02*
X720993Y424657D01*
G01X719378Y426192D02*
X717843Y424657D01*
G01X719378Y429342D02*
X717843Y427807D01*
G01X716229Y426192D02*
X714694Y424657D01*
G01X716229Y429342D02*
X714694Y427807D01*
G01X713079Y429342D02*
X711544Y427807D01*
G01X722528Y429342D02*
X720993Y427807D01*
G01X719378Y435641D02*
X717843Y434106D01*
G01X722528Y435641D02*
X720993Y434106D01*
G01X719378Y438791D02*
X717843Y437256D01*
G01X722528Y438791D02*
X720993Y437256D01*
G01X716229Y438791D02*
X714694Y437256D01*
G01X713079Y435641D02*
X711544Y434106D01*
G01X716229Y435641D02*
X714694Y434106D01*
G01X713079Y438791D02*
X711544Y437256D01*
G01X709930Y435641D02*
X708395Y434106D01*
G01X709930Y441940D02*
X708395Y440405D01*
G01X709930Y445090D02*
X708395Y443555D01*
G01X713079Y445090D02*
X711544Y443555D01*
G01X709930Y438791D02*
X708395Y437256D01*
G01X716229Y441940D02*
X714694Y440405D01*
G01X709930Y448240D02*
X708395Y446705D01*
G01X713079Y441940D02*
X711544Y440405D01*
G01X716229Y445090D02*
X714694Y443555D01*
G01X713079Y448240D02*
X711544Y446705D01*
G01X709930Y460838D02*
X708395Y462373D01*
G01X709930Y451389D02*
X708395Y449854D01*
G01X713079Y457688D02*
X711544Y459223D01*
G01X716229Y460838D02*
X714694Y462373D01*
G01X713079Y460838D02*
X711544Y462373D01*
G01X709930Y454539D02*
X708395Y456074D01*
G01X716229Y451389D02*
X714694Y449854D01*
G01X713079Y451389D02*
X711544Y449854D01*
G01X716229Y454539D02*
X714694Y456074D01*
G01X713079Y454539D02*
X711544Y456074D01*
G01X709930Y457688D02*
X708395Y459223D01*
G01X709930Y463988D02*
X708395Y465523D01*
G01X722528Y470287D02*
X720993Y471822D01*
G01X722528Y467137D02*
X720993Y468672D01*
G01X713079Y476586D02*
X711544Y478121D01*
G01X719378Y473436D02*
X717843Y474971D01*
G01X722528Y476586D02*
X720993Y478121D01*
G01X719378Y476586D02*
X717843Y478121D01*
G01X722528Y473436D02*
X720993Y474971D01*
G01X716229Y463988D02*
X714694Y465523D01*
G01X719378Y470287D02*
X717843Y471822D01*
G01X719378Y467137D02*
X717843Y468672D01*
G01X716229Y470287D02*
X714694Y471822D01*
G01X713079Y470287D02*
X711544Y471822D01*
G01X709930Y476586D02*
X708395Y478121D01*
G01X716229Y467137D02*
X714694Y468672D01*
G01X713079Y467137D02*
X711544Y468672D01*
G01X709930Y470287D02*
X708395Y471822D01*
G01X713079Y473436D02*
X711544Y474971D01*
G01X709930Y467137D02*
X708395Y468672D01*
G01X716229Y476586D02*
X714694Y478121D01*
G01X716229Y473436D02*
X714694Y474971D01*
G01X713079Y463988D02*
X711544Y465523D01*
G01X719378Y479736D02*
X717843Y481271D01*
G01X716229Y479736D02*
X714694Y481271D01*
G01X722528Y486035D02*
Y489510D01*
X724500Y491482D01*
Y503014D01*
G01X714672Y515211D02*
Y506053D01*
X713920Y505301D01*
Y502083D01*
X714864Y501139D01*
Y495922D01*
X716229Y494557D01*
Y486035D01*
G01X713079D02*
Y487998D01*
X709570Y491507D01*
Y504315D01*
G01X712500Y500014D02*
Y495986D01*
X714622Y493864D01*
Y484492D01*
X716229Y482885D01*
G01X722528Y479736D02*
X720993Y481271D01*
G01X720500Y500014D02*
Y491692D01*
X719378Y490570D01*
Y486035D01*
G01X716500Y503014D02*
Y496295D01*
X717802Y494993D01*
Y484461D01*
X719378Y482885D01*
G01X722528D02*
X720993Y484420D01*
G01X709930Y482885D02*
X708395Y484420D01*
G01X709930Y479736D02*
X708395Y481271D01*
G01X709570Y504315D02*
X708500Y505385D01*
Y507787D01*
G01X712500D02*
Y500014D01*
G01X720500Y507787D02*
Y500014D01*
G01X716500Y507787D02*
Y503014D01*
G01Y521862D02*
X716016Y522346D01*
Y524350D01*
G01X712484Y522976D02*
Y522352D01*
X714672Y520164D01*
Y515211D01*
G01X724500Y517362D02*
X723634D01*
X722500Y518496D01*
Y523708D01*
X723032Y524240D01*
G01X719518Y524256D02*
Y521492D01*
X720500Y520510D01*
Y517540D01*
X720400Y517440D01*
G01X720500Y510937D02*
X720452Y510985D01*
Y513362D01*
G01X716500Y510937D02*
X716716Y511153D01*
Y513368D01*
G01X712113Y537797D02*
Y528446D01*
X710500Y526833D01*
Y516505D01*
X709511Y515516D01*
Y512736D01*
X711310Y510937D01*
X712500D01*
G01X708509Y523770D02*
Y517371D01*
X708500Y517362D01*
G01X791723Y574946D02*
X775809D01*
X745775Y562505D01*
X743227Y559957D01*
X718593D01*
X716385Y557749D01*
Y536314D01*
X716500Y536199D01*
Y530852D01*
X716016Y530368D01*
Y527500D01*
G01X720499Y533474D02*
X720530Y533443D01*
Y529892D01*
X723032Y527390D01*
G01X708500Y540287D02*
X708210Y539997D01*
Y537816D01*
G01X719518Y527406D02*
Y529252D01*
X718689Y530081D01*
Y536051D01*
X719841Y537203D01*
Y537348D01*
G01D02*
X719986D01*
X720500Y537862D01*
Y540287D01*
G01X712409Y555413D02*
X713942Y553880D01*
Y527584D01*
X712484Y526126D01*
G01X708509Y526920D02*
X710350Y528761D01*
Y537028D01*
X710167Y537211D01*
Y538740D01*
X712115Y540688D01*
Y541872D01*
G01X726793Y527424D02*
Y528354D01*
X726512Y528635D01*
Y529993D01*
X726707Y530188D01*
Y532183D01*
X725806Y533084D01*
X723485D01*
X722194Y534375D01*
Y541979D01*
X722730Y542515D01*
Y547650D01*
X721915Y548465D01*
X718985D01*
X718171Y549279D01*
Y556815D01*
X719557Y558201D01*
X743906D01*
X746856Y561151D01*
X754303D01*
X759407Y566255D01*
X763166Y567812D01*
X764399D01*
X768081Y569337D01*
X775815D01*
X778747Y572269D01*
G01X724684Y545864D02*
Y547738D01*
X722135Y550287D01*
X720500D01*
G01X708500Y543437D02*
Y555451D01*
G01X710464Y549398D02*
Y545787D01*
X710429Y545752D01*
G01X710464Y552548D02*
Y557036D01*
G01X708056Y577506D02*
Y575081D01*
G01X716721Y633842D02*
X713343D01*
G01X716721D02*
X717466Y634587D01*
Y638957D01*
X721113Y642604D01*
Y646147D01*
G01X720787Y633906D02*
X724000D01*
G01X723082Y646147D02*
Y641243D01*
X720787Y638948D01*
Y633906D01*
G01X717176Y651187D02*
Y652921D01*
X715371Y654726D01*
G01X719145Y651187D02*
Y653734D01*
X718129Y654750D01*
Y656130D01*
G01D02*
Y661092D01*
G01X721113Y651187D02*
Y652835D01*
X723166Y654888D01*
Y656225D01*
G01X726201Y667394D02*
X724598Y668997D01*
X717755D01*
X715803Y670949D01*
G01X714129Y661092D02*
X718129D01*
G01X723166Y656225D02*
Y658023D01*
X722129Y659060D01*
Y661092D01*
G01X726201Y661094D02*
X722131D01*
X722129Y661092D01*
G01X714129Y664242D02*
X712170D01*
X711295Y665117D01*
G01X754532Y735859D02*
Y722975D01*
X714111Y682554D01*
Y678859D01*
X712164Y676912D01*
G01X735316Y736742D02*
Y706554D01*
X712120Y683358D01*
Y680287D01*
G01X729391Y734135D02*
Y703525D01*
X708012Y682146D01*
Y676836D01*
G01X760425Y736233D02*
Y726071D01*
X715568Y681214D01*
Y678786D01*
X719213Y675141D01*
X721708D01*
X724931Y678364D01*
G01X717515Y679833D02*
X762396Y724714D01*
Y732915D01*
G01X720563Y679886D02*
X764568Y723891D01*
Y736183D01*
G01X720613Y677040D02*
X771941Y728368D01*
X778401D01*
X784543Y734510D01*
G01X709150Y1538500D02*
Y1536250D01*
G01X720325Y1566333D02*
Y1569848D01*
X721440Y1570963D01*
G01D02*
X722356Y1571879D01*
Y1573552D01*
G01X716697Y1588562D02*
X715110D01*
X711403Y1592269D01*
Y1593154D01*
X709836Y1594721D01*
G01X717110Y1599448D02*
X717466Y1599092D01*
X719621D01*
X723390Y1595323D01*
X723590D01*
G01X709382Y1601210D02*
Y1597405D01*
X709756Y1597031D01*
X710794D01*
X711795Y1596030D01*
X713310Y1592371D01*
X714511Y1591170D01*
X718813D01*
G01X718892Y1597152D02*
Y1596001D01*
X722356Y1592537D01*
Y1591170D01*
G01X720585D02*
Y1591838D01*
X719477Y1592946D01*
X716185D01*
X714452Y1594679D01*
X714372D01*
G01X715152Y1627506D02*
Y1623434D01*
X715744Y1622842D01*
G01X725286Y1614743D02*
X719596D01*
X717229Y1612376D01*
G01X715152Y1627506D02*
X719152D01*
G01X719339Y1643326D02*
Y1640352D01*
X718116Y1639129D01*
G01X715152Y1634265D02*
Y1630656D01*
G01X716780Y1643326D02*
Y1640394D01*
X715152Y1638766D01*
Y1634265D01*
G01X721898Y1636624D02*
Y1632920D01*
X724723Y1630095D01*
G01X721898Y1643326D02*
Y1640203D01*
X723099Y1639002D01*
Y1637825D01*
X721898Y1636624D01*
G01X707997Y1630768D02*
Y1634114D01*
X714221Y1640338D01*
Y1643326D01*
G01X716780Y1666358D02*
Y1669414D01*
X712042Y1674152D01*
X709800D01*
X709523Y1674429D01*
G01X724457Y1666358D02*
Y1668978D01*
X722647Y1670788D01*
Y1674929D01*
X722015Y1675561D01*
Y1677258D01*
X721408Y1677865D01*
G01X721898Y1666358D02*
Y1669263D01*
X720259Y1670902D01*
Y1671569D01*
X718891Y1672937D01*
G01X721909Y1684446D02*
Y1687553D01*
X723181Y1688825D01*
G01X721408Y1677865D02*
Y1680795D01*
X721909Y1681296D01*
G01X715309Y1680118D02*
X716513D01*
X719117Y1682722D01*
G01X718891Y1672937D02*
X715309Y1676519D01*
Y1676968D01*
G01X735677Y53543D02*
Y46206D01*
X736621Y45262D01*
G01X733315Y53543D02*
Y40862D01*
G01X730953Y53543D02*
Y45794D01*
X728721Y43562D01*
G01X728591Y53543D02*
Y47472D01*
X724621Y43502D01*
Y40062D01*
G01X723866Y65157D02*
Y62397D01*
X725701Y60562D01*
X726789D01*
G01X742764Y65157D02*
Y62405D01*
X741956Y61597D01*
X735609D01*
X734769Y60757D01*
G01X726228Y65157D02*
Y69278D01*
X725769Y69737D01*
G01X734380Y74943D02*
X736864D01*
G01X735677Y65157D02*
Y72925D01*
X736864Y74112D01*
Y74943D01*
G01X729380D02*
X731864D01*
G01X733315Y65157D02*
Y73005D01*
X731864Y74456D01*
Y74943D01*
G01X728591Y65157D02*
Y71819D01*
X727200Y73210D01*
G01X737093Y87902D02*
X733972D01*
X733068Y86998D01*
G01X737093Y87902D02*
X741048D01*
X741850Y87100D01*
G01X734380Y78093D02*
Y80518D01*
G01X729380Y78093D02*
Y80518D01*
G01X741097Y101942D02*
X737058D01*
X736650Y102350D01*
G01D02*
X736268Y101968D01*
X733578D01*
G01X733098Y95158D02*
X733268Y94988D01*
X735771D01*
G01X741097Y98005D02*
Y97697D01*
X738468Y95068D01*
X735851D01*
X735771Y94988D01*
G01X741097Y103911D02*
X739012D01*
X737521Y105402D01*
X733644D01*
X733578Y105468D01*
G01D02*
Y107745D01*
X732839Y108484D01*
X730660D01*
G01X733068Y90998D02*
X737039D01*
X737093Y91052D01*
G01D02*
X739824D01*
G01X745500Y199425D02*
Y183000D01*
X740000Y177500D01*
Y153000D01*
X735500Y148500D01*
Y143000D01*
G01X863369Y827461D02*
X878810Y812020D01*
Y806326D01*
X891765Y793371D01*
Y651261D01*
X872157Y631653D01*
Y581182D01*
X879624Y573715D01*
Y544110D01*
X881687Y542047D01*
Y491302D01*
X869978Y479593D01*
Y462920D01*
X877354Y455544D01*
Y381504D01*
X864868Y369018D01*
X831200D01*
X820935Y358753D01*
Y354957D01*
X818072Y352094D01*
X799296D01*
X798181Y350979D01*
X785386D01*
X784271Y352094D01*
X746262D01*
X744034Y349866D01*
X732698D01*
X729211Y346379D01*
G01X726431Y346384D02*
X731253Y351206D01*
X743478D01*
X745706Y353434D01*
X785738D01*
X786704Y352468D01*
X797750D01*
X798716Y353434D01*
X813145D01*
X830107Y370396D01*
X864350D01*
X876014Y382060D01*
Y454365D01*
X868638Y461741D01*
Y480149D01*
X880347Y491858D01*
Y541490D01*
X878284Y543553D01*
Y573159D01*
X870817Y580626D01*
Y632209D01*
X890425Y651817D01*
Y792814D01*
X877470Y805769D01*
Y811267D01*
X864024Y824713D01*
X863344D01*
G01X863372Y830718D02*
X880150Y813940D01*
Y806883D01*
X893105Y793928D01*
Y650705D01*
X873497Y631097D01*
Y581738D01*
X880964Y574271D01*
Y544667D01*
X883183Y542448D01*
Y490902D01*
X871318Y479037D01*
Y463476D01*
X878694Y456100D01*
Y380948D01*
X865387Y367641D01*
X831719D01*
X822275Y358197D01*
Y353933D01*
X819096Y350754D01*
X799852D01*
X798641Y349543D01*
X784926D01*
X783715Y350754D01*
X746818D01*
X744590Y348526D01*
X736277D01*
X734463Y346712D01*
G01X735449Y371953D02*
Y368913D01*
X735500Y368862D01*
G01X727564Y376787D02*
Y368862D01*
G01X731500Y363287D02*
Y360862D01*
G01X723500Y363287D02*
Y360862D01*
G01X731500Y366437D02*
Y368862D01*
G01X731406Y379906D02*
X734175Y382675D01*
Y385537D01*
X735500Y386862D01*
G01X727564Y379937D02*
Y386798D01*
X727500Y386862D01*
G01X723500Y393287D02*
Y390862D01*
G01X733900Y405940D02*
X733200Y405240D01*
Y397689D01*
X734452Y396437D01*
X735500D01*
G01X723500D02*
Y401062D01*
G01X735500Y393287D02*
Y390862D01*
G01X731500Y396437D02*
X731300Y396637D01*
Y398645D01*
X731208Y398737D01*
G01D02*
X731000Y398945D01*
Y413431D01*
X735126Y417557D01*
Y419893D01*
G01X727500Y396437D02*
Y414192D01*
X730403Y417095D01*
Y434065D01*
X728827Y435641D01*
G01X738276Y419893D02*
Y406426D01*
X737425Y405575D01*
Y402000D01*
G01X739652Y396419D02*
Y399773D01*
X737425Y402000D01*
G01X739652Y393269D02*
X738000D01*
X737500Y393769D01*
Y397330D01*
X735500Y399330D01*
G01X735126Y423043D02*
X736722Y421447D01*
Y416414D01*
X733900Y413592D01*
Y405940D01*
G01X731977Y419893D02*
X733512Y418358D01*
G01X728827Y419893D02*
X727292Y418358D01*
G01X725678Y419893D02*
X724143Y418358D01*
G01X735126Y426192D02*
X736661Y424657D01*
G01X735126Y432492D02*
X736661Y430957D01*
G01X731977Y423043D02*
X733512Y421508D01*
G01X731977Y432492D02*
X733512Y430957D01*
G01X728827Y432492D02*
X727292Y430957D01*
G01X725678Y432492D02*
X724143Y430957D01*
G01X728827Y429342D02*
X727292Y427807D01*
G01X735126Y429342D02*
X736661Y427807D01*
G01X728827Y426192D02*
X727292Y424657D01*
G01X725678Y423043D02*
X724143Y421508D01*
G01X725678Y429342D02*
X724143Y427807D01*
G01X725678Y426192D02*
X724143Y424657D01*
G01X735126Y435641D02*
X736661Y434106D01*
G01X731977Y435641D02*
X733512Y434106D01*
G01X731977Y438791D02*
X733512Y437256D01*
G01X728827Y438791D02*
X727292Y437256D01*
G01X728827Y435641D02*
X727292Y434106D01*
G01X725678Y438791D02*
X724143Y437256D01*
G01X725678Y435641D02*
X724143Y434106D01*
G01X735126Y438791D02*
X736661Y437256D01*
G01X728827Y470287D02*
X727292Y471822D01*
G01X725678Y467137D02*
X724143Y468672D01*
G01X728827Y467137D02*
X727292Y468672D01*
G01X735126Y467137D02*
X736661Y468672D01*
G01X725678Y470287D02*
X724143Y471822D01*
G01X725678Y473436D02*
X724143Y474971D01*
G01X731977Y476586D02*
X733512Y478121D01*
G01X731977Y467137D02*
X733512Y468672D01*
G01X735126Y476586D02*
X736661Y478121D01*
G01X735126Y470287D02*
X736661Y471822D01*
G01X725678Y476586D02*
X724143Y478121D01*
G01X728827Y476586D02*
X727292Y478121D01*
G01X731977Y470287D02*
X733512Y471822D01*
G01X735126Y473436D02*
X736661Y474971D01*
G01X736500Y510937D02*
X737424D01*
X738275Y510086D01*
Y502137D01*
X738848Y501564D01*
Y498564D01*
X736500Y496216D01*
Y487731D01*
X736661Y487570D01*
G01X736500Y500014D02*
X734422Y497936D01*
Y486739D01*
X735126Y486035D01*
G01X732500Y503014D02*
Y488157D01*
X733552Y487105D01*
Y484460D01*
X731977Y482885D01*
G01X728500Y500014D02*
X729324Y499190D01*
Y488688D01*
X731977Y486035D01*
G01X735126Y479736D02*
X736661Y481271D01*
G01X731977Y479736D02*
X733512Y481271D01*
G01X725678Y479736D02*
X724143Y481271D01*
G01X728827Y479736D02*
X727292Y481271D01*
G01X725678Y486035D02*
X724143Y487570D01*
G01X728827Y482885D02*
X727292Y484420D01*
G01X728827Y486035D02*
X727292Y487570D01*
G01X726793Y524274D02*
X726498Y523979D01*
Y506657D01*
X726997Y506158D01*
Y502066D01*
X726048Y501117D01*
Y498455D01*
X727292Y497211D01*
Y487570D01*
G01X736500Y500014D02*
Y507787D01*
G01X724500D02*
Y503014D01*
G01X732500Y507787D02*
Y503014D01*
G01X728500Y507787D02*
Y500014D01*
G01X724500Y510937D02*
Y513362D01*
G01X732500D02*
Y510937D01*
G01X730310Y524208D02*
Y523672D01*
X728500Y521862D01*
G01Y513362D02*
Y510937D01*
G01X733811Y524162D02*
Y522466D01*
X732500Y521155D01*
Y518442D01*
X736339Y514603D01*
G01X738672Y494444D02*
X740293Y496065D01*
Y502754D01*
X739796Y503251D01*
Y510657D01*
X737000Y513453D01*
Y513942D01*
X736339Y514603D01*
G01X737324Y523928D02*
Y521959D01*
X736609Y521244D01*
Y518426D01*
G01X728500Y529862D02*
Y529168D01*
X730310Y527358D01*
G01X728500Y540287D02*
Y537552D01*
X728576Y537476D01*
G01X736500Y540287D02*
Y537862D01*
G01X724500Y540287D02*
X724336Y540123D01*
Y537527D01*
G01X732500Y529862D02*
Y528623D01*
X733811Y527312D01*
G01X732500Y540425D02*
X734570Y538355D01*
Y531849D01*
X736647Y529772D01*
G01X737324Y527078D02*
X738967Y528721D01*
Y536538D01*
X738690Y536815D01*
Y547751D01*
X735734Y550707D01*
Y554355D01*
X738114Y556735D01*
X744645D01*
X747397Y559487D01*
X756677D01*
X762530Y565340D01*
G01X736500Y543437D02*
Y545694D01*
X736670Y545864D01*
G01X724500Y543437D02*
Y545680D01*
X724684Y545864D01*
G01X724281Y553438D02*
Y552284D01*
X727933Y548632D01*
X728493D01*
X730487Y546638D01*
Y544378D01*
X729546Y543437D01*
X728500D01*
G01X732500Y543575D02*
X733836D01*
X734730Y544469D01*
Y548174D01*
X728714Y554190D01*
G01X736528Y579615D02*
Y611492D01*
X753149Y628113D01*
X818045Y654996D01*
X819849Y656800D01*
X852332Y735216D01*
Y792267D01*
X864149Y804084D01*
X866629D01*
X867430Y804885D01*
Y809286D01*
X866353Y810363D01*
X859725D01*
X850297Y819791D01*
Y1271369D01*
X875246Y1296318D01*
Y1315915D01*
X879063Y1319732D01*
Y1423703D01*
X879424Y1424064D01*
Y1425001D01*
G01X723082Y651187D02*
Y651983D01*
X725812Y654713D01*
G01X730770Y644218D02*
X758486D01*
X773178Y658910D01*
X776674D01*
X835553Y717789D01*
X843949Y738057D01*
Y789942D01*
X826482Y807409D01*
X822555D01*
G01X731694Y662061D02*
X738009Y655746D01*
Y655152D01*
X735741Y652884D01*
X735740Y652292D01*
X736859Y651173D01*
X737453D01*
X739721Y653441D01*
X740315Y653440D01*
X741433Y652322D01*
Y651728D01*
X739165Y649460D01*
X739164Y648868D01*
X740283Y647749D01*
X740877D01*
X743145Y650017D01*
X743739Y650016D01*
X747328Y646427D01*
X757501D01*
X772181Y661107D01*
X775825D01*
X833787Y719069D01*
X841829Y738484D01*
Y789062D01*
X825803Y805088D01*
X821539D01*
X816550Y800099D01*
Y770218D01*
G01X726201Y664244D02*
X729511D01*
X731694Y662061D01*
G01X734442Y675695D02*
Y678491D01*
X774261Y718310D01*
X800447D01*
X812995Y730858D01*
X820408Y748755D01*
Y795588D01*
X822331Y797511D01*
X822794D01*
G01X722898Y766871D02*
X727448D01*
G01X736457D02*
X731462D01*
G01X736457Y763525D02*
X731907D01*
G01X722898Y770218D02*
X727448D01*
G01X727325Y1563400D02*
Y1566333D01*
G01X723590Y1595323D02*
X723710Y1595203D01*
Y1592664D01*
X723936Y1592438D01*
Y1591362D01*
X724128Y1591170D01*
G01X732723Y1626945D02*
Y1625705D01*
X730647Y1623629D01*
G01X724723Y1626945D02*
Y1624325D01*
X722889Y1622491D01*
G01X728723Y1626945D02*
Y1625101D01*
X727320Y1623698D01*
G01X736723Y1626945D02*
Y1623938D01*
G01X728723Y1630095D02*
Y1633831D01*
X727755Y1634799D01*
Y1636539D01*
G01D02*
Y1637997D01*
X729576Y1639818D01*
Y1643326D01*
G01X732260Y1633591D02*
Y1637367D01*
X732135Y1637492D01*
Y1643326D01*
G01X732723Y1630095D02*
Y1631487D01*
X732260Y1631950D01*
Y1633591D01*
G01X736485Y1636763D02*
X734694Y1638554D01*
Y1643326D01*
G01X736723Y1630095D02*
Y1636525D01*
X736485Y1636763D01*
G01X740723Y1633619D02*
Y1636708D01*
X737253Y1640178D01*
Y1643326D01*
G01X734694Y1666358D02*
Y1670560D01*
X738526Y1674392D01*
G01X734017Y1676824D02*
Y1671687D01*
X732135Y1669805D01*
Y1666358D01*
G01X730592Y1672921D02*
X729576Y1671905D01*
Y1666358D01*
G01X727017D02*
Y1671584D01*
X725371Y1673230D01*
G01X737253Y1666358D02*
Y1669752D01*
X743478Y1675977D01*
Y1681759D01*
X745382Y1683663D01*
G01X737468Y1687128D02*
Y1683683D01*
X737467Y1683682D01*
G01X729616Y1680336D02*
Y1682171D01*
X730347Y1682902D01*
G01D02*
X732434Y1684989D01*
Y1685098D01*
G01X725638Y1682890D02*
Y1680341D01*
X725632Y1680335D01*
G01X728454Y1684929D02*
X727677D01*
X725638Y1682890D01*
G01X737467Y1680532D02*
Y1680274D01*
X734017Y1676824D01*
G01X729616Y1677186D02*
X730592Y1676210D01*
Y1672921D01*
G01X725632Y1677185D02*
Y1675334D01*
X725371Y1675073D01*
Y1673230D01*
G01X732852Y1695701D02*
X734977Y1693576D01*
Y1689619D01*
X737468Y1687128D01*
G01X740402Y53543D02*
Y47481D01*
X745901Y41982D01*
Y40362D01*
G01X738039Y53543D02*
Y46844D01*
X740101Y44782D01*
Y41162D01*
G01X742764Y53543D02*
Y48167D01*
X744669Y46262D01*
X746101D01*
G01X747488Y65157D02*
Y71429D01*
G01X740402Y65157D02*
Y69743D01*
X740537Y69878D01*
Y73564D01*
G01X741850Y87100D02*
Y89010D01*
X745035Y92195D01*
Y98005D01*
G01X750940Y103911D02*
Y106403D01*
X750701Y106642D01*
G01X743066Y98005D02*
Y97556D01*
X739824Y94314D01*
Y91052D01*
G01X743066Y103911D02*
Y106985D01*
X741309Y108742D01*
G01X751558Y111288D02*
Y111218D01*
X750496Y110156D01*
Y106847D01*
X750701Y106642D01*
G01X751558Y115288D02*
Y111288D01*
G01X751560Y119172D02*
Y115290D01*
X751558Y115288D01*
G01X741270Y115584D02*
Y111290D01*
X741308Y111252D01*
G01D02*
Y108743D01*
X741309Y108742D01*
G01X745660Y142050D02*
Y137874D01*
X745670Y137864D01*
G01D02*
X744368D01*
X743050Y139182D01*
G01X748810Y142050D02*
X748811D01*
X750199Y143438D01*
X753601D01*
G01X748160Y161463D02*
X745031D01*
G01X751310D02*
X763722D01*
X764343Y162084D01*
G01X751275Y167537D02*
X752876D01*
X755901Y170562D01*
G01X751575Y175500D02*
X753606Y177531D01*
Y182221D01*
X751575Y184252D01*
G01X745500Y202575D02*
X747924D01*
X749000Y201499D01*
Y191206D01*
X754737Y185469D01*
G01X751000Y212760D02*
Y212000D01*
X746500Y207500D01*
G01D02*
X745500Y206500D01*
Y202575D01*
G01X748441Y220240D02*
Y224441D01*
X749000Y225000D01*
X751000D01*
G01Y220240D02*
Y225000D01*
G01X754479Y228201D02*
X754201D01*
X751000Y225000D01*
G01X746522Y308804D02*
X748483Y310765D01*
X750630Y315948D01*
X760787Y326105D01*
X770129D01*
X774773Y330749D01*
X782512D01*
X785015Y333252D01*
X821092D01*
X842088Y354248D01*
X870321D01*
X891134Y375061D01*
Y461279D01*
X884463Y467950D01*
Y473795D01*
X896551Y485883D01*
Y552426D01*
X895335Y553642D01*
Y578431D01*
X886362Y587404D01*
Y626222D01*
X915212Y655072D01*
Y726169D01*
X914313Y727068D01*
Y737217D01*
X907689Y753209D01*
Y802716D01*
X896127Y814278D01*
Y832749D01*
X903107Y839729D01*
X909373D01*
X909793Y839309D01*
Y833544D01*
X910213Y833124D01*
X911003D01*
X911423Y833544D01*
Y839309D01*
X911843Y839729D01*
X929422D01*
X952773Y863080D01*
X956920D01*
X958000Y862000D01*
G01X747594Y319106D02*
Y321100D01*
X753939Y327445D01*
X769573D01*
X774217Y332089D01*
X781956D01*
X784459Y334592D01*
X820298D01*
X841294Y355588D01*
X869765D01*
X889794Y375617D01*
Y460723D01*
X883123Y467394D01*
Y474351D01*
X895211Y486439D01*
Y551870D01*
X893995Y553086D01*
Y577875D01*
X885022Y586848D01*
Y626778D01*
X913872Y655628D01*
Y725561D01*
X912847Y726586D01*
Y737254D01*
X906349Y752941D01*
Y801694D01*
X894591Y813452D01*
Y833109D01*
X902551Y841069D01*
X928866D01*
X952217Y864420D01*
X956920D01*
X958000Y865500D01*
G01X867651Y836820D02*
X884270Y820201D01*
Y808453D01*
X897125Y795598D01*
Y649037D01*
X877517Y629429D01*
Y583406D01*
X884984Y575939D01*
Y546336D01*
X887388Y543932D01*
Y489210D01*
X884984Y486806D01*
Y486805D01*
X875338Y477159D01*
Y465144D01*
X882714Y457768D01*
Y379280D01*
X866516Y363082D01*
X838911D01*
X822563Y346734D01*
X801521D01*
X799969Y345182D01*
X783598D01*
X782046Y346734D01*
X774636D01*
X774216Y346314D01*
Y344496D01*
X773796Y344076D01*
X772906D01*
X772486Y344496D01*
Y346314D01*
X772066Y346734D01*
X771176D01*
X770756Y346314D01*
Y344496D01*
X770336Y344076D01*
X769446D01*
X769026Y344496D01*
Y346314D01*
X768606Y346734D01*
X766329D01*
X761143Y341548D01*
X750786D01*
X748752Y343582D01*
G01X867733Y575522D02*
X874189Y569066D01*
Y541958D01*
X876327Y539820D01*
Y493527D01*
X864477Y481677D01*
Y454570D01*
X874620Y444427D01*
Y382601D01*
X868923Y376904D01*
X865436D01*
X861721Y373189D01*
X829151D01*
X813039Y357077D01*
X798574D01*
X797151Y355654D01*
X791090D01*
X790199Y356545D01*
X749584D01*
X747500Y358629D01*
Y368862D01*
G01X775075Y364000D02*
Y362075D01*
X771000Y358000D01*
X751889D01*
X749389Y360500D01*
Y360816D01*
G01X738773Y346716D02*
X744676D01*
X747374Y349414D01*
X783158D01*
X784544Y348028D01*
X799022D01*
X800408Y349414D01*
X819653D01*
X823615Y353376D01*
Y357641D01*
X832194Y366220D01*
X865862D01*
X880034Y380392D01*
Y456656D01*
X872658Y464032D01*
Y478271D01*
X882304Y487917D01*
Y487918D01*
X884523Y490137D01*
Y543004D01*
X882304Y545223D01*
Y574827D01*
X874837Y582294D01*
Y630541D01*
X894445Y650149D01*
Y794484D01*
X881590Y807339D01*
Y815251D01*
X863372Y833469D01*
G01X867646Y833388D02*
X882930Y818104D01*
Y807896D01*
X895785Y795041D01*
Y649593D01*
X876177Y629985D01*
Y582850D01*
X883644Y575383D01*
Y545779D01*
X885863Y543560D01*
Y489581D01*
X884029Y487747D01*
Y487746D01*
X873998Y477715D01*
Y464588D01*
X881374Y457212D01*
Y379836D01*
X866087Y364549D01*
X832420D01*
X824955Y357084D01*
Y352820D01*
X820209Y348074D01*
X800965D01*
X799509Y346618D01*
X784058D01*
X782602Y348074D01*
X748242D01*
X745132Y344964D01*
G01X747500Y393287D02*
X746426D01*
X745500Y392361D01*
Y388771D01*
X747454Y386817D01*
G01X751500Y393287D02*
X750426D01*
X749500Y392361D01*
Y388771D01*
X751409Y386862D01*
X751652D01*
G01X743500Y379937D02*
X739500D01*
G01D02*
Y383500D01*
G01D02*
Y385500D01*
X741015Y387015D01*
X741500Y388187D01*
Y401000D01*
X739811Y402689D01*
Y421508D01*
X738276Y423043D01*
G01X747500Y379937D02*
X749255D01*
X754813Y374379D01*
Y374362D01*
G01X739500Y376787D02*
Y374362D01*
G01X747500Y376787D02*
Y374362D01*
G01X743500Y393287D02*
X743652Y393135D01*
Y391014D01*
X743500Y390862D01*
G01X745000Y400000D02*
X743500Y398500D01*
Y396437D01*
G01X741426Y419893D02*
Y403574D01*
X745000Y400000D01*
G01X747500Y396437D02*
Y402470D01*
X744000Y405970D01*
G01X751500Y396437D02*
Y398201D01*
X750800Y398901D01*
Y405992D01*
G01X744000Y405970D02*
X743022Y406948D01*
Y421447D01*
X741426Y423043D01*
G01X756300Y405840D02*
Y406370D01*
X754800Y407870D01*
Y410326D01*
X747725Y417401D01*
Y419893D01*
G01X762500Y401100D02*
Y401870D01*
X759100Y405270D01*
Y410170D01*
X755736Y413534D01*
X753902D01*
X749342Y418094D01*
Y421426D01*
X747725Y423043D01*
G01X750800Y405992D02*
Y407770D01*
X744575Y413995D01*
Y419893D01*
G01Y423043D02*
Y422051D01*
X746142Y420484D01*
Y415717D01*
X753300Y408559D01*
Y401579D01*
X753700Y401179D01*
G01X761600Y406060D02*
Y410679D01*
X756935Y415344D01*
X755423D01*
X750874Y419893D01*
G01X738276Y426192D02*
X739811Y424657D01*
G01X738276Y429342D02*
X739811Y427807D01*
G01X741426Y426192D02*
X742961Y424657D01*
G01X741426Y429342D02*
X742961Y427807D01*
G01X744575Y426192D02*
X746110Y424657D01*
G01X744575Y429342D02*
X746110Y427807D01*
G01X750874Y432492D02*
X752409Y430957D01*
G01X747725Y426192D02*
X749260Y424657D01*
G01X744575Y432492D02*
X746110Y430957D01*
G01X747725Y432492D02*
X749260Y430957D01*
G01X741426Y432492D02*
X742961Y430957D01*
G01X750874Y429342D02*
X752409Y427807D01*
G01X747725Y429342D02*
X749260Y427807D01*
G01X738276Y432492D02*
X739811Y430957D01*
G01X750874Y445090D02*
X752409Y443555D01*
G01X738276Y438791D02*
X739811Y437256D01*
G01X744575Y438791D02*
X746110Y437256D01*
G01X750874Y435641D02*
X752409Y434106D01*
G01X741426Y438791D02*
X742961Y437256D01*
G01X744575Y441940D02*
X746110Y440405D01*
G01X747725Y435641D02*
X749260Y434106D01*
G01X747725Y438791D02*
X749260Y437256D01*
G01X750874Y441940D02*
X752409Y440405D01*
G01X747725Y441940D02*
X749260Y440405D01*
G01X747725Y448240D02*
X749260Y446705D01*
G01X750874Y438791D02*
X752409Y437256D01*
G01X750874Y448240D02*
X752409Y446705D01*
G01X744575Y448240D02*
X746110Y446705D01*
G01X738276Y435641D02*
X739811Y434106D01*
G01X744575Y445090D02*
X746110Y443555D01*
G01X747725Y445090D02*
X749260Y443555D01*
G01X741426Y435641D02*
X742961Y434106D01*
G01X744575Y435641D02*
X746110Y434106D01*
G01X750874Y454539D02*
X752409Y456074D01*
G01X747725Y451389D02*
X749260Y449854D01*
G01X744575Y457688D02*
X746110Y459223D01*
G01X750874Y460838D02*
X752409Y462373D01*
G01X750874Y457688D02*
X752409Y459223D01*
G01X747725Y457688D02*
X749260Y459223D01*
G01X744575Y454539D02*
X746110Y456074D01*
G01X744575Y451389D02*
X746110Y449854D01*
G01X744575Y460838D02*
X746110Y462373D01*
G01X747725Y460838D02*
X749260Y462373D01*
G01X750874Y451389D02*
X752409Y449854D01*
G01X747725Y454539D02*
X749260Y456074D01*
G01X741426Y473436D02*
X742961Y474971D01*
G01X741426Y467137D02*
X742961Y468672D01*
G01X738276Y476586D02*
X739811Y478121D01*
G01X738276Y473436D02*
X739811Y474971D01*
G01X738276Y470287D02*
X739811Y471822D01*
G01X747725Y470287D02*
X749260Y471822D01*
G01X738276Y467137D02*
X739811Y468672D01*
G01X747725Y467137D02*
X749260Y468672D01*
G01X747725Y473436D02*
X749260Y474971D01*
G01X741426Y470287D02*
X742961Y471822D01*
G01X747725Y476586D02*
X749260Y478121D01*
G01X744575Y473436D02*
X746110Y474971D01*
G01X750874Y467137D02*
X752409Y468672D01*
G01X741426Y476586D02*
X742961Y478121D01*
G01X744575Y467137D02*
X746110Y468672D01*
G01X750874Y476586D02*
X752409Y478121D01*
G01X750874Y470287D02*
X752409Y471822D01*
G01X750874Y463988D02*
X752409Y465523D01*
G01X744575Y463988D02*
X746110Y465523D01*
G01X747725Y463988D02*
X749260Y465523D01*
G01X750874Y473436D02*
X752409Y474971D01*
G01X744575Y476586D02*
X746110Y478121D01*
G01X744575Y470287D02*
X746110Y471822D01*
G01X747725Y479736D02*
X749260Y481271D01*
G01X741426Y482885D02*
X742961Y484420D01*
G01X738276Y479736D02*
X739811Y481271D01*
G01X742144Y504935D02*
Y504736D01*
X742142Y504734D01*
Y500563D01*
X742200Y500505D01*
Y495296D01*
X738276Y491372D01*
Y486035D01*
G01X744575Y482885D02*
X746110Y484420D01*
G01X747725Y482885D02*
X749260Y484420D01*
G01X750874Y486035D02*
X752409Y487570D01*
G01X744500Y500014D02*
Y494938D01*
X739852Y490290D01*
Y484461D01*
X738276Y482885D01*
G01X747725Y486035D02*
X746000Y487760D01*
Y496136D01*
X747080Y497216D01*
Y501133D01*
X745874Y502339D01*
Y505153D01*
X746632Y505911D01*
Y516077D01*
G01X741426Y486035D02*
X742961Y487570D01*
G01X744575Y486035D02*
Y488456D01*
X742961Y490070D01*
G01X744575Y479736D02*
X746110Y481271D01*
G01X741426Y479736D02*
X742961Y481271D01*
G01X752500Y500014D02*
Y495986D01*
X753252Y495234D01*
G01X752500Y507787D02*
X755062Y505225D01*
Y502576D01*
X752500Y500014D01*
G01X741000Y518862D02*
Y516404D01*
X742470Y514934D01*
Y510343D01*
X742144Y510017D01*
Y504935D01*
G01X744500Y507787D02*
Y500014D01*
G01X748500Y507787D02*
Y503014D01*
G01D02*
Y495363D01*
X748381Y495244D01*
G01X752500Y517362D02*
Y516350D01*
X754500Y514350D01*
Y512010D01*
X753427Y510937D01*
X752500D01*
G01X744500D02*
Y513362D01*
G01X740895Y524306D02*
Y518967D01*
X741000Y518862D01*
G01X748500Y524287D02*
X750500Y522287D01*
Y515362D01*
X752500Y513362D01*
G01X744500Y524287D02*
X745773Y523014D01*
Y520723D01*
X746632Y519864D01*
Y516077D01*
G01X748500Y510937D02*
Y513362D01*
G01X741851Y553544D02*
X742989Y552406D01*
Y534009D01*
X740895Y531915D01*
Y527456D01*
G01X740500Y540287D02*
Y537862D01*
G01X748500Y527437D02*
Y529548D01*
X748307Y529741D01*
Y530105D01*
X748143Y530269D01*
G01X744500Y527437D02*
Y529651D01*
X744916Y530067D01*
Y530268D01*
G01X753951Y521801D02*
Y521974D01*
X752500Y523425D01*
Y524287D01*
G01X748500Y540287D02*
Y538362D01*
X748000Y537862D01*
G01X740500Y543437D02*
Y545862D01*
G01X752500Y540287D02*
Y538143D01*
X752965Y537678D01*
G01X748500Y545862D02*
Y543437D01*
G01X750062Y655415D02*
X760549Y665902D01*
X773486D01*
X828462Y720878D01*
X837409Y742478D01*
Y778660D01*
X824824Y791245D01*
X822982D01*
G01X751885Y666724D02*
X753557Y665052D01*
X756578D01*
X763091Y671565D01*
X775115D01*
X826394Y722844D01*
X835169Y744028D01*
Y773716D01*
X824848Y784037D01*
Y785338D01*
X824348Y785838D01*
X822790D01*
G01X746665Y678879D02*
X780673Y712887D01*
X802695D01*
X818472Y728664D01*
X825628Y745939D01*
Y760526D01*
X822625Y763529D01*
G01X738486Y679139D02*
X775444Y716097D01*
X801364D01*
X815439Y730172D01*
X821828Y745597D01*
Y756545D01*
X822218Y756935D01*
Y756979D01*
G01X750168Y675833D02*
Y679179D01*
X782456Y711467D01*
X803284D01*
X819676Y727859D01*
X827048Y745655D01*
Y762897D01*
X825061Y764884D01*
G01X747160Y1587773D02*
X744405Y1585018D01*
X742189D01*
G01X751770Y1631358D02*
X757770D01*
G01X751770D02*
Y1634083D01*
X753770Y1636083D01*
G01X740723Y1626945D02*
X743664D01*
G01X740723Y1630095D02*
Y1633619D01*
G01X767368Y1662487D02*
X765856D01*
X763884Y1660515D01*
Y1649035D01*
X762831Y1647982D01*
X742792D01*
G01X744315Y1673134D02*
X742474Y1671293D01*
Y1670111D01*
X740205Y1667842D01*
Y1666358D01*
G01X752187Y1674919D02*
X756321D01*
X761297Y1679895D01*
G01X752187Y1674919D02*
X752039Y1674771D01*
X748254D01*
G01X741326Y1683737D02*
Y1680132D01*
G01X746766Y1696036D02*
X746538D01*
X743116Y1692614D01*
Y1685182D01*
X741671Y1683737D01*
X741326D01*
G01X738526Y1674392D02*
X739919Y1675785D01*
X740129D01*
X741326Y1676982D01*
G01X745537Y1680217D02*
X747563D01*
X748413Y1679367D01*
G01X745537Y1677067D02*
Y1674356D01*
X744315Y1673134D01*
G01X745382Y1687195D02*
Y1683663D01*
G01Y1690345D02*
Y1691156D01*
X747289Y1693063D01*
G01X760237Y1693369D02*
Y1691604D01*
X759737Y1691104D01*
X755555D01*
X754730Y1690279D01*
Y1688909D01*
X754390Y1688569D01*
X752187D01*
G01Y1691058D02*
Y1692949D01*
X752607Y1693369D01*
X757087D01*
G01X754783Y96553D02*
Y90690D01*
X756125Y89348D01*
X757043D01*
G01X760193D02*
Y93273D01*
G01X752909Y98005D02*
X753878D01*
X754783Y97100D01*
Y96553D01*
G01X760193Y93273D02*
X758052D01*
X757188Y92409D01*
Y91829D01*
G01X752909Y99974D02*
X753974D01*
X757000Y103000D01*
Y111999D01*
X757576Y112575D01*
G01X760193Y103803D02*
Y106500D01*
G01X757576Y112575D02*
X760500D01*
G01Y109425D02*
Y106807D01*
X760193Y106500D01*
G01X759289Y143438D02*
X753601D01*
G01X753501Y151312D02*
X763029D01*
G01X777878Y153728D02*
Y153727D01*
X775463Y151312D01*
X763029D01*
G01X768725Y172636D02*
X766254D01*
X765788Y172170D01*
Y163529D01*
X764343Y162084D01*
G01X761245Y167518D02*
X763091D01*
X763389Y167816D01*
Y169450D01*
X762762Y170077D01*
X761245D01*
G01Y167518D02*
X758945D01*
X755901Y170562D01*
G01X761000Y212425D02*
Y199000D01*
G01D02*
X758500Y196500D01*
X753547D01*
X753500Y196547D01*
G01Y202453D02*
Y208000D01*
G01D02*
Y212701D01*
X753559Y212760D01*
G01X759841Y269322D02*
X759842Y269321D01*
Y265323D01*
X759841Y265322D01*
G01D02*
X762767D01*
X764767Y267322D01*
G01X769829Y271354D02*
X768799D01*
X764767Y267322D01*
G01X759842Y276322D02*
X763389Y272775D01*
X763958D01*
G01D02*
X766650D01*
X767197Y273322D01*
X769829D01*
G01X758510Y298620D02*
X758680Y298790D01*
X763179D01*
X763668Y299279D01*
G01X777468D02*
X766818D01*
G01X759000Y363787D02*
X763265Y368052D01*
X764983D01*
G01X763500Y376787D02*
X764833D01*
X766304Y375316D01*
Y372862D01*
G01X759000Y366937D02*
X758908Y366845D01*
X757197D01*
X755135Y368907D01*
G01X778925Y367500D02*
X768500D01*
X762500Y361500D01*
X758344D01*
X756844Y363000D01*
X754905D01*
X752926Y361021D01*
G01X754800Y379919D02*
X757500Y382619D01*
Y392863D01*
X757924Y393287D01*
X759500D01*
G01Y379937D02*
X759482Y379919D01*
X754800D01*
G01X759500Y386862D02*
Y379937D01*
G01X763500D02*
Y386862D01*
G01X759500Y390791D02*
X759930D01*
X762408Y393269D01*
X763482D01*
X763500Y393287D01*
G01X755500D02*
Y390862D01*
G01X759500Y396437D02*
X756300Y399637D01*
Y405840D01*
G01X763500Y396437D02*
Y397501D01*
X762500Y398501D01*
Y401100D01*
G01X753700Y401179D02*
X754000Y400879D01*
Y397937D01*
X755500Y396437D01*
G01X767500D02*
X764900Y399037D01*
Y402412D01*
X761600Y405712D01*
Y406060D01*
G01X766300Y404280D02*
X769202D01*
X771512Y401970D01*
Y398060D01*
X771500Y398048D01*
Y396437D01*
G01X766300Y404280D02*
X763822Y406758D01*
Y416228D01*
X764357Y416763D01*
X765621D01*
X766900Y418042D01*
Y418986D01*
X764372Y421514D01*
X761852D01*
X760323Y423043D01*
G01X775500Y396437D02*
X773578Y398359D01*
Y402923D01*
X766740Y409761D01*
Y413647D01*
X766739Y413650D01*
X765975Y414414D01*
G01D02*
Y415160D01*
X767770Y416955D01*
Y419926D01*
X764653Y423043D01*
X763473D01*
G01X754024Y419893D02*
X755559Y418358D01*
G01X757174Y419893D02*
X758709Y418358D01*
G01X761858D02*
X760323Y419893D01*
G01X754024Y429342D02*
X755559Y427807D01*
G01X754024Y432492D02*
X755559Y430957D01*
G01X757174Y429342D02*
X758709Y427807D01*
G01X763473Y435641D02*
X764470D01*
X767680Y432431D01*
Y427156D01*
X770530Y424306D01*
Y423460D01*
G01X757174Y432492D02*
X758709Y430957D01*
G01X763473Y426192D02*
X765008Y424657D01*
G01D02*
X770216Y419449D01*
Y414363D01*
X771605Y412974D01*
X777021D01*
X777640Y413593D01*
Y413857D01*
X779127Y415344D01*
X779227D01*
G01X754024Y426192D02*
X755559Y424657D01*
G01X802175Y418362D02*
X801132Y417319D01*
X773842D01*
X766568Y424593D01*
Y431818D01*
X764322Y434064D01*
X761900D01*
X760323Y435641D01*
G01X757174Y426192D02*
X758709Y424657D01*
G01X757174Y423043D02*
X758709Y421508D01*
G01X754024Y423043D02*
X755559Y421508D01*
G01X760323Y426192D02*
X761858Y424657D01*
G01X763473Y432492D02*
X765008Y430957D01*
G01X760323Y432492D02*
X761858Y430957D01*
G01X760323Y429342D02*
X761858Y427807D01*
G01X763473Y429342D02*
X765008Y427807D01*
G01X763473Y448240D02*
X765008Y446705D01*
G01X757174Y448240D02*
X758709Y446705D01*
G01X754024Y445090D02*
X755559Y443555D01*
G01X754024Y448240D02*
X755559Y446705D01*
G01X769648Y430511D02*
X769575D01*
X769005Y431081D01*
Y432338D01*
X764109Y437234D01*
X761880D01*
X760323Y438791D01*
G01Y441940D02*
X761879Y440384D01*
X766140D01*
X768301Y438223D01*
G01X760323Y445090D02*
X761839Y443574D01*
X769711D01*
X770775Y442510D01*
X770918D01*
G01X772610Y434690D02*
X772423Y434877D01*
X768285D01*
X764371Y438791D01*
X763473D01*
G01X775077Y439344D02*
X773265D01*
X772371Y440238D01*
X769438D01*
X767736Y441940D01*
X763473D01*
G01X770042Y446829D02*
X769703D01*
X767964Y445090D01*
X763473D01*
G01X754024Y435641D02*
X755559Y434106D01*
G01X757174Y441940D02*
X758709Y440405D01*
G01X754024Y441940D02*
X755559Y440405D01*
G01X757174Y435641D02*
X758709Y434106D01*
G01X757174Y445090D02*
X758709Y443555D01*
G01X760323Y448240D02*
X761858Y446705D01*
G01X763473Y457688D02*
X770565D01*
X772221Y459344D01*
X775077D01*
G01X772677Y451374D02*
X771941D01*
X770830Y450263D01*
X770789D01*
X770330Y449804D01*
X761908D01*
X760323Y451389D01*
G01Y457688D02*
X761929Y459294D01*
X767059D01*
X771109Y463344D01*
X775077D01*
G01X754024Y457688D02*
X755559Y459223D01*
G01X763473Y454539D02*
X765008Y456074D01*
G01X775077Y455344D02*
X769852D01*
X767522Y453014D01*
X761848D01*
X760323Y454539D01*
G01X786624Y465585D02*
X785704D01*
X781912Y469377D01*
X774195D01*
X765656Y460838D01*
X763473D01*
G01X783895Y470961D02*
X780460D01*
X780108Y470609D01*
X773417D01*
X765202Y462394D01*
X761879D01*
X760323Y460838D01*
G01X754024D02*
X755559Y462373D01*
G01X757174Y457688D02*
X758709Y459223D01*
G01X757174Y460838D02*
X758709Y462373D01*
G01X757174Y454539D02*
X758709Y456074D01*
G01X763473Y451389D02*
X769038D01*
X771030Y453381D01*
X800185D01*
G01X757174Y451389D02*
X758709Y449854D01*
G01X754024Y476586D02*
X755559Y478121D01*
G01X754024Y470287D02*
X755559Y471822D01*
G01X757174Y470287D02*
X758709Y471822D01*
G01X760323Y476586D02*
X761858Y478121D01*
G01X760323Y473436D02*
X761858Y474971D01*
G01X760323Y470287D02*
X761858Y471822D01*
G01X757174Y473436D02*
X758709Y474971D01*
G01X763473Y470287D02*
X765008Y471822D01*
G01X763473Y473436D02*
X765008Y474971D01*
G01X763473Y463988D02*
X765008Y465523D01*
G01X757174Y476586D02*
X758709Y478121D01*
G01X760323Y467137D02*
X761858Y468672D01*
G01X757174Y463988D02*
X758709Y465523D01*
G01X777465Y483344D02*
X770231D01*
X763473Y476586D01*
G01X760323Y463988D02*
X761858Y465523D01*
G01X763473Y467137D02*
X765008Y468672D01*
G01X754024Y463988D02*
X755559Y465523D01*
G01X754024Y473436D02*
X755559Y474971D01*
G01X757500Y499980D02*
Y494755D01*
X754024Y491279D01*
Y486035D01*
G01X771039Y511292D02*
X769982Y510235D01*
Y498714D01*
X767044Y495776D01*
Y491793D01*
X765915Y490664D01*
X764177D01*
X760323Y486810D01*
Y486035D01*
G01X766566Y532172D02*
X768000Y530738D01*
Y498741D01*
X765008Y495749D01*
Y493281D01*
X763155Y491428D01*
X759746D01*
X758760Y490442D01*
Y484471D01*
X757174Y482885D01*
G01X754024Y479736D02*
X755559Y481271D01*
G01X761500Y503014D02*
Y495844D01*
X757174Y491518D01*
Y486035D01*
G01X754024Y482885D02*
X755559Y484420D01*
G01X763473Y479736D02*
X765008Y481271D01*
G01X760323Y479736D02*
X761858Y481271D01*
G01X763473Y482885D02*
X769856Y489268D01*
Y495333D01*
X772800Y498277D01*
Y507403D01*
X774665Y509268D01*
X776053D01*
X779400Y512615D01*
Y532880D01*
X778980Y533300D01*
X776400D01*
G01X757174Y479736D02*
X758709Y481271D01*
G01X760323Y482885D02*
X761902Y484464D01*
Y486790D01*
X764278Y489166D01*
X766912D01*
X768524Y490778D01*
Y495246D01*
X771434Y498156D01*
Y508749D01*
X772916Y510231D01*
Y518246D01*
X768880Y522282D01*
Y529722D01*
X769565Y530407D01*
Y534405D01*
X770800Y535640D01*
G01X756500Y507787D02*
X757500Y506787D01*
Y499980D01*
G01X762800Y493654D02*
X763652Y494506D01*
Y496912D01*
X765690Y498950D01*
Y499980D01*
G01D02*
Y506597D01*
X764500Y507787D01*
G01X760500D02*
X761500Y506787D01*
Y503014D01*
G01X756500Y510937D02*
Y513340D01*
G01X765809Y563410D02*
X765526Y563127D01*
X765514D01*
X763711Y561324D01*
Y554332D01*
X762502Y553123D01*
Y518503D01*
X761990Y517991D01*
Y513364D01*
X764417Y510937D01*
X764500D01*
G01X756500Y524287D02*
Y522639D01*
X756100Y522239D01*
Y517750D01*
X756800Y517050D01*
G01X760500Y524287D02*
Y521189D01*
G01X757860Y537859D02*
Y533725D01*
X758690Y532895D01*
Y522752D01*
X757900Y521962D01*
Y518850D01*
X760500Y516250D01*
Y510937D01*
G01X764600Y517022D02*
X766500Y518922D01*
Y522861D01*
X765074Y524287D01*
X764500D01*
G01X756500Y527437D02*
Y529574D01*
X756186Y529888D01*
G01X765000Y540287D02*
Y537347D01*
X766566Y535781D01*
Y532172D01*
G01X764500Y527437D02*
Y529862D01*
G01X760500Y527437D02*
Y529845D01*
G01X756500Y540287D02*
X757860Y538927D01*
Y537859D01*
G01X752500Y527437D02*
Y529862D01*
G01X760500Y540287D02*
X760660Y540127D01*
Y537862D01*
G01X765000Y543437D02*
X766410Y544847D01*
Y560030D01*
X768340Y561960D01*
Y563678D01*
G01X752500Y543437D02*
Y545862D01*
G01X759568Y545867D02*
X760500Y544935D01*
Y543437D01*
G01X753309Y655515D02*
X762537Y664743D01*
X774186D01*
X830208Y720765D01*
X838289Y740274D01*
Y779516D01*
X822794Y795011D01*
G01X757745Y655353D02*
X765661Y663269D01*
X774806D01*
X832118Y720581D01*
X839709Y738907D01*
Y787604D01*
X824372Y802941D01*
X822494D01*
G01X755765Y666904D02*
X761754Y672893D01*
X775126D01*
X825699Y723466D01*
X834289Y744204D01*
Y772888D01*
X823915Y783262D01*
X822864D01*
G01X762656Y667835D02*
X773692D01*
X827178Y721321D01*
X836289Y743318D01*
Y777634D01*
X825564Y788359D01*
X822772D01*
G01X753231Y678679D02*
X785139Y710587D01*
X803649D01*
X820425Y727363D01*
X827928Y745476D01*
Y764577D01*
X824994Y767511D01*
X822794D01*
G01X756936Y676319D02*
Y678988D01*
X787655Y709707D01*
X804014D01*
X821173Y726866D01*
X828808Y745298D01*
Y766602D01*
X825390Y770020D01*
G01X760529Y677715D02*
X791101Y708287D01*
X804603D01*
X822377Y726061D01*
X830228Y745015D01*
Y767865D01*
X825582Y772511D01*
X822794D01*
G01X764401Y676968D02*
X794300Y706867D01*
X805192D01*
X823581Y725256D01*
X831648Y744731D01*
Y768455D01*
X825092Y775011D01*
X822794D01*
G01X752599Y766871D02*
X757149D01*
G01X766158D02*
X761608D01*
G01X766158Y763525D02*
X761608D01*
G01X752599Y770218D02*
X757149D01*
G01X762913Y1498663D02*
X758163D01*
G01X762913Y1494726D02*
X758163D01*
G01X762913Y1502600D02*
X758163D01*
G01X762913Y1506538D02*
X758163D01*
G01X757826Y1514412D02*
X762913D01*
G01X758056Y1518349D02*
X762913D01*
G01Y1522286D02*
X758163D01*
G01X755185Y1584023D02*
X757610D01*
G01X761770Y1628208D02*
X759723Y1626161D01*
G01X753770Y1636083D02*
Y1641299D01*
X754030Y1641559D01*
G01X757770Y1636083D02*
Y1641559D01*
G01X761770Y1631358D02*
Y1633562D01*
X760623Y1634709D01*
X759144D01*
X757770Y1636083D01*
G01X761510Y1656483D02*
Y1651007D01*
G01X754030Y1666158D02*
Y1669256D01*
G01Y1663008D02*
X758030D01*
G01D02*
X762030D01*
G01D02*
Y1657003D01*
X761510Y1656483D01*
G01X767381Y1670166D02*
X767368Y1670153D01*
Y1665637D01*
G01X768733Y1694485D02*
X770325Y1692893D01*
Y1673110D01*
X767381Y1670166D01*
G01X768463Y1687769D02*
Y1690965D01*
X766059Y1693369D01*
X760237D01*
G01X765037Y1687769D02*
X768463D01*
G01X777995Y163254D02*
Y158157D01*
X777864Y158026D01*
G01D02*
Y153742D01*
X777878Y153728D01*
G01X774845Y163254D02*
Y169120D01*
X773901Y170064D01*
G01X774714Y158026D02*
X771427D01*
G01X768725Y170077D02*
X773888D01*
X773901Y170064D01*
G01X777703Y271354D02*
X779335D01*
X782967Y267722D01*
X783267D01*
G01X777703Y275290D02*
X778655D01*
X783267Y279902D01*
Y282922D01*
G01X777703Y273322D02*
X779268D01*
X781268Y275322D01*
X783267D01*
G01X777468Y296315D02*
Y299279D01*
G01X776102Y303410D02*
X779121D01*
G01D02*
X786052D01*
G01X776017Y308755D02*
X779121D01*
G01D02*
X785967D01*
G01X778925Y364000D02*
X775075D01*
G01X782075Y367500D02*
Y371000D01*
G01Y364000D02*
Y367500D01*
G01D02*
X784500D01*
G01X823778Y376378D02*
X819046D01*
X813259Y370591D01*
X788907D01*
X781456Y378042D01*
G01X787905Y381192D02*
X781456D01*
G01D02*
X779215D01*
X772513Y374490D01*
G01X767500Y393287D02*
Y390862D01*
G01X771500Y393287D02*
X771512Y393275D01*
Y390862D01*
G01X775500Y393287D02*
X775388Y393175D01*
Y390862D01*
G01X784498Y396353D02*
X780351Y400500D01*
X777198D01*
X775641Y402057D01*
Y406746D01*
X773233Y409154D01*
G01X770159Y410257D02*
X770866Y410964D01*
X777051D01*
X779266Y408749D01*
Y407745D01*
X782110Y404901D01*
X785125D01*
X786571Y403455D01*
G01X775077Y427344D02*
X774659D01*
X771833Y430170D01*
X769989D01*
X769648Y430511D01*
G01X775077Y431344D02*
Y432333D01*
X772720Y434690D01*
X772610D01*
G01X775094Y419464D02*
X775168Y419538D01*
Y423253D01*
X775077Y423344D01*
G01X770530Y423460D02*
X771376D01*
X771492Y423344D01*
X775077D01*
G01X778227Y427344D02*
X780877D01*
G01X778227Y431344D02*
Y429945D01*
X779018Y429154D01*
X782067D01*
X783877Y427344D01*
G01X778227Y423344D02*
X780877D01*
G01X768301Y438223D02*
X769356Y437168D01*
X773253D01*
X775077Y435344D01*
G01X770918Y442510D02*
X774243D01*
X775077Y443344D01*
G01Y439344D02*
Y440183D01*
X775994Y441100D01*
X783736D01*
G01X775077Y447344D02*
X772353D01*
X771838Y446829D01*
X770042D01*
G01X778227Y435344D02*
X778447Y435564D01*
X780577D01*
G01X778227Y443344D02*
X780877D01*
G01X778227Y439344D02*
X779977D01*
X783877Y435444D01*
G01X778227Y447344D02*
X780877D01*
G01X778227Y459344D02*
X780797D01*
X780977Y459524D01*
G01X783241Y461515D02*
X775800D01*
X775077Y460792D01*
Y459344D01*
G01X778227Y455344D02*
X780877D01*
G01X775077Y451344D02*
X773731D01*
X773543Y451532D01*
X772835D01*
X772677Y451374D01*
G01X775077Y463344D02*
Y464571D01*
X777385Y466879D01*
G01X778227Y451344D02*
Y449960D01*
X778843Y449344D01*
X792045D01*
X792727Y448662D01*
Y447344D01*
G01X778227Y463344D02*
X780001Y465118D01*
X783309D01*
X786825Y461602D01*
Y459518D01*
G01X783796Y456205D02*
X782904Y457097D01*
X775577D01*
X775077Y456597D01*
Y455344D01*
G01Y472344D02*
X771994D01*
X770590Y470940D01*
G01X778227Y472344D02*
X779037Y473154D01*
X789157D01*
X789577Y472734D01*
Y471344D01*
G01X775077Y476344D02*
X773427D01*
X772427Y475344D01*
G01X778227Y476344D02*
X779037Y477154D01*
X785067D01*
X786877Y475344D01*
G01X778227Y487344D02*
X797285D01*
X797405Y487464D01*
G01X775077Y491344D02*
X772687D01*
X772390Y491047D01*
G01X775077Y487344D02*
X772427D01*
G01X790087Y483458D02*
X788057Y485488D01*
X780149D01*
X778005Y483344D01*
X777465D01*
G01X778227Y495344D02*
X779351D01*
X781351Y497344D01*
X785085D01*
X786979Y499238D01*
X787279D01*
G01X866727Y650739D02*
X863307D01*
X858051Y645483D01*
Y642685D01*
X812917Y597551D01*
Y589827D01*
X797000Y573910D01*
Y528001D01*
X776186Y507187D01*
X774738D01*
X774318Y506767D01*
Y503286D01*
X775100Y502504D01*
G01X778227Y499344D02*
X779937Y501054D01*
X788296D01*
X790337Y499013D01*
X800759D01*
X802250Y500504D01*
G01X775077Y495344D02*
X772427D01*
G01X775077Y499344D02*
X777166Y501433D01*
Y504477D01*
G01X773000Y540287D02*
X773900Y539387D01*
Y534500D01*
X772100Y532700D01*
G01X776400Y533300D02*
X774400Y531300D01*
Y526570D01*
X772117Y524287D01*
X772000D01*
G01X768700Y540425D02*
X770800Y538325D01*
Y535640D01*
G01X772000Y545862D02*
Y544437D01*
X773000Y543437D01*
G01X771553Y677963D02*
X777533D01*
X824328Y724758D01*
X832528Y744554D01*
Y768821D01*
X823838Y777511D01*
X822794D01*
G01X768565Y677573D02*
X770063Y676075D01*
X776890D01*
X825075Y724260D01*
X833408Y744377D01*
Y770157D01*
X823554Y780011D01*
X823206D01*
X822883Y780334D01*
G01X788191Y267822D02*
X783367D01*
X783267Y267722D01*
G01X788191Y281822D02*
Y281823D01*
X787092Y282922D01*
X783267D01*
G01X788191Y274822D02*
X783767D01*
X783267Y275322D01*
G01X791341Y274822D02*
X797022D01*
X801341Y279141D01*
G01X786052Y303410D02*
Y295068D01*
X788990Y292130D01*
X797367D01*
X806237Y301000D01*
X854173D01*
X855481Y299692D01*
G01X789202Y303410D02*
X791043Y301569D01*
X794058D01*
G01X789117Y308755D02*
X789388Y309026D01*
X793897D01*
G01X860071Y304850D02*
Y311188D01*
X856676Y314583D01*
X788653D01*
X785967Y311897D01*
Y308755D01*
G01X792302Y357537D02*
X794178Y359413D01*
X813130D01*
X831373Y377656D01*
Y383511D01*
X836937Y389075D01*
X839000D01*
G01X789276Y366000D02*
X786000D01*
X784500Y367500D01*
G01X852000Y408000D02*
X840500Y396500D01*
X824500D01*
X818500Y390500D01*
X796526D01*
X792575Y394451D01*
Y399000D01*
G01X789425D02*
X786778Y396353D01*
X784498D01*
G01X792575Y403000D02*
X796075Y399500D01*
X801776D01*
G01X789425Y403000D02*
X787026D01*
X786571Y403455D01*
G01X789527Y415344D02*
X782760D01*
X782700Y415284D01*
G01X792677Y415344D02*
X796283D01*
G01X800776Y409500D02*
X797401D01*
X795401Y407500D01*
X792575D01*
G01D02*
Y411500D01*
G01X789425D02*
X785000D01*
X783500Y410000D01*
Y409584D01*
X783256Y409340D01*
G01X789527Y423344D02*
X787317D01*
X786427Y422454D01*
X783770D01*
G01X789527Y419344D02*
X786073D01*
X785923Y419194D01*
G01X789527Y427344D02*
X786877D01*
G01X792677Y423344D02*
X796283D01*
G01X792677Y431344D02*
X796283D01*
G01D02*
X796322Y431383D01*
X806272D01*
X806311Y431344D01*
G01X792677Y419344D02*
X796283D01*
G01X792677Y427344D02*
X796283D01*
G01X789527Y431344D02*
X789337Y431534D01*
X783821D01*
G01X792677Y443344D02*
X797252D01*
G01X789527D02*
X786877D01*
G01X783736Y441100D02*
X789157D01*
X789577Y440680D01*
Y439344D01*
G01X792727Y435344D02*
X796333D01*
G01X792727Y447344D02*
X797197D01*
G01X789577Y435344D02*
X787131D01*
X786999Y435476D01*
G01X792727Y451344D02*
X797252D01*
G01X792727Y463344D02*
X797322D01*
G01X789577Y459344D02*
X786999D01*
X786825Y459518D01*
G01X789577Y451344D02*
X786887D01*
G01X789577Y463344D02*
X788865D01*
X786624Y465585D01*
G01X789577Y455344D02*
X786935D01*
X786755Y455524D01*
G01X792727Y455344D02*
X797252D01*
G01X786877Y471344D02*
X789577D01*
G01X789746Y467646D02*
X787936Y469456D01*
X785400D01*
X783895Y470961D01*
G01X792896Y467646D02*
X794404Y469154D01*
X797894D01*
X799370Y470630D01*
Y473062D01*
X799920Y473612D01*
X814049D01*
X819308Y478871D01*
X827206D01*
X830046Y476031D01*
G01X793237Y483458D02*
X795433Y485654D01*
X800442D01*
X802324Y483772D01*
X810910D01*
X812000Y484862D01*
X813000D01*
G01X793454Y479511D02*
X795105Y481162D01*
X800622D01*
X801710Y482250D01*
X824826D01*
X826472Y483896D01*
G01X790304Y479511D02*
X787698D01*
X786440Y480769D01*
G01X789925Y507000D02*
X786638D01*
X786102Y507536D01*
G01X787446Y495344D02*
X789649Y497547D01*
X812372D01*
X813187Y498362D01*
G01X806425Y504000D02*
X804770Y502345D01*
X801566D01*
X801426Y502205D01*
X795331D01*
X795164Y502372D01*
X791049D01*
X790503Y501826D01*
G01X793075Y507000D02*
X795212Y509137D01*
X796786D01*
X799450Y511801D01*
G01X865466Y795581D02*
X864494D01*
X856432Y787519D01*
Y733512D01*
X819934Y645404D01*
X806315Y631785D01*
X787591D01*
G01X782300Y766871D02*
X786850D01*
G01X795858D02*
X791308D01*
G01X795858Y763525D02*
X791308D01*
G01X786850Y770218D02*
X782300D01*
G01X796276Y1345886D02*
X798069D01*
X804171Y1351988D01*
X804696D01*
G01X794386Y1585316D02*
X794980D01*
X799775Y1590111D01*
Y1591498D01*
G01X794386Y1587284D02*
X794935D01*
X797052Y1589401D01*
Y1595996D01*
X799775Y1598719D01*
G01X810811Y135132D02*
X811593Y135914D01*
X818002D01*
G01X810641Y128262D02*
X816324Y133945D01*
X818002D01*
G01X810481Y141762D02*
Y140582D01*
X813181Y137882D01*
X818002D01*
G01X804330Y281380D02*
X804787D01*
X810559Y287152D01*
X817120D01*
X820683Y283589D01*
X841331D01*
X843504Y285762D01*
Y287602D01*
G01X808617Y330102D02*
X822121D01*
X838854Y346835D01*
X843367D01*
X847453Y350921D01*
X871136D01*
X894089Y373874D01*
Y462116D01*
X890566Y465639D01*
Y468426D01*
X900850Y478710D01*
Y552663D01*
X898327Y555186D01*
Y581769D01*
X889737Y590359D01*
Y625538D01*
X918354Y654155D01*
Y727038D01*
X916993Y728399D01*
Y737755D01*
X910369Y753747D01*
Y806173D01*
X900301Y816241D01*
Y828248D01*
G01X806117Y330102D02*
Y331134D01*
X806895Y331912D01*
X822035D01*
X838298Y348175D01*
X842811D01*
X846897Y352261D01*
X870580D01*
X892749Y374430D01*
Y461560D01*
X886430Y467879D01*
Y470410D01*
X896523Y480503D01*
Y483745D01*
X898880Y486102D01*
Y551994D01*
X896987Y553887D01*
Y581213D01*
X888397Y589803D01*
Y626094D01*
X916986Y654683D01*
Y726400D01*
X915653Y727733D01*
Y737485D01*
X909029Y753477D01*
Y804903D01*
X898491Y815441D01*
Y829471D01*
X900241Y831221D01*
X900301D01*
G01X923000Y895500D02*
X927000Y891500D01*
Y875424D01*
X889975Y838399D01*
Y810711D01*
X902725Y797961D01*
Y646714D01*
X883117Y627106D01*
Y586503D01*
X892655Y576965D01*
Y552819D01*
X893059Y551843D01*
Y486251D01*
X881009Y474201D01*
Y467532D01*
X888454Y460087D01*
Y377097D01*
X868617Y357260D01*
X841013D01*
X822271Y338518D01*
X815142D01*
X812070Y341590D01*
G01X805491Y376753D02*
Y373158D01*
G01X808641Y381020D02*
Y376753D01*
G01Y381020D02*
X818157D01*
G01X797551Y377452D02*
X801856D01*
X802555Y376753D01*
X805491D01*
G01X808575Y392500D02*
X812425D01*
G01X801575D02*
X805425D01*
G01X801776Y399500D02*
X802976D01*
X805425Y397051D01*
Y395502D01*
G01Y392500D02*
Y395502D01*
G01X806500Y422687D02*
X802175Y418362D01*
G01X816747Y412367D02*
X806867D01*
X804000Y409500D01*
X800776D01*
G01X809610Y427344D02*
X812968D01*
X813252Y427060D01*
G01X806500Y422687D02*
Y427304D01*
X806460Y427344D01*
G01X809461Y431344D02*
X811451Y433334D01*
X827152D01*
X833233Y427253D01*
X843826D01*
X845986Y429413D01*
G01X802459Y443218D02*
Y440892D01*
X803723Y439628D01*
X805334D01*
G01X809584Y435628D02*
X812924D01*
X813208Y435344D01*
G01X808484Y439628D02*
X810530D01*
X813114Y442212D01*
Y443344D01*
G01X806434Y435628D02*
X802526D01*
X802270Y435372D01*
G01X809289Y449802D02*
X812895D01*
G01X809508Y459344D02*
X813114D01*
G01X806227Y463578D02*
X805967Y463318D01*
X801552D01*
G01X806139Y449802D02*
X802533D01*
G01X806358Y459344D02*
X802752D01*
G01X800185Y453381D02*
X800950Y452616D01*
X830052D01*
X832224Y450444D01*
Y450328D01*
G01X809508Y455344D02*
X813114D01*
G01X809508Y471344D02*
X812983D01*
G01X809621Y476159D02*
X812983D01*
G01X809377Y463578D02*
X812983D01*
G01X806358Y471344D02*
X801874D01*
G01X806471Y476159D02*
X797463D01*
G01X809508Y487344D02*
X813143D01*
X817393Y491594D01*
G01X817996Y496219D02*
X813121Y491344D01*
X809577D01*
G01X809621Y480159D02*
X812983D01*
G01X806358Y487344D02*
X802752D01*
G01X806427Y491344D02*
X801753D01*
G01X806471Y480159D02*
X802752D01*
G01X806425Y512000D02*
Y508000D01*
G01D02*
Y504000D01*
G01X806544Y495344D02*
X801762D01*
G01X806425Y516000D02*
Y526575D01*
X800500Y532500D01*
Y540500D01*
G01X809575Y512000D02*
Y516000D01*
G01D02*
Y523500D01*
X810075Y524000D01*
X811189D01*
G01X811575Y534500D02*
X815941D01*
X817441Y533000D01*
G01X820000Y520760D02*
Y523500D01*
X819500Y524000D01*
X811189D01*
G01X809216Y551473D02*
Y561261D01*
X809817Y561862D01*
G01X811283Y541448D02*
Y549406D01*
X809216Y551473D01*
G01X821993Y539872D02*
X817027D01*
X815451Y541448D01*
X811283D01*
G01X814954Y565087D02*
X809892D01*
X809817Y565012D01*
G01X868539Y790882D02*
X867537Y789880D01*
Y781312D01*
X864112Y777887D01*
Y711491D01*
X840033Y653365D01*
X818943Y632275D01*
Y628527D01*
X810763Y620347D01*
X805199D01*
G01X865466Y793081D02*
X864240D01*
X857852Y786693D01*
Y733227D01*
X821111Y644534D01*
X812606Y636029D01*
Y634532D01*
X804863Y626789D01*
G01X865466Y785581D02*
X864156D01*
X861572Y782997D01*
Y713290D01*
X837334Y654780D01*
X814232Y631678D01*
X812985D01*
X805150Y623843D01*
G01X812000Y766871D02*
X807879D01*
X807451Y767299D01*
G01X812000Y770218D02*
X807867D01*
X807127Y770958D01*
G01X804696Y1351988D02*
Y1351833D01*
X806351Y1350178D01*
X811481D01*
X812621Y1351318D01*
Y1354638D01*
X811771Y1355488D01*
G01X799775Y1591498D02*
Y1594819D01*
X803589Y1598633D01*
X804575D01*
G01X827114Y120773D02*
Y121115D01*
X822531Y125698D01*
G01X822530Y131386D02*
Y125699D01*
X822531Y125698D01*
G01X823114Y120773D02*
X819114D01*
G01X820561Y131386D02*
Y127219D01*
X814115Y120773D01*
G01X819114D02*
X814115D01*
G01X824498Y131386D02*
Y129815D01*
X828615Y125698D01*
G01X826467Y131386D02*
Y130710D01*
X827436Y129741D01*
X833072D01*
X833615Y129198D01*
G01X828145Y176362D02*
X822635Y170852D01*
Y165468D01*
G01X816232Y341584D02*
X817958Y339858D01*
X821715D01*
X840457Y358600D01*
X868061D01*
X887114Y377653D01*
Y459531D01*
X879669Y466976D01*
Y474757D01*
X891648Y486736D01*
Y551747D01*
X891315Y552080D01*
Y576409D01*
X881777Y585947D01*
Y627662D01*
X901385Y647270D01*
Y797366D01*
X888635Y810116D01*
Y839008D01*
X925000Y875373D01*
Y890500D01*
X920000Y895500D01*
G01X841809Y423219D02*
Y400809D01*
X839000Y398000D01*
X816501D01*
X812425Y393924D01*
Y392500D01*
G01X823075Y409500D02*
X826925D01*
G01D02*
Y410425D01*
X828500Y412000D01*
X836000D01*
X838500Y409500D01*
G01X820844Y415344D02*
X817497D01*
G01X819925Y409500D02*
X817058Y412367D01*
X816747D01*
G01X823994Y415344D02*
X827341D01*
G01X827108Y405347D02*
X824653D01*
G01X823994Y427344D02*
X828737D01*
X830499Y425582D01*
X846746D01*
X855722Y416606D01*
G01X820844Y427344D02*
X817781D01*
X817497Y427060D01*
G01X823994Y431344D02*
X826474D01*
G01X823994Y419344D02*
X827341D01*
G01X820844Y431344D02*
X817781D01*
X817497Y431060D01*
G01X820844Y419344D02*
X817497D01*
G01X820836Y423099D02*
Y419352D01*
X820844Y419344D01*
G01X823994Y435628D02*
X826190D01*
X826474Y435344D01*
G01X824121Y439279D02*
X829106D01*
G01X820844Y443552D02*
X816117D01*
G01X823994D02*
X828714D01*
G01X820844Y435628D02*
X816523D01*
X816239Y435344D01*
G01X820971Y439279D02*
X816236D01*
G01X823994Y455344D02*
X828751D01*
G01X820844D02*
X816109D01*
G01X823994Y449802D02*
X828979D01*
G01X823994Y459344D02*
X828751D01*
G01X820844Y449802D02*
X816109D01*
G01X820844Y459344D02*
X820024Y458524D01*
X816170D01*
G01X823933Y471344D02*
X828751D01*
G01X823933Y467568D02*
X828751D01*
G01X823933Y463578D02*
X828751D01*
G01X820783Y471344D02*
X816109D01*
G01X820783Y467568D02*
X816409D01*
G01X820783Y463578D02*
X816000D01*
G01X821588Y489055D02*
X827000D01*
G01X852000Y489075D02*
X847956Y493119D01*
Y495531D01*
X846909Y496578D01*
X839431D01*
X831908Y489055D01*
X827000D01*
G01X820500Y511575D02*
Y515323D01*
G01D02*
Y517004D01*
X822559Y519063D01*
Y520760D01*
G01X831000Y508425D02*
X824500D01*
G01D02*
X820500D01*
G01X817441Y528240D02*
Y533000D01*
G01X820000Y528240D02*
Y532500D01*
X819500Y533000D01*
X817441D01*
G01X821347Y565087D02*
X814954D01*
G01X865466Y790581D02*
X864178D01*
X859272Y785675D01*
Y732418D01*
X822150Y642806D01*
X820617Y641273D01*
G01X865466Y783081D02*
X862992Y780607D01*
Y712538D01*
X838672Y653832D01*
X816732Y631892D01*
Y629198D01*
G01X865394Y801244D02*
X864731Y800581D01*
X864250D01*
X853672Y790003D01*
Y734710D01*
X821153Y656207D01*
X815753Y650807D01*
Y644219D01*
G01X865466Y798081D02*
X864082D01*
X855012Y789011D01*
Y734010D01*
X822532Y655591D01*
X817900Y650959D01*
Y649012D01*
G01X840037Y58448D02*
X840038D01*
Y68540D01*
X837532Y71046D01*
X831943D01*
X831540Y70643D01*
G01Y65918D02*
Y70643D01*
G01Y62768D02*
X836780Y68008D01*
G01X839899Y87248D02*
Y89949D01*
X840401Y90451D01*
G01X839899Y87248D02*
X842596Y84551D01*
Y81448D01*
G01X837251Y90451D02*
Y93221D01*
G01X844936Y93326D02*
X842440D01*
X841585Y94181D01*
G01X841742Y99651D02*
Y99219D01*
X841584Y99061D01*
Y94182D01*
X841585Y94181D01*
G01X835114Y117623D02*
Y115224D01*
X835115Y115223D01*
G01X839360Y120657D02*
X835230D01*
X835114Y120773D01*
G01X831114D02*
X827114D01*
G01X835114D02*
Y121379D01*
X830795Y125698D01*
X828615D01*
G01X829026Y133945D02*
X832362D01*
X834115Y135698D01*
G01X839145Y129362D02*
X837490D01*
X837326Y129198D01*
X833615D01*
G01X829026Y135914D02*
X830614D01*
X834301Y139601D01*
X840530D01*
X846191Y145262D01*
G01X829026Y137882D02*
X830344D01*
X834794Y142332D01*
X835751D01*
X839461Y146042D01*
G01X829026Y139851D02*
X829734D01*
X830243Y140360D01*
Y142834D01*
X833321Y145912D01*
G01X839145Y135862D02*
X834279D01*
X834115Y135698D01*
G01X838221Y163862D02*
Y169362D01*
X839777Y170918D01*
X842562D01*
G01X835221Y163862D02*
Y169142D01*
X839557Y173478D01*
X842562D01*
G01X831295Y166862D02*
Y171631D01*
X831296Y171632D01*
G01X831295Y176362D02*
Y171633D01*
X831296Y171632D01*
G01X842562Y176332D02*
X839854D01*
X838568Y177618D01*
X832551D01*
X831295Y176362D01*
G01X840221Y187937D02*
X839221Y188937D01*
Y192862D01*
G01D02*
Y196788D01*
X840220Y197787D01*
G01X842721Y181362D02*
X840221Y183862D01*
Y184787D01*
G01X838821Y206872D02*
Y209362D01*
X840897Y211438D01*
X841967D01*
G01X840220Y200937D02*
Y205473D01*
X838821Y206872D01*
G01X837161Y213207D02*
X837361Y213407D01*
X841967D01*
G01X837161Y218212D02*
X839998Y215375D01*
X841967D01*
G01Y217344D02*
X841100D01*
X838141Y220303D01*
X834921D01*
G01D02*
X833716Y221508D01*
Y224992D01*
X833715Y224993D01*
G01X844526Y219903D02*
Y220745D01*
X844527Y220746D01*
X841791Y223482D01*
X839951D01*
X838681Y224752D01*
G01X846495Y219903D02*
Y220876D01*
X846496Y220877D01*
X840911Y226462D01*
Y231422D01*
X839081Y233252D01*
G01X830418Y311865D02*
Y305759D01*
X827621Y302962D01*
G01X951886Y804495D02*
X954468Y801913D01*
Y751352D01*
X925393Y681155D01*
Y656186D01*
X893277Y624070D01*
Y592309D01*
X901867Y583719D01*
Y559533D01*
X907893Y553507D01*
Y476635D01*
X896329Y465071D01*
Y373047D01*
X872083Y348801D01*
X852357D01*
X840457Y336901D01*
Y335368D01*
G01X839075Y393000D02*
Y389150D01*
X839000Y389075D01*
G01Y385925D02*
X840386D01*
X841423Y384888D01*
X843417D01*
G01X845500Y393000D02*
X839075D01*
G01X830258Y405347D02*
X837847D01*
G01X840133Y439552D02*
Y443552D01*
G01Y439552D02*
Y435552D01*
G01Y443552D02*
X841648D01*
X845100Y440100D01*
G01X836983Y443552D02*
X834948D01*
X833800Y444700D01*
G01X840133Y459578D02*
Y463578D01*
G01Y459578D02*
Y455578D01*
G01X830212Y483892D02*
X831925Y482179D01*
Y471000D01*
G01X840133Y463578D02*
Y466967D01*
X839200Y467900D01*
G01X836983Y463578D02*
X833751D01*
G01X844760Y467276D02*
Y470240D01*
X844000Y471000D01*
X838500D01*
G01X835075D02*
X838500D01*
G01X840662Y486478D02*
Y482165D01*
X840625Y482128D01*
G01X835236Y483635D02*
X836743Y482128D01*
X840625D01*
G01X829028Y486496D02*
X832375D01*
X835236Y483635D01*
G01X840626Y490567D02*
X840662Y490531D01*
Y486478D01*
G01X840511Y494661D02*
X840626Y494546D01*
Y490567D01*
G01X846182Y507106D02*
X843988D01*
X841854Y504972D01*
G01X831000Y508425D02*
X836395D01*
X838342Y510372D01*
Y514610D01*
G01X836893Y537215D02*
X841900Y542222D01*
G01X829867Y536132D02*
X830950Y537215D01*
X836893D01*
G01X847941Y538325D02*
X841937D01*
X841872Y538260D01*
G01X841900Y545372D02*
X843233D01*
X844741Y543864D01*
G01X834750Y561347D02*
X829221D01*
G01X834750D02*
Y566147D01*
G01X837391Y659820D02*
Y666060D01*
X839245Y667914D01*
Y681535D01*
X839378Y681668D01*
X860152Y731814D01*
Y784117D01*
X864116Y788081D01*
X865466D01*
G01X846575Y1598633D02*
X845589D01*
X841775Y1594819D01*
Y1591574D01*
G01D02*
Y1589989D01*
X837102Y1585316D01*
X836386D01*
G01X841851Y1598753D02*
X838938Y1595840D01*
Y1589219D01*
X837003Y1587284D01*
X836386D01*
G01X856630Y70793D02*
X853312D01*
X845157Y62638D01*
Y58448D01*
X845156D01*
G01X847715D02*
Y56256D01*
X849079Y54892D01*
X852258D01*
G01X856630Y66068D02*
Y70793D01*
G01X858630Y60293D02*
X856630Y62293D01*
Y62918D01*
G01X845156Y81448D02*
Y85281D01*
X846896Y87021D01*
Y91366D01*
X844936Y93326D01*
G01X850016Y90176D02*
Y87341D01*
G01X847715Y81448D02*
X848632D01*
X850016Y82832D01*
Y87341D01*
G01X850088Y105951D02*
X848916D01*
X845766Y102801D01*
Y96461D01*
X847473Y94754D01*
G01D02*
X848901Y93326D01*
X850016D01*
G01X848646Y129362D02*
X845221D01*
G01X842295D02*
X845221D01*
G01X851796D02*
X854221D01*
G01X848646Y135862D02*
X845221D01*
G01X842295D02*
X845221D01*
G01X851796D02*
X854221D01*
G01X856213Y191545D02*
X868433D01*
X878038Y201150D01*
X890305D01*
X897892Y193563D01*
X913386D01*
G01X844221Y187937D02*
X845221Y188937D01*
Y192862D01*
G01D02*
Y196786D01*
X844220Y197787D01*
G01X844221Y184787D02*
X845721Y183287D01*
Y181362D01*
G01X846495Y208879D02*
Y205619D01*
X847261Y204853D01*
Y198592D01*
X849321Y196532D01*
G01X848463Y208879D02*
Y206435D01*
X850761Y204137D01*
Y202512D01*
X853341Y199932D01*
G01X850432Y208879D02*
Y207251D01*
X852911Y204772D01*
X855401D01*
G01X844526Y208879D02*
Y204969D01*
X844527Y204968D01*
G01X844220Y200937D02*
Y202592D01*
X844527Y202899D01*
Y204968D01*
G01X843511Y228962D02*
X848463Y224010D01*
Y219903D01*
G01X856244Y286447D02*
X858084D01*
X859888Y284643D01*
Y283527D01*
G01X843308Y335550D02*
Y336752D01*
X853237Y346681D01*
X872962D01*
X898449Y372168D01*
Y464050D01*
X910425Y476026D01*
Y554485D01*
X903987Y560923D01*
Y584890D01*
X895397Y593480D01*
Y623191D01*
X927971Y655765D01*
Y681838D01*
X956588Y750928D01*
Y803470D01*
X951895Y808163D01*
G01X848425Y385000D02*
Y381000D01*
G01D02*
Y378089D01*
G01X843417Y384888D02*
X843947D01*
X846155Y387096D01*
X851042D01*
X851575Y386563D01*
Y385000D01*
G01X852500Y390441D02*
X855425D01*
X856238Y389628D01*
Y384122D01*
X856146Y384030D01*
G01D02*
X854536D01*
X853566Y385000D01*
X851575D01*
G01X845500Y395559D02*
X847884D01*
X850330Y393113D01*
X857312D01*
X858925Y391500D01*
G01X886362Y1428973D02*
Y1342605D01*
X883483Y1339726D01*
Y1318918D01*
X879746Y1315181D01*
Y1295554D01*
X854878Y1270686D01*
Y822733D01*
X858194Y819417D01*
X863122D01*
X872099Y810440D01*
Y795870D01*
X877375Y790594D01*
Y780578D01*
X880185Y777768D01*
Y664200D01*
X874032Y658047D01*
Y651180D01*
X868622Y645770D01*
X863149D01*
X861072Y643693D01*
Y621644D01*
X861877Y620839D01*
Y544801D01*
X869410Y537268D01*
Y511271D01*
X867976Y509837D01*
Y503162D01*
X867449Y502635D01*
Y492617D01*
X856340Y481508D01*
Y471044D01*
X854331Y469035D01*
Y456860D01*
X865230Y445961D01*
Y427130D01*
X857610Y419510D01*
Y415921D01*
X854603Y412914D01*
X854242D01*
Y412911D01*
X854239D01*
G01X884399Y1431507D02*
X887007D01*
X888243Y1430271D01*
Y1340841D01*
X885431Y1338029D01*
Y1318856D01*
X881166Y1314591D01*
Y1294965D01*
X856298Y1270097D01*
Y823422D01*
X858883Y820837D01*
X863995D01*
X873602Y811230D01*
Y796480D01*
X879483Y790599D01*
Y784797D01*
X881605Y782675D01*
Y662461D01*
X876148Y657004D01*
Y650804D01*
X869669Y644325D01*
X863858D01*
X862492Y642959D01*
Y622233D01*
X863297Y621428D01*
Y545731D01*
X870914Y538114D01*
Y496287D01*
X869297Y494670D01*
Y492336D01*
X857834Y480873D01*
Y470071D01*
X855751Y467988D01*
Y457451D01*
X866650Y446552D01*
Y426480D01*
X859110Y418940D01*
Y415150D01*
X854820Y410860D01*
X852402D01*
X851517Y411745D01*
G01X848500Y467276D02*
Y461500D01*
G01Y458075D02*
Y461500D01*
G01Y454925D02*
Y452128D01*
G01X847686Y475915D02*
X849985Y473616D01*
X854145D01*
X854898Y474369D01*
Y482880D01*
X856094Y484076D01*
Y494585D01*
G01X852240Y476724D02*
Y482500D01*
G01X843812Y486478D02*
X846613D01*
X847303Y485788D01*
G01X843776Y490567D02*
X847180D01*
X847518Y490905D01*
G01X843775Y482128D02*
X846411D01*
G01X852000Y485925D02*
Y482740D01*
X852240Y482500D01*
G01X843661Y494661D02*
X846104D01*
G01X849332Y507106D02*
X851179Y505259D01*
X853551D01*
X855497Y507205D01*
G01X877936Y1312336D02*
Y1295754D01*
X853458Y1271276D01*
Y821471D01*
X857131Y817798D01*
X862393D01*
X870465Y809726D01*
Y795259D01*
X875680Y790044D01*
Y779676D01*
X878765Y776591D01*
Y665839D01*
X870050Y657124D01*
Y649607D01*
X867787Y647344D01*
X862518D01*
X859540Y644366D01*
Y620424D01*
X859984Y619980D01*
Y544397D01*
X867356Y537025D01*
Y532289D01*
X866275Y531208D01*
Y505000D01*
X862264Y500989D01*
X858294D01*
X856166Y498861D01*
G01X853016D02*
X849560D01*
X849351Y499070D01*
G01X852750Y503154D02*
X850706D01*
X850545Y503315D01*
X848097D01*
G01X855900Y503154D02*
X860341D01*
G01X852944Y494585D02*
X849772D01*
G01X855837Y524413D02*
Y519713D01*
G01X848762Y524413D02*
Y521530D01*
X862987Y507305D01*
G01X852687Y524413D02*
X848762D01*
G01X855184Y538325D02*
X847941D01*
G01X863846Y534585D02*
Y537165D01*
X856647Y544364D01*
Y616786D01*
G01X844250Y1266759D02*
Y1280005D01*
X845801Y1281556D01*
Y1287776D01*
G01X849725Y1598633D02*
X852150D01*
G01X871145Y171362D02*
Y172728D01*
X871999Y173582D01*
X877745D01*
X879145Y172182D01*
Y171362D01*
G01X871145D02*
X868645Y168862D01*
X866452D01*
G01D02*
X864396Y170918D01*
X859688D01*
G01X871145Y176862D02*
Y179195D01*
X871563Y179613D01*
X877214D01*
X879145Y177682D01*
Y176862D01*
G01X859688Y173478D02*
X866068D01*
X866452Y173862D01*
G01D02*
X869452Y176862D01*
X871145D01*
G01X859378Y265057D02*
X862390D01*
X863294Y265961D01*
G01X868520Y263654D02*
X867851D01*
X867273Y264232D01*
X865023D01*
X863294Y265961D01*
G01X871345Y276064D02*
Y266479D01*
X868520Y263654D01*
G01X859378Y269057D02*
X863240D01*
X863294Y269111D01*
G01X868104Y273103D02*
X864112Y269111D01*
X863294D01*
G01X867407Y280001D02*
X863230D01*
G01D02*
X859914D01*
X859888Y280027D01*
G01X859408Y273217D02*
X862990D01*
X863104Y273103D01*
G01D02*
X864446D01*
X867407Y276064D01*
G01Y281970D02*
X865850Y283527D01*
X859888D01*
G01X869376Y276064D02*
Y274375D01*
X868104Y273103D01*
G01X869376Y281970D02*
Y282914D01*
X866619Y285671D01*
Y286801D01*
G01X867571Y293810D02*
Y289358D01*
X867618Y289311D01*
G01X866619Y286801D02*
X867618Y287800D01*
Y289311D01*
G01X877260Y320028D02*
Y320740D01*
X875000Y323000D01*
X871099D01*
G01D02*
Y319976D01*
X871500Y319575D01*
G01X871190Y384685D02*
Y382230D01*
G01X860372Y375195D02*
X867407Y382230D01*
X868070D01*
X869000Y383160D01*
Y386410D01*
X867575Y387835D01*
X867190D01*
G01D02*
Y390531D01*
X867800Y391141D01*
Y400620D01*
X869630Y402450D01*
X870864D01*
G01X859075Y387739D02*
X859296Y387518D01*
Y384030D01*
G01X858925Y391500D02*
X859075Y391350D01*
Y387739D01*
G01X871190Y387835D02*
Y391760D01*
G01X862075Y391500D02*
Y386375D01*
X863765Y384685D01*
X867190D01*
G01X871190Y391760D02*
Y393699D01*
X873270Y395779D01*
Y405690D01*
X872770Y406190D01*
X870864D01*
G01X864826Y411557D02*
X865366Y411017D01*
Y393710D01*
G01D02*
Y392847D01*
X864019Y391500D01*
X862075D01*
G01X868445Y418720D02*
X865920D01*
X864386Y417186D01*
G01D02*
X862890Y415690D01*
Y411134D01*
X861686Y409930D01*
X861416D01*
G01X864826Y411557D02*
X871595Y418326D01*
Y418720D01*
G01X875412Y797350D02*
X880903Y791859D01*
Y785545D01*
X883025Y783423D01*
Y661698D01*
X877653Y656326D01*
Y646748D01*
X865003Y634098D01*
Y574149D01*
X871978Y567174D01*
Y539748D01*
X873798Y537928D01*
Y494667D01*
X862166Y483035D01*
Y453354D01*
X868290Y447230D01*
Y429477D01*
X870064Y427703D01*
G01X883633Y790336D02*
X886625Y787344D01*
Y659692D01*
X881907Y654974D01*
Y645195D01*
X868921Y632209D01*
Y580626D01*
X876944Y572603D01*
Y542996D01*
X879007Y540933D01*
Y492414D01*
X867298Y480705D01*
Y456956D01*
X873763Y450491D01*
X873884D01*
G01X883776Y786814D02*
X885285Y785305D01*
Y660248D01*
X880407Y655370D01*
Y645592D01*
X867581Y632766D01*
Y580070D01*
X875604Y572047D01*
Y542440D01*
X877667Y540377D01*
Y492970D01*
X865958Y481261D01*
Y455857D01*
X873824Y447991D01*
X873884D01*
G01X864065Y519111D02*
Y534366D01*
X863846Y534585D01*
G01X882295Y171362D02*
X887521D01*
G01X882295Y176862D02*
X887521D01*
G01X884300Y192055D02*
Y187449D01*
G01Y192055D02*
X885917D01*
X889351Y195489D01*
G01X884290Y183169D02*
X887130D01*
G01X883853Y267407D02*
X881354D01*
G01D02*
Y273929D01*
X879219Y276064D01*
G01X885764Y284361D02*
X886503Y283622D01*
Y281862D01*
G01X885764Y284361D02*
X884925D01*
X884034Y283470D01*
Y282023D01*
X880044Y278033D01*
X879219D01*
G01X877250Y281970D02*
Y284627D01*
X877448Y284825D01*
G01X887003Y267407D02*
Y270832D01*
X886503Y271332D01*
G01D02*
X884004D01*
G01X877868Y293347D02*
Y289467D01*
X877840Y289439D01*
G01X877891Y297365D02*
Y293370D01*
X877868Y293347D01*
G01X877448Y284825D02*
X877840Y285217D01*
Y289439D01*
G01X884925Y326000D02*
X880575D01*
G01D02*
Y320575D01*
X880028Y320028D01*
X877260D01*
G01X877459Y802356D02*
X878986D01*
X889085Y792257D01*
Y657081D01*
X885916Y653912D01*
G01X884410Y794332D02*
X887965Y790777D01*
Y658793D01*
X883731Y654559D01*
Y651690D01*
G01X1123816Y1456373D02*
X1118034D01*
X1109708Y1448047D01*
X1068811D01*
X1064743Y1452115D01*
X999142D01*
X976118Y1429091D01*
X912506D01*
X901241Y1440356D01*
X883562D01*
G01X888575Y1598633D02*
X887589D01*
X883869Y1594913D01*
Y1591629D01*
G01D02*
Y1590151D01*
X879034Y1585316D01*
X878386D01*
G01Y1587284D02*
X878971D01*
X881033Y1589346D01*
Y1595918D01*
X883831Y1598716D01*
G01X931496Y181752D02*
X926950D01*
X926450Y181252D01*
Y166675D01*
X923387Y163612D01*
X914538D01*
X906544Y155618D01*
X900456D01*
G01X931496Y184114D02*
X927244D01*
X925153Y182023D01*
Y166623D01*
X923022Y164492D01*
X914173D01*
X907609Y157928D01*
X897766D01*
X895456Y155618D01*
G01X889351Y195489D02*
X893752D01*
X898040Y191201D01*
X913386D01*
G01X887130Y183169D02*
X890437Y186476D01*
X913386D01*
G01X893701Y201799D02*
X897213Y198287D01*
X913386D01*
G01X899501Y201899D02*
X900751Y200649D01*
X913386D01*
G01X888075Y326000D02*
X888000Y325925D01*
Y293000D01*
G01X892376Y466430D02*
X897955Y472009D01*
X899891D01*
X905501Y477619D01*
Y552654D01*
X899747Y558408D01*
Y582358D01*
X891157Y590948D01*
Y624949D01*
X923273Y657065D01*
Y681581D01*
X952348Y751774D01*
Y799230D01*
X942365Y809213D01*
X909875D01*
X903149Y815939D01*
Y825094D01*
G01X902376Y590172D02*
X897517Y595031D01*
Y605658D01*
X898774Y606915D01*
X902206D01*
G01X902225Y602182D02*
X900323Y604084D01*
Y604377D01*
G01X908823Y655116D02*
X911208Y657501D01*
Y724331D01*
X910418Y725121D01*
Y737310D01*
X904065Y752653D01*
Y799970D01*
X891315Y812720D01*
Y837843D01*
X902020Y848548D01*
X916046D01*
X922245Y854747D01*
Y862346D01*
X938428Y878529D01*
Y895838D01*
X942087Y899497D01*
Y907818D01*
X936380Y913525D01*
Y920815D01*
X935368Y921827D01*
Y939182D01*
G01X944515Y939850D02*
Y913075D01*
X943354Y911914D01*
Y898972D01*
X939695Y895313D01*
Y878004D01*
X923512Y861821D01*
Y854222D01*
X916571Y847281D01*
X902545D01*
X892582Y837318D01*
Y813245D01*
X904945Y800882D01*
Y752828D01*
X911465Y737088D01*
Y725848D01*
X912475Y724838D01*
Y656207D01*
X909276Y653008D01*
X908187D01*
X906274Y654921D01*
G01X889273Y1134470D02*
X893825D01*
X897198Y1137843D01*
G01D02*
X903300Y1143945D01*
X905618D01*
G01X900885Y1435041D02*
X910536Y1425390D01*
X956063D01*
X1022500Y1358953D01*
Y1330192D01*
X1028733Y1323959D01*
Y768564D01*
X1031209Y766088D01*
Y741905D01*
X1026960Y737656D01*
Y728595D01*
X1030987Y724568D01*
Y592656D01*
X1027301Y588970D01*
Y579364D01*
X1019261Y571324D01*
G01X900808Y1437798D02*
X911527Y1427079D01*
X956408D01*
X1024000Y1359487D01*
Y1330868D01*
X1030271Y1324597D01*
Y769130D01*
X1032672Y766729D01*
Y741192D01*
X1028380Y736900D01*
Y729351D01*
X1032525Y725206D01*
Y590436D01*
X1029431Y587342D01*
G01X891725Y1598633D02*
X894150D01*
G01X913386Y181752D02*
X921394D01*
X922128Y182486D01*
G01X913386Y184114D02*
X917387D01*
G01X908621Y188899D02*
X908682Y188838D01*
X913386D01*
G01X920268Y272284D02*
X916268D01*
G01D02*
Y269859D01*
G01X916889Y585132D02*
X912128D01*
X911980Y585280D01*
G01X916889Y587692D02*
X904856D01*
X902376Y590172D01*
G01X916889Y590251D02*
X910731D01*
G01X916889Y604751D02*
X913444D01*
X911280Y606915D01*
X910598D01*
X910377Y606694D01*
G01D02*
X905577D01*
X905356Y606915D01*
G01X916889Y602192D02*
X913421D01*
X911980Y600751D01*
X910258D01*
G01D02*
X906806D01*
X905375Y602182D01*
G01X916889Y628632D02*
X913348D01*
X910587Y631393D01*
X906696D01*
X903386Y628083D01*
Y618882D01*
X905745Y616523D01*
X910669D01*
X913060Y614132D01*
X916889D01*
G01Y619251D02*
X910535D01*
G01X906313Y825095D02*
X952309D01*
X964150Y813254D01*
Y749414D01*
X943337Y699169D01*
Y666109D01*
X939860Y662632D01*
X938800D01*
X915334Y639166D01*
G01X916889Y631192D02*
X913080D01*
X912051Y632221D01*
Y635518D01*
X913200Y636667D01*
X924541D01*
X926439Y634769D01*
Y629699D01*
X927488Y628650D01*
X931437D01*
X931455Y628632D01*
G01X909320Y663930D02*
Y723947D01*
X906345Y726922D01*
Y742414D01*
G01X907207Y667646D02*
Y724344D01*
X904535Y727016D01*
Y744639D01*
G01X941478Y668648D02*
Y698393D01*
X962730Y749697D01*
Y810251D01*
X951760Y821221D01*
X906387D01*
G01X939216Y664767D02*
Y696434D01*
X961390Y749976D01*
Y809695D01*
X952364Y818721D01*
X933844D01*
X933424Y818301D01*
Y813605D01*
X933004Y813185D01*
X930414D01*
X929994Y813605D01*
Y818301D01*
X929574Y818721D01*
X926984D01*
X926564Y818301D01*
Y813605D01*
X926144Y813185D01*
X923554D01*
X923134Y813605D01*
Y818301D01*
X922714Y818721D01*
X920124D01*
X919704Y818301D01*
Y813605D01*
X919284Y813185D01*
X916694D01*
X916274Y813605D01*
Y818301D01*
X915854Y818721D01*
X911359D01*
X908359Y815721D01*
X906387D01*
G01X1160750Y1463250D02*
X1158843Y1465157D01*
X1120046D01*
X1111184Y1456295D01*
X996429D01*
X979412Y1439278D01*
X914421D01*
X913270Y1440429D01*
G01X1164300Y1463300D02*
X1160834Y1466766D01*
X1119398D01*
X1110347Y1457715D01*
X995788D01*
X978791Y1440718D01*
X918072D01*
X916427Y1442363D01*
X911868D01*
X910041Y1440536D01*
G01X1596273Y1271472D02*
Y1273127D01*
X1600370Y1277224D01*
Y1287708D01*
X1598436Y1289642D01*
Y1298131D01*
X1594871Y1301696D01*
Y1354586D01*
X1601601Y1361316D01*
Y1383155D01*
X1564937Y1419819D01*
X1425894D01*
X1372760Y1472953D01*
X1174358D01*
X1166782Y1480529D01*
X1114005D01*
X1096917Y1463441D01*
X977299D01*
X964057Y1450199D01*
X910893D01*
X909473Y1448779D01*
G01X931496Y193563D02*
X923386D01*
G01X931348Y272340D02*
X925068D01*
G01X920268Y275434D02*
X923959D01*
X925068Y274325D01*
Y272340D01*
G01X920031Y570706D02*
Y562091D01*
X919968Y562028D01*
G01X926449Y570703D02*
Y560469D01*
X928630Y558288D01*
G01X920031Y570706D02*
Y577846D01*
G01X926449Y570703D02*
Y577806D01*
G01X916889Y599632D02*
X919672D01*
X921950Y597354D01*
Y586551D01*
X920564Y585165D01*
X916922D01*
X916889Y585132D01*
G01X931455Y602192D02*
X926484D01*
X924840Y600548D01*
Y588959D01*
X926089Y587710D01*
X931437D01*
X931455Y587692D01*
G01X935746Y611573D02*
X936729Y610590D01*
Y601147D01*
X935231Y599649D01*
X931472D01*
X931455Y599632D01*
G01X916889Y614132D02*
X920989D01*
G01X925643Y616620D02*
X931383D01*
X931455Y616692D01*
G01X916889D02*
X919989D01*
X920989Y617692D01*
G01D02*
X921943Y618646D01*
Y632521D01*
X920713Y633751D01*
X916889D01*
G01X931455Y626073D02*
X928537D01*
X924987Y622523D01*
G01X917341Y1283775D02*
X920223Y1280893D01*
X929515D01*
X938558Y1271850D01*
X951043D01*
X953893Y1269000D01*
X962000D01*
X964000Y1267000D01*
G01X964669Y1271000D02*
X957850D01*
X955850Y1273000D01*
X941553D01*
X929458Y1285095D01*
X920174D01*
X917034Y1288235D01*
G01X963500Y1275000D02*
X961500Y1277000D01*
X951499D01*
X949979Y1275480D01*
X940929D01*
X939130Y1277279D01*
Y1279573D01*
X929246Y1289457D01*
X919768D01*
X916895Y1292330D01*
G01X916945Y1296713D02*
X918378Y1298146D01*
X940117D01*
X944265Y1293998D01*
Y1285729D01*
G01X925650Y1586733D02*
X926150Y1586233D01*
X930575D01*
G01X920386Y1585316D02*
X921422D01*
X921756Y1585650D01*
X924567D01*
X925650Y1586733D01*
G01X920386Y1587284D02*
X922283D01*
X924448Y1589449D01*
X926946D01*
X928225Y1588170D01*
X937188D01*
X938171Y1589153D01*
Y1594465D01*
X937755Y1594881D01*
G01X941370Y185052D02*
X940289D01*
X939252Y184015D01*
X936454D01*
G01D02*
X933993Y186476D01*
X931496D01*
G01X941370Y189052D02*
X937309D01*
X937267Y189010D01*
G01D02*
X934912D01*
X934740Y188838D01*
X931496D01*
G01X944520Y189052D02*
Y192664D01*
X945120Y193264D01*
G01X938788Y269781D02*
X945263D01*
G01D02*
Y274581D01*
G01D02*
X949263D01*
G01X931455Y582573D02*
X935492D01*
X937310Y580755D01*
G01X931455Y587692D02*
X935766D01*
G01X931455Y585132D02*
X938956D01*
G01D02*
X944900D01*
X944968Y585200D01*
G01X931455Y597073D02*
X939511D01*
G01X931455Y611573D02*
X935746D01*
G01X931455Y614132D02*
X940838D01*
X940856Y614150D01*
G01D02*
X945656D01*
G01X931455Y631192D02*
X935783D01*
G01X944481Y628662D02*
X939681D01*
G01X931455Y628632D02*
X939651D01*
X939681Y628662D01*
G01X961592Y821737D02*
X965570Y817759D01*
Y749131D01*
X944823Y699043D01*
Y673574D01*
X948207Y670190D01*
Y663885D01*
X945760Y661438D01*
X941435D01*
X937580Y657583D01*
Y655946D01*
G01X934539Y664648D02*
X932419Y666768D01*
Y687035D01*
X958708Y750506D01*
Y807262D01*
X955649Y810321D01*
X949513D01*
X948644Y811190D01*
G01X951466Y816400D02*
X960048Y807818D01*
Y750238D01*
X934339Y688166D01*
Y668533D01*
G01X955000Y1283000D02*
X987880D01*
X1017472Y1253408D01*
Y893311D01*
X966990Y842829D01*
Y748847D01*
X946291Y698875D01*
Y674214D01*
X949657Y670848D01*
Y638019D01*
X954362Y633314D01*
G01X937148Y1134343D02*
X936298Y1135193D01*
Y1138513D01*
X937438Y1139653D01*
X942568D01*
X944223Y1137998D01*
Y1137843D01*
G01D02*
X950325Y1143945D01*
X952643D01*
G01X944265Y1285729D02*
X948994Y1281000D01*
X963586D01*
X966441Y1278145D01*
G01X933725Y1586233D02*
X936150D01*
G01X949263Y277731D02*
Y280049D01*
X949181Y280131D01*
G01X948118Y585200D02*
Y590379D01*
X948156Y590417D01*
G01D02*
Y593912D01*
G01X952497Y614080D02*
X948876D01*
X948806Y614150D01*
G01X947631Y628662D02*
X951102D01*
G01X955000Y1287000D02*
X957330Y1284670D01*
X988989D01*
X1019024Y1254635D01*
Y892800D01*
X968330Y842106D01*
Y748578D01*
X947721Y698823D01*
Y675439D01*
X951007Y672153D01*
Y639408D01*
X956235Y634180D01*
Y631934D01*
X954362Y630061D01*
G01X995000Y1362000D02*
X1001797Y1355203D01*
Y1291826D01*
X1020678Y1272945D01*
Y891358D01*
X969750Y840430D01*
Y748294D01*
X952489Y706622D01*
Y659141D01*
X954259Y657371D01*
G01X1016000Y1303000D02*
X1025506Y1293494D01*
Y889697D01*
X974010Y838201D01*
Y747438D01*
X959447Y712279D01*
Y666327D01*
X958299Y665179D01*
Y659886D01*
G01X998000Y1365500D02*
X1003391Y1360109D01*
Y1292535D01*
X1022353Y1273573D01*
Y890664D01*
X971170Y839481D01*
Y748010D01*
X954361Y707427D01*
Y660215D01*
G01X1016000Y1361000D02*
Y1306500D01*
X1012500Y1303000D01*
Y1286276D01*
X1024027Y1274749D01*
Y890298D01*
X972590Y838861D01*
Y747726D01*
X957462Y711200D01*
Y668700D01*
G01X985500Y152224D02*
X991350D01*
X991425Y152299D01*
G01D02*
Y154402D01*
X990579Y155248D01*
G01X986447Y158209D02*
X990994D01*
X992452Y159667D01*
G01X985500Y155374D02*
Y157262D01*
X986447Y158209D01*
G01X981445Y179508D02*
Y176387D01*
X982349Y175483D01*
G01X992452Y167541D02*
X988751D01*
G01D02*
X987427D01*
X981806Y173162D01*
Y174940D01*
X982349Y175483D01*
G01X989605Y175400D02*
Y179478D01*
G01X992452Y171479D02*
X989605Y174326D01*
Y175400D01*
G01X992452Y169510D02*
X990101Y171861D01*
X985922D01*
G01X985445Y179508D02*
Y175537D01*
X985499Y175483D01*
G01X985922Y171861D02*
X985499Y172284D01*
Y175483D01*
G01X977071Y211123D02*
Y215709D01*
G01X977196Y210998D02*
X977071Y211123D01*
G01X992830Y260781D02*
X988030D01*
G01D02*
Y264781D01*
G01X997689Y268884D02*
X982224D01*
X978269Y264929D01*
G01X984880Y260781D02*
X982455D01*
G01X984880Y271443D02*
X982455D01*
G01X992830D02*
X988030D01*
G01D02*
Y275443D01*
G01X987659Y295641D02*
X992501D01*
X992508Y295634D01*
G01X984509Y295641D02*
Y303623D01*
G01X988460Y363461D02*
Y358405D01*
G01Y366611D02*
Y371248D01*
X988646Y371434D01*
G01D02*
Y372838D01*
X991786Y375978D01*
Y378999D01*
G01X986668D02*
Y388311D01*
X985668Y389311D01*
G01X980690Y387784D02*
X980189Y388285D01*
Y425907D01*
X993292Y439010D01*
X1046324D01*
X1049325Y442011D01*
Y450632D01*
X1044651Y455306D01*
Y493424D01*
X1054532Y503305D01*
Y564147D01*
X1048575Y570104D01*
Y576789D01*
X1054392Y582606D01*
X1143815D01*
X1159469Y566952D01*
X1208438D01*
X1239059Y597573D01*
Y668897D01*
X1271473Y701311D01*
Y762759D01*
X1273677Y764963D01*
Y765063D01*
G01X992678Y424626D02*
X988190D01*
G01X992678Y428366D02*
X986696D01*
G01X992809Y473675D02*
X991455D01*
X988650Y470870D01*
Y465315D01*
G01X995959Y479175D02*
X993132Y482002D01*
X991316D01*
X988125Y485193D01*
G01X992809Y479175D02*
X987755D01*
X986790Y480140D01*
G01X994421Y159667D02*
Y158449D01*
X995181Y157689D01*
G01X998425Y152299D02*
X996920Y153804D01*
Y156414D01*
X995645Y157689D01*
X995181D01*
G01X1005735Y161018D02*
X1009735D01*
G01X998358Y161636D02*
X1005117D01*
X1005735Y161018D01*
G01X996389Y171479D02*
Y176552D01*
X996416Y176579D01*
G01X996415Y178998D02*
Y176580D01*
X996416Y176579D01*
G01X999915Y178998D02*
X1002722D01*
X1002921Y178799D01*
G01X999915Y178998D02*
Y173036D01*
X998358Y171479D01*
G01X1009801Y171278D02*
X1005709D01*
X1005699Y171268D01*
G01X998358Y169510D02*
X999858D01*
X1002827Y172479D01*
G01D02*
X1004038Y171268D01*
X1005699D01*
G01X1004868Y194419D02*
X1007130D01*
X1008555Y192994D01*
X1008918D01*
G01X1008121Y203525D02*
X1006889Y202293D01*
X1004967D01*
G01X1011068Y207667D02*
X1009843D01*
X1006437Y204261D01*
X1004967D01*
G01X1011120Y198114D02*
X1010748D01*
X1009394Y199468D01*
Y199481D01*
X1008550Y200325D01*
X1004967D01*
G01X1001395Y218348D02*
Y215823D01*
X1000611Y215039D01*
G01D02*
X1001423Y214227D01*
Y211742D01*
G01X997487Y221233D02*
Y225233D01*
G01Y217233D02*
Y221233D01*
G01Y211742D02*
Y217233D01*
G01Y225233D02*
Y229993D01*
X997461Y230019D01*
G01X997689Y258222D02*
X996007D01*
X995506Y257721D01*
Y236670D01*
X997300Y234876D01*
G01X1005169Y263340D02*
X1010028D01*
G01X1005169D02*
X1003500D01*
X1002862Y262702D01*
Y261281D01*
X1003362Y260781D01*
X1005169D01*
G01X997689D02*
X992830D01*
G01X1005169Y274002D02*
X1010028D01*
G01X1005169D02*
X1003099D01*
X1002599Y273502D01*
Y272077D01*
X1003233Y271443D01*
X1005169D01*
G01X997689D02*
X992830D01*
G01X1005169Y295634D02*
X1006982D01*
X1009660Y298312D01*
X1010550D01*
G01X997689Y290516D02*
X997735Y290470D01*
X1000015D01*
X1000584Y291039D01*
Y294812D01*
X999762Y295634D01*
X997689D01*
G01X992508D02*
X997689D01*
G01X1005169Y290516D02*
X1008130D01*
X1010157Y288489D01*
G01X1000460Y363461D02*
Y361405D01*
X1003460Y358405D01*
G01X996460Y363461D02*
Y360405D01*
X998460Y358405D01*
G01X992460Y363461D02*
Y359405D01*
X993460Y358405D01*
G01X1000460Y366611D02*
Y369535D01*
G01D02*
Y374576D01*
X999464Y375572D01*
Y378999D01*
G01X996460Y366611D02*
X995493Y367578D01*
Y371136D01*
X996889Y372532D01*
Y374156D01*
G01X992460Y366611D02*
Y370659D01*
G01D02*
X994366Y372565D01*
Y378978D01*
X994345Y378999D01*
G01X991786Y401047D02*
Y392611D01*
X1000520Y383877D01*
X1005347D01*
X1042979Y346245D01*
X1092385D01*
X1111485Y365345D01*
X1140610D01*
X1147178Y371913D01*
Y386684D01*
X1142300Y391562D01*
X1131400D01*
G01X996889Y374156D02*
Y378983D01*
X996905Y378999D01*
G01X1138710Y370496D02*
X1137996D01*
X1137000Y369500D01*
X1109882D01*
X1089867Y349485D01*
X1044877D01*
X1005366Y388996D01*
X1000457D01*
X996905Y392548D01*
Y401047D01*
G01X1133330Y385698D02*
Y386592D01*
X1135900Y389162D01*
X1141300D01*
X1144619Y385843D01*
Y372119D01*
X1140000Y367500D01*
X1110762D01*
X1091127Y347865D01*
X1043790D01*
X1005219Y386436D01*
X1000704D01*
X994345Y392795D01*
Y401047D01*
G01X991786D02*
Y410240D01*
X999079Y417533D01*
X1014846D01*
X1019000Y413379D01*
Y400110D01*
X1021384Y397726D01*
G01X999464Y401047D02*
Y407519D01*
X1001800Y409855D01*
X1010124D01*
X1013100Y406879D01*
Y388296D01*
X1021394Y380002D01*
Y378764D01*
G01X1133330Y380533D02*
Y372000D01*
X1132830Y371500D01*
X1108732D01*
X1088337Y351105D01*
X1046276D01*
X999464Y397917D01*
Y401047D01*
G01X996905D02*
Y408559D01*
X1000760Y412414D01*
X1011311D01*
X1015000Y408725D01*
Y390158D01*
X1021394Y383764D01*
G01X994345Y401047D02*
Y409900D01*
X999419Y414974D01*
X1012036D01*
X1017000Y410010D01*
Y393158D01*
X1021394Y388764D01*
G01X1002126Y420886D02*
X1008108D01*
G01X1011189Y452155D02*
X1005209Y446175D01*
X1003909D01*
G01X994900Y446192D02*
X997617Y443475D01*
X1001209D01*
X1003909Y446175D01*
G01X991664Y446372D02*
X991877Y446585D01*
Y448846D01*
X997058Y454027D01*
X1001557D01*
X1003909Y451675D01*
G01X1011189Y460155D02*
X1006889D01*
X1003909Y457175D01*
G01Y454662D02*
Y457175D01*
G01X1011189Y464155D02*
X1009709Y462675D01*
X1003909D01*
G01D02*
Y460162D01*
G01X1011189Y456155D02*
X1006709Y451675D01*
X1003909D01*
G01X1011189Y476155D02*
X1006929D01*
X1003909Y479175D01*
G01D02*
X1001329Y476595D01*
X998153D01*
X995959Y474401D01*
Y473675D01*
G01D02*
X993939Y471655D01*
X992713D01*
X991270Y470212D01*
G01X1011189Y468155D02*
X1011169Y468175D01*
X1003909D01*
G01X993650Y465315D02*
X1001049D01*
X1003909Y468175D01*
G01X1011189Y472155D02*
X1005429D01*
X1003909Y473675D01*
G01X996320Y470364D02*
X996941Y470985D01*
X1001219D01*
X1003909Y473675D01*
G01Y490175D02*
Y488105D01*
X1007077Y484937D01*
G01X1003909Y484675D02*
X1001329Y482095D01*
X998153D01*
G01X1011189Y480155D02*
X1008429D01*
X1003909Y484675D01*
G01X998153Y482095D02*
X995959Y479901D01*
Y479175D01*
G01X1014339Y488642D02*
X1011676Y491305D01*
X1006779D01*
X1003909Y494175D01*
G01X1014339Y493655D02*
Y493755D01*
X1008419Y499675D01*
X1003909D01*
G01X1002056Y521014D02*
X999631D01*
G01X1008631Y522264D02*
X1003306D01*
X1002056Y521014D01*
G01Y516014D02*
X999631D01*
G01X1008631Y519705D02*
X1005747D01*
X1002056Y516014D01*
G01X994056Y521014D02*
X991631D01*
G01X996481D02*
X994056D01*
G01Y516014D02*
X991631D01*
G01X996481D02*
X994056D01*
G01X1002056Y526074D02*
X1003306Y524824D01*
X1008631D01*
G01X999631Y526074D02*
X1002056D01*
G01X1008631Y527383D02*
X1005111D01*
X1002056Y530438D01*
Y531074D01*
G01D02*
X999631D01*
G01X994056Y526074D02*
X991631D01*
G01X996481D02*
X994056D01*
G01Y531074D02*
X991631D01*
G01X996481D02*
X994056D01*
G01X1009735Y161018D02*
X1013935D01*
X1014435Y160518D01*
G01X1012885Y153868D02*
X1014435Y155418D01*
Y160518D01*
G01X1008918Y192994D02*
X1012240D01*
X1013745Y194499D01*
G01X1016895D02*
X1020521D01*
G01X1013545Y203099D02*
X1012223D01*
X1011797Y203525D01*
X1008121D01*
G01X1013620Y207423D02*
X1011312D01*
X1011068Y207667D01*
G01X1011120Y198114D02*
X1011776D01*
X1012661Y198999D01*
X1013645D01*
G01X1016770Y230423D02*
X1019531D01*
G01X1086838Y454495D02*
X1079969Y447626D01*
Y438143D01*
X1084782Y433330D01*
X1124959D01*
X1153352Y404937D01*
Y371318D01*
X1136223Y354189D01*
X1107386D01*
X1054103Y300906D01*
Y284497D01*
X1018220Y248614D01*
Y243638D01*
G01X1015220D02*
Y247510D01*
X1052763Y285053D01*
Y301462D01*
X1106830Y355529D01*
X1135667D01*
X1152012Y371874D01*
Y404381D01*
X1124403Y431990D01*
X1084226D01*
X1078295Y437921D01*
Y448535D01*
X1068871Y457959D01*
G01X1009220Y243638D02*
X1051423Y285841D01*
Y302018D01*
X1106274Y356869D01*
X1135111D01*
X1150672Y372430D01*
Y403825D01*
X1123847Y430650D01*
X1079466D01*
X1068821Y441295D01*
Y445499D01*
G01X1010028Y263340D02*
X1011528Y264840D01*
X1014828D01*
G01Y274002D02*
X1010028D01*
G01X1010550Y298312D02*
X1015258D01*
X1015259Y298311D01*
G01X1018409D02*
X1023000D01*
G01X1018409Y287311D02*
X1023110D01*
G01X1015259D02*
X1011335D01*
X1010157Y288489D01*
G01X1013982Y420902D02*
Y425902D01*
G01X1008108Y420886D02*
X1013966D01*
X1013982Y420902D01*
G01X1017132D02*
X1020748D01*
G01X1014339Y460155D02*
X1015746Y461562D01*
X1018809D01*
X1020168Y462921D01*
X1023420D01*
G01X1023515Y454397D02*
X1021273Y452155D01*
X1014339D01*
G01X1019205Y457687D02*
X1017673Y456155D01*
X1014339D01*
G01X1029035Y460362D02*
X1021880D01*
X1019205Y457687D01*
G01X1023420Y468039D02*
X1020380D01*
X1020264Y468155D01*
X1014339D01*
G01Y472155D02*
X1017350D01*
G01D02*
X1018254D01*
X1019810Y470599D01*
X1029035D01*
G01X1014339Y464155D02*
X1017220D01*
G01D02*
X1018545Y465480D01*
X1029035D01*
G01X1022874Y474545D02*
X1021264Y476155D01*
X1014339D01*
G01X1011189Y484155D02*
X1009929D01*
G01D02*
X1007859D01*
X1007077Y484937D01*
G01X1014339Y488642D02*
Y488655D01*
X1015339Y489655D01*
X1022764D01*
G01X1029035Y478276D02*
X1025216D01*
X1019410Y484082D01*
Y485582D01*
G01D02*
X1017983Y484155D01*
X1014339D01*
G01Y480155D02*
X1019210D01*
G01D02*
X1020764D01*
X1025202Y475717D01*
X1029035D01*
G01X1019264Y493655D02*
X1022764D01*
X1025264Y491155D01*
Y484155D01*
X1026025Y483394D01*
X1029035D01*
G01X1014339Y493655D02*
X1019264D01*
G01X1008631Y532501D02*
X1013306D01*
G01X1018872Y549855D02*
X1018653Y550074D01*
X1015361D01*
G01X1024961Y546649D02*
X1022512D01*
X1019306Y549855D01*
X1018872D01*
G01X1017961Y545074D02*
X1015361D01*
G01X1024961D02*
X1017961D01*
G01X1012211Y550074D02*
X1009611D01*
G01D02*
X1007011D01*
G01X1012211Y545074D02*
X1009611D01*
G01D02*
X1007011D01*
G01X1019161Y554757D02*
Y556557D01*
X1019961Y557357D01*
G01X1024961Y548224D02*
X1023724D01*
X1022167Y549781D01*
Y551751D01*
X1019161Y554757D01*
G01X1016075Y560500D02*
X1019954D01*
X1019961Y560507D01*
G01X1016075Y560500D02*
Y563032D01*
X1016000Y563107D01*
G01X1026229Y254641D02*
X1024220Y252632D01*
Y243638D01*
G01X1026229Y254641D02*
X1055443Y283855D01*
Y300350D01*
X1107942Y352849D01*
X1136779D01*
X1154692Y370762D01*
Y405493D01*
X1125515Y434670D01*
X1085493D01*
X1081442Y438721D01*
Y445582D01*
X1084875Y449015D01*
X1090923D01*
X1093513Y451605D01*
G01X1023000Y298311D02*
X1027829D01*
G01X1023110Y287311D02*
X1027829D01*
G01X1040045Y388803D02*
X1030697D01*
X1028662Y389646D01*
X1024544Y393764D01*
G01Y378764D02*
X1029269D01*
G01D02*
X1033492D01*
X1035853Y381125D01*
X1040045D01*
G01X1024544Y383764D02*
X1025544Y382764D01*
X1033069D01*
G01D02*
X1033989Y383684D01*
X1040045D01*
G01X1024544Y388764D02*
X1027064Y386244D01*
X1029269D01*
G01D02*
X1040045D01*
G01Y393921D02*
X1030067D01*
X1029601Y394387D01*
G01X1024575Y402000D02*
X1028000D01*
X1030000Y400000D01*
Y394786D01*
X1029601Y394387D01*
G01X1021384Y397726D02*
Y393774D01*
X1021394Y393764D01*
G01X1033449Y424500D02*
X1028994D01*
X1025368Y420874D01*
Y409071D01*
X1037092Y397347D01*
X1041934D01*
X1044352Y394929D01*
Y389902D01*
X1043253Y388803D01*
X1040045D01*
G01X1040425Y421941D02*
X1040422Y421944D01*
X1036300D01*
X1035946Y421590D01*
X1030405D01*
X1027177Y418362D01*
Y409821D01*
X1037842Y399156D01*
X1042684D01*
X1046161Y395679D01*
Y388416D01*
X1043989Y386244D01*
X1040045D01*
G01X1040425Y416822D02*
X1032955D01*
X1030796Y414663D01*
Y411321D01*
X1039342Y402775D01*
X1044184D01*
X1049780Y397179D01*
Y385240D01*
X1045665Y381125D01*
X1040045D01*
G01X1040425Y419381D02*
X1032118D01*
X1028987Y416250D01*
Y410571D01*
X1038592Y400966D01*
X1043434D01*
X1047971Y396429D01*
Y387178D01*
X1044477Y383684D01*
X1040045D01*
G01X1040425Y429618D02*
X1034409D01*
G01X1040425Y424500D02*
X1033449D01*
G01X1034899Y444404D02*
Y450240D01*
X1038270Y453611D01*
Y494488D01*
X1049833Y506051D01*
Y561830D01*
X1041124Y570539D01*
Y578036D01*
X1035367Y583793D01*
Y726857D01*
X1030190Y732034D01*
Y735023D01*
G01X1023420Y462921D02*
X1029035D01*
G01Y457803D02*
X1024431D01*
X1023515Y456887D01*
Y454397D01*
G01X1029035Y468039D02*
X1023420D01*
G01X1029035Y473158D02*
X1024261D01*
X1022874Y474545D01*
G01X1022764Y489655D02*
X1023764Y488655D01*
Y483155D01*
X1026084Y480835D01*
X1029035D01*
G01X1037254Y521014D02*
X1036004Y522264D01*
X1030679D01*
G01X1036708Y514883D02*
X1035852Y515739D01*
Y517744D01*
X1033891Y519705D01*
X1030679D01*
G01X1037254Y526074D02*
X1036004Y524824D01*
X1030679D01*
G01X1036021Y534990D02*
Y529641D01*
X1033763Y527383D01*
X1030679D01*
G01X1027520Y543499D02*
Y541993D01*
X1025631Y540104D01*
G01X1024961Y549799D02*
Y553957D01*
X1024161Y554757D01*
G01X1030079Y548224D02*
X1032252D01*
X1033215Y549187D01*
X1033545Y549984D01*
Y553279D01*
X1034246Y553980D01*
G01X1030000Y554500D02*
Y552724D01*
X1031500Y551224D01*
Y550300D01*
X1030999Y549799D01*
X1030079D01*
G01Y546649D02*
X1033392D01*
X1037841Y551098D01*
X1038333D01*
G01X1030079Y545074D02*
X1037241D01*
X1038054Y544261D01*
G01X1039000Y560575D02*
X1035500D01*
G01X1028425Y566000D02*
Y563075D01*
X1028500Y563000D01*
G01X1030000Y560575D02*
Y561500D01*
X1028500Y563000D01*
G01X1024161Y554757D02*
Y556557D01*
X1024961Y557357D01*
G01Y560507D02*
Y562039D01*
X1024000Y563000D01*
G01X1024575Y566000D02*
Y563575D01*
X1024000Y563000D01*
G01X1035500Y557425D02*
X1034500Y556425D01*
Y554234D01*
X1034246Y553980D01*
G01X1030000Y557425D02*
Y554500D01*
G01X1039015Y444404D02*
X1039458Y444847D01*
Y493927D01*
X1051007Y505476D01*
Y562287D01*
X1042753Y570541D01*
Y578171D01*
X1036782Y584142D01*
Y728302D01*
X1032736Y732348D01*
Y735320D01*
G01X1042015Y444404D02*
X1041363Y445056D01*
Y493998D01*
X1052130Y504765D01*
Y562794D01*
X1044076Y570848D01*
Y578654D01*
X1037951Y584779D01*
Y729676D01*
X1035269Y732358D01*
Y735474D01*
G01X1046384Y269814D02*
Y266253D01*
X1049565Y263072D01*
X1052542D01*
X1053466Y263996D01*
X1059298D01*
X1064925Y258369D01*
X1068196D01*
X1103041Y223524D01*
X1411113D01*
X1412839Y225250D01*
X1513644D01*
G01X1049451Y266747D02*
X1050782Y268078D01*
X1057508D01*
X1065597Y259989D01*
X1068868D01*
X1103713Y225144D01*
X1410441D01*
X1416547Y231250D01*
X1518944D01*
G01X1043377Y452740D02*
X1043266Y452851D01*
Y494199D01*
X1053345Y504278D01*
Y563507D01*
X1046351Y570501D01*
Y580599D01*
X1043029Y583921D01*
Y732786D01*
X1042389Y733426D01*
G01X1039679Y521074D02*
X1037314D01*
X1037254Y521014D01*
G01X1039679Y516014D02*
X1037839D01*
X1036708Y514883D01*
G01X1039679Y526074D02*
X1037254D01*
G01X1045575Y538000D02*
Y539395D01*
X1043991Y540979D01*
G01X1039679Y534074D02*
X1036937D01*
X1036021Y534990D01*
G01X1038054Y544261D02*
Y543513D01*
X1040725Y540842D01*
X1041481Y539019D01*
X1042425Y538075D01*
Y538000D01*
G01X1044906Y553641D02*
Y552801D01*
X1041679Y549574D01*
G01X1039407Y547723D02*
X1040511D01*
X1041679Y548891D01*
Y549574D01*
G01X1043991Y540979D02*
X1041679Y543291D01*
Y544574D01*
G01X1038333Y551098D02*
X1039213D01*
X1041756Y553641D01*
G01X1039000Y560575D02*
X1042628Y556947D01*
Y556845D01*
G01X1078499Y648202D02*
Y651894D01*
X1045295Y685098D01*
Y735688D01*
X1044795Y736188D01*
X1044056D01*
G01X1168957Y575602D02*
X1166431Y573076D01*
X1161281D01*
X1088540Y645817D01*
Y655292D01*
X1071934Y671898D01*
Y736820D01*
X1061628Y747126D01*
X1044345D01*
X1038127Y753344D01*
X1036970Y756135D01*
Y769989D01*
X1036427Y770532D01*
G01X1038867Y774960D02*
X1039096Y774731D01*
Y756312D01*
X1039743Y754748D01*
X1045149Y749342D01*
X1063264D01*
X1074264Y738342D01*
Y673255D01*
X1090837Y656682D01*
Y646647D01*
X1142194Y595290D01*
X1166383D01*
X1169000Y592673D01*
G01X1045465Y766870D02*
X1040915D01*
G01X1045465Y763524D02*
X1040915D01*
G01X1045677Y1646205D02*
X1052589D01*
X1054606Y1648222D01*
G01X1044394Y1658146D02*
Y1655137D01*
X1045545Y1653986D01*
Y1652082D01*
G01X1053290D02*
X1045545D01*
G01X1050104Y1665459D02*
X1047915D01*
X1045545Y1663089D01*
G01X1050104Y1662309D02*
X1048557D01*
X1044394Y1658146D01*
G01X1062704Y270875D02*
X1068730Y264849D01*
X1072254D01*
X1107099Y230004D01*
X1407055D01*
X1414130Y237079D01*
X1511423D01*
X1513644Y239300D01*
Y246350D01*
G01X1060719Y512359D02*
X1105426D01*
X1124591Y493194D01*
Y442579D01*
X1158236Y408934D01*
Y371511D01*
X1136768Y350043D01*
X1107996D01*
X1057273Y299320D01*
Y270605D01*
X1066269Y261609D01*
X1070910D01*
X1105755Y226764D01*
X1408399D01*
X1415474Y233839D01*
X1537269D01*
X1541858Y229250D01*
X1545620D01*
G01X1060719Y516059D02*
X1104018D01*
X1126211Y493866D01*
Y443251D01*
X1159856Y409606D01*
Y370839D01*
X1137440Y348423D01*
X1108668D01*
X1058893Y298648D01*
Y271277D01*
X1066941Y263229D01*
X1071582D01*
X1106427Y228384D01*
X1407727D01*
X1414802Y235459D01*
X1539419D01*
X1540628Y234250D01*
X1545620D01*
G01X1523744Y201250D02*
X1511328D01*
X1501928Y210650D01*
X1242400D01*
X1240966Y212084D01*
X1167356D01*
X1159475Y219965D01*
X1102016D01*
X1066852Y255129D01*
X1063580D01*
X1059533Y259176D01*
X1056941D01*
G01X1054613Y261586D02*
X1059415D01*
X1064252Y256749D01*
X1067524D01*
X1102369Y221904D01*
X1236976D01*
X1242552Y216328D01*
X1508202D01*
X1511280Y213250D01*
X1513644D01*
G01X1058231Y523238D02*
X1059812Y524819D01*
X1073351D01*
X1080491Y517679D01*
X1104690D01*
X1127831Y494538D01*
Y443923D01*
X1161476Y410278D01*
Y370167D01*
X1138112Y346803D01*
X1109340D01*
X1060513Y297976D01*
Y278477D01*
X1063782Y275208D01*
X1065382D01*
X1069105Y271485D01*
Y269885D01*
X1072521Y266469D01*
X1072926D01*
X1107438Y231957D01*
X1406716D01*
X1413458Y238699D01*
X1507113D01*
X1509251Y240837D01*
Y256956D01*
X1511908Y259613D01*
X1513348D01*
G01X1062093Y388803D02*
X1061908Y388988D01*
X1055934D01*
G01X1062093Y381125D02*
X1067206D01*
X1068143Y380188D01*
G01X1062093Y383684D02*
X1057630D01*
X1055934Y381988D01*
G01X1086714Y353515D02*
Y363883D01*
X1070991Y379606D01*
Y384761D01*
X1068786Y386966D01*
X1066735D01*
X1066013Y386244D01*
X1062093D01*
G01X1062473Y416822D02*
X1067238D01*
X1072738Y411322D01*
G01X1075526Y424389D02*
X1075415Y424500D01*
X1062473D01*
G01Y419381D02*
X1068915D01*
X1071533Y416763D01*
X1072738D01*
G01X1062473Y421941D02*
X1072719D01*
X1072738Y421922D01*
G01X1057276Y458155D02*
X1055264D01*
X1054912Y457803D01*
X1051083D01*
G01X1065689Y453655D02*
X1061776D01*
X1057276Y458155D01*
G01X1062640Y449155D02*
X1065189D01*
X1065689Y449655D01*
G01X1051083Y455244D02*
X1056551D01*
G01D02*
X1062640Y449155D01*
G01X1058223Y464938D02*
X1060534D01*
X1062947Y462525D01*
X1065719D01*
G01X1051083Y462921D02*
X1056206D01*
X1058223Y464938D01*
G01X1074635Y457959D02*
X1072343Y460251D01*
X1060316D01*
G01D02*
X1056966D01*
X1056855Y460362D01*
X1051083D01*
G01X1054702Y475717D02*
X1051083D01*
G01X1054702D02*
X1058235D01*
X1062173Y479655D01*
G01X1051083Y478276D02*
X1055653D01*
G01D02*
X1055854D01*
X1062250Y484672D01*
G01X1065719Y471500D02*
X1058205D01*
G01D02*
X1054744Y468039D01*
X1051083D01*
G01X1062258Y467919D02*
X1057772D01*
X1055333Y465480D01*
X1051083D01*
G01X1065719Y467000D02*
X1064800Y467919D01*
X1062258D01*
G01X1065689Y479655D02*
X1062173D01*
G01X1062250Y484672D02*
X1064672D01*
X1065689Y483655D01*
G01X1056960Y482262D02*
X1055533Y480835D01*
X1051083D01*
G01X1065689Y487655D02*
X1062353D01*
X1056960Y482262D01*
G01X1083281Y651601D02*
X1081866Y653016D01*
X1080071D01*
X1061452Y671635D01*
Y735997D01*
X1061817Y736362D01*
G01X1162067Y570050D02*
X1161307D01*
X1086346Y645011D01*
Y652406D01*
X1084416Y654336D01*
X1081181D01*
X1066989Y668528D01*
Y734447D01*
X1065154Y736282D01*
G01X1061607Y766870D02*
X1066157D01*
G01X1061607Y770217D02*
X1066157D01*
G01X1063751Y1647919D02*
X1068093D01*
X1068094Y1647920D01*
G01X1054606Y1648222D02*
X1063448D01*
X1063751Y1647919D01*
G01X1058346Y1656096D02*
X1060740D01*
X1060754Y1656110D01*
X1063486D01*
X1064221Y1656845D01*
G01X1058346Y1656096D02*
X1054332Y1652082D01*
X1053290D01*
G01X1068221Y1656845D02*
X1064221D01*
G01X1594537Y298182D02*
X1591484D01*
X1589291Y295989D01*
Y292269D01*
X1607358Y274202D01*
Y219467D01*
X1582495Y194604D01*
X1510148D01*
X1508763Y195989D01*
X1106120D01*
X1075209Y165078D01*
X1066231D01*
G01X1594537Y300742D02*
X1591812D01*
X1587713Y296643D01*
Y291615D01*
X1605780Y273548D01*
Y220121D01*
X1581841Y196182D01*
X1510802D01*
X1508698Y198286D01*
X1106185D01*
X1075477Y167578D01*
X1066231D01*
G01X1071698Y270702D02*
X1108716Y233684D01*
X1406049D01*
X1412881Y240516D01*
X1488191D01*
X1510722Y263047D01*
X1578462D01*
X1593349Y248160D01*
G01X1068506Y369792D02*
Y374052D01*
X1068143Y374415D01*
Y380188D01*
G01X1081660Y379226D02*
X1075616D01*
X1074654Y380188D01*
G01X1081660Y383226D02*
X1078400D01*
G01X1081660Y387226D02*
X1074818D01*
X1074249Y387795D01*
G01X1081660Y391226D02*
X1078400D01*
G01X1075526Y424389D02*
X1086431D01*
X1090061Y428019D01*
G01X1068839Y449655D02*
Y445517D01*
X1068821Y445499D01*
G01X1068871Y457959D02*
Y453687D01*
X1068839Y453655D01*
G01X1068869Y462525D02*
X1076954D01*
X1077873Y463444D01*
G01X1077785Y457959D02*
X1080453D01*
G01X1065689Y479655D02*
X1065719Y479625D01*
Y475525D01*
G01X1068869Y471500D02*
X1071667D01*
G01D02*
X1074719D01*
G01X1068869Y467000D02*
X1071667D01*
G01D02*
X1074719D01*
G01X1071710Y483655D02*
X1071837Y483782D01*
X1074635D01*
G01X1068839Y483655D02*
X1071710D01*
G01Y488782D02*
X1070583Y487655D01*
X1068839D01*
G01X1074635Y487782D02*
X1072710D01*
X1071710Y488782D01*
G01X1072232Y667749D02*
X1069476Y670505D01*
Y735697D01*
X1068378Y736795D01*
G01X1075166Y766870D02*
X1070616D01*
G01X1075166Y763524D02*
X1070616D01*
G01X1068094Y1647920D02*
X1072134D01*
G01X1080970Y1650958D02*
X1076417D01*
X1070530Y1656845D01*
X1068221D01*
G01X1097111Y388265D02*
X1093621D01*
X1093071Y388815D01*
Y392146D01*
X1091047Y394170D01*
X1088221D01*
G01X1097111Y380587D02*
X1091839D01*
X1088558Y377306D01*
G01D02*
X1086730D01*
X1084810Y379226D01*
G01X1097111Y383146D02*
X1090700D01*
X1090060Y382506D01*
X1088588D01*
G01D02*
X1085530D01*
X1084810Y383226D01*
G01X1090035Y388477D02*
X1087145D01*
X1085894Y387226D01*
X1084810D01*
G01X1097111Y385706D02*
X1092806D01*
X1090035Y388477D01*
G01X1097111Y393383D02*
X1096725D01*
X1089866Y400242D01*
X1085692D01*
X1082866Y403068D01*
G01X1088221Y394170D02*
X1087754D01*
X1084810Y391226D01*
G01X1084840Y438234D02*
X1091142D01*
X1093513Y440605D01*
G01X1098873Y447355D02*
X1093513Y441995D01*
Y440605D01*
G01X1084840Y443515D02*
X1090923D01*
X1093513Y446105D01*
G01X1098873Y451355D02*
X1098763D01*
X1093513Y446105D01*
G01X1098873Y455355D02*
X1097263D01*
X1093513Y451605D01*
G01X1098873Y459355D02*
X1095763D01*
X1093513Y457105D01*
G01X1086838Y454495D02*
X1090903D01*
X1093513Y457105D01*
G01X1098873Y463355D02*
X1094263D01*
X1093513Y462605D01*
G01X1084840Y460005D02*
X1090913D01*
X1093513Y462605D01*
G01X1098873Y467355D02*
X1098123Y468105D01*
X1093513D01*
G01X1085851Y465978D02*
X1086595Y465234D01*
X1090642D01*
X1093513Y468105D01*
G01X1090363Y472105D02*
X1086513D01*
G01D02*
Y474987D01*
X1084000Y477500D01*
G01X1093513Y472105D02*
X1103755D01*
X1107005Y475355D01*
G01X1092948Y476280D02*
X1097948D01*
X1098873Y475355D01*
G01X1090000Y477500D02*
X1091220Y476280D01*
X1092948D01*
G01X1098873Y479355D02*
X1098763D01*
X1093513Y484605D01*
G01X1083434Y481500D02*
X1090408D01*
X1093513Y484605D01*
G01Y489641D02*
X1096269Y486885D01*
X1099529D01*
X1102023Y484391D01*
G01Y489391D02*
X1096773Y494641D01*
X1093513D01*
G01X1118435Y625307D02*
X1117892Y625850D01*
X1114634D01*
X1093088Y647396D01*
Y658071D01*
X1088168Y662991D01*
Y670184D01*
X1106484Y688500D01*
X1137398D01*
X1182713Y733815D01*
G01X1091308Y766870D02*
X1095858D01*
G01X1091308Y770217D02*
X1095858D01*
G01X1091306Y1629945D02*
X1091406D01*
X1095602Y1625749D01*
X1098549D01*
G01X1100961Y1622543D02*
X1095957D01*
X1089500Y1629000D01*
Y1632500D01*
X1090726Y1633726D01*
X1091264D01*
G01X1094456Y1629945D02*
X1094901Y1629500D01*
X1097000D01*
G01X1096768Y1635080D02*
X1095768D01*
X1094414Y1633726D01*
G01X1087141Y1688914D02*
Y1688724D01*
X1088636Y1687229D01*
X1091539D01*
G01X1094689D02*
Y1691229D01*
G01D02*
X1099108D01*
G01X1098514Y1722841D02*
X1094514D01*
G01D02*
X1089030D01*
G01Y1717841D02*
X1093364D01*
X1094514Y1718991D01*
G01D02*
X1098514D01*
G01X1102023Y447355D02*
X1107043D01*
G01D02*
X1111543Y451855D01*
Y455355D01*
X1113991Y457803D01*
X1118614D01*
G01X1102023Y463355D02*
Y464335D01*
X1105727Y468039D01*
X1107043D01*
G01X1107300Y456944D02*
X1103612D01*
X1102023Y455355D01*
G01X1118614Y462921D02*
X1113277D01*
X1107300Y456944D01*
G01X1102023Y459355D02*
X1106023Y463355D01*
X1110043D01*
X1111076Y464388D01*
G01X1102023Y451355D02*
X1107543D01*
X1109043Y452855D01*
G01D02*
Y455435D01*
X1113970Y460362D01*
X1118614D01*
G01X1107043Y468039D02*
X1118614D01*
G01X1102023Y467355D02*
Y468335D01*
X1105543Y471855D01*
X1111043D01*
G01X1118614Y473158D02*
X1113943D01*
X1111746Y475355D01*
X1107005D01*
G01X1102023D02*
X1105023Y478355D01*
X1111005D01*
G01X1102023Y489391D02*
X1107043D01*
G01D02*
X1112007D01*
X1114543Y486855D01*
Y484855D01*
X1116004Y483394D01*
X1118614D01*
G01X1102023Y484391D02*
X1103403Y485771D01*
X1111043D01*
G01X1118614Y478276D02*
X1115122D01*
X1112043Y481355D01*
X1107005D01*
G01D02*
X1104023D01*
X1102023Y479355D01*
G01X1126387Y615658D02*
Y620768D01*
X1119314Y627841D01*
X1114784D01*
X1097459Y645166D01*
Y657623D01*
X1123178Y683342D01*
X1166139D01*
X1217999Y735202D01*
Y776263D01*
X1234096Y792364D01*
Y792368D01*
X1248866Y807138D01*
X1254985D01*
X1256785Y808938D01*
X1257527D01*
G01X1129387Y615658D02*
Y620043D01*
X1120392Y629038D01*
X1115280D01*
X1098656Y645662D01*
Y657127D01*
X1123674Y682145D01*
X1166635D01*
X1219196Y734706D01*
Y775767D01*
X1235308Y791883D01*
Y791887D01*
X1249362Y805941D01*
X1257504D01*
X1260427Y808864D01*
Y809008D01*
G01X1138387Y615658D02*
Y615998D01*
X1122213Y632172D01*
X1116579D01*
X1101790Y646961D01*
Y655828D01*
X1124973Y679011D01*
X1167934D01*
X1222330Y733407D01*
Y774468D01*
X1237527Y789665D01*
Y789668D01*
X1250662Y802803D01*
X1261178D01*
X1266568Y808193D01*
Y809078D01*
G01X1135387Y615658D02*
Y616356D01*
X1121285Y630458D01*
X1115869D01*
X1100076Y646251D01*
Y656538D01*
X1124263Y680725D01*
X1167224D01*
X1220616Y734117D01*
Y775178D01*
X1235813Y790375D01*
Y790378D01*
X1249952Y804517D01*
X1259548D01*
X1263647Y808616D01*
Y809118D01*
G01X1114467Y640802D02*
Y644018D01*
X1107858Y650627D01*
Y655297D01*
X1126907Y674346D01*
X1169868D01*
X1226995Y731473D01*
Y772830D01*
X1241743Y787578D01*
X1244986D01*
G01X1108076Y646774D02*
Y647359D01*
X1106394Y649041D01*
Y656170D01*
X1126222Y675998D01*
X1169183D01*
X1225343Y732158D01*
Y772952D01*
X1243607Y791216D01*
X1258585D01*
X1268521Y801152D01*
X1268528D01*
X1275177Y807801D01*
Y808963D01*
G01X1104443Y646983D02*
X1104151Y647275D01*
Y655971D01*
X1125623Y677443D01*
X1168584D01*
X1223898Y732757D01*
Y773818D01*
X1251314Y801234D01*
X1261674D01*
X1265658Y805218D01*
X1267983D01*
X1271177Y808412D01*
Y808963D01*
G01X1104866Y766870D02*
X1100316D01*
G01X1104866Y763524D02*
X1100316D01*
G01X1099098Y1498695D02*
Y1501204D01*
G01D02*
Y1505029D01*
G01X1773963Y557537D02*
X1784660Y568234D01*
Y646580D01*
X1802410Y664330D01*
X1825579D01*
X1837340Y676091D01*
Y772769D01*
X1826210Y783899D01*
Y1290309D01*
X1762035Y1354484D01*
Y1429034D01*
X1746370Y1444699D01*
X1700777D01*
X1685383Y1460093D01*
X1395338D01*
X1376073Y1479358D01*
X1174916D01*
X1167642Y1486632D01*
X1138144D01*
X1131407Y1493369D01*
X1118301D01*
X1110120Y1501550D01*
Y1524121D01*
X1112407Y1526408D01*
Y1529745D01*
X1114617Y1531955D01*
G01X1768041Y556537D02*
Y557549D01*
X1769992Y559500D01*
X1773417D01*
X1783240Y569323D01*
Y647169D01*
X1801821Y665750D01*
X1824990D01*
X1835920Y676680D01*
Y772180D01*
X1824790Y783310D01*
Y1289720D01*
X1760615Y1353895D01*
Y1428445D01*
X1745781Y1443279D01*
X1700188D01*
X1684794Y1458673D01*
X1394749D01*
X1375484Y1477938D01*
X1174439D01*
X1167085Y1485292D01*
X1137588D01*
X1130851Y1492029D01*
X1117517D01*
X1108490Y1501056D01*
Y1524771D01*
X1110966Y1527247D01*
Y1529736D01*
X1108747Y1531955D01*
G01Y1535805D02*
Y1531955D01*
G01Y1538955D02*
Y1540251D01*
X1109533Y1541037D01*
X1116505D01*
X1117665Y1539877D01*
G01X1109558Y1547661D02*
X1112529D01*
G01X1109522Y1551358D02*
Y1547697D01*
X1109558Y1547661D01*
G01X1113167Y1554508D02*
X1109522D01*
G01X1102075Y1639000D02*
Y1642500D01*
G01X1116166Y1642020D02*
X1113835D01*
X1107766Y1635951D01*
G01D02*
X1104195Y1632380D01*
Y1631610D01*
X1102791Y1630206D01*
Y1630123D01*
G01X1102598Y1634400D02*
Y1636185D01*
X1106016Y1639603D01*
X1107437D01*
X1111167Y1643333D01*
G01X1097000Y1629500D02*
X1097623Y1630123D01*
X1099641D01*
G01X1099448Y1634400D02*
X1097448D01*
X1096768Y1635080D01*
G01X1105500Y1643500D02*
X1106546Y1644546D01*
X1109047D01*
X1110458Y1645957D01*
X1116166D01*
G01X1102075Y1642500D02*
X1104500D01*
X1105500Y1643500D01*
G01X1109000Y1665425D02*
Y1661444D01*
X1109519Y1660925D01*
G01D02*
X1111387Y1659057D01*
Y1657782D01*
X1115338Y1653831D01*
X1116166D01*
G01X1098048Y1703764D02*
X1099489Y1702323D01*
Y1696029D01*
G01X1099108Y1691229D02*
X1099489Y1691610D01*
Y1696029D01*
G01X1098048Y1711244D02*
X1103489D01*
G01D02*
X1108289D01*
G01X1107021Y1721550D02*
X1103105D01*
X1101814Y1722841D01*
X1098514D01*
G01Y1718991D02*
X1107021D01*
G01X1129808Y52651D02*
Y53930D01*
X1126933Y56805D01*
X1124834D01*
G01X1119159Y388265D02*
X1124797D01*
X1128094Y391562D01*
X1131400D01*
G01X1119159Y380587D02*
X1124375D01*
X1128100Y376862D01*
G01X1138710Y370496D02*
X1142059Y373845D01*
Y380303D01*
X1139216Y383146D01*
X1119159D01*
G01X1127408Y386271D02*
X1126843Y385706D01*
X1119159D01*
G01X1111043Y471855D02*
X1112299Y470599D01*
X1118614D01*
G01X1111076Y464388D02*
X1112168Y465480D01*
X1118614D01*
G01Y475717D02*
X1113643D01*
X1111005Y478355D01*
G01X1111043Y485771D02*
X1115979Y480835D01*
X1118614D01*
G01X1116540Y651070D02*
X1157036D01*
X1234015Y728049D01*
Y770679D01*
X1233084Y771610D01*
Y772582D01*
G01X1112190Y651962D02*
X1132803Y672575D01*
X1170634D01*
X1228770Y730711D01*
Y772299D01*
X1233684Y777213D01*
X1235215D01*
G01X1121008Y766870D02*
X1125558D01*
G01X1121008Y770217D02*
X1125558D01*
G01X1123816Y1456373D02*
X1129846D01*
G01X1114117Y1538955D02*
X1118218Y1534854D01*
X1119131D01*
G01D02*
X1120001D01*
X1126745Y1541598D01*
Y1546733D01*
G01X1114617Y1531955D02*
Y1535305D01*
X1114117Y1535805D01*
G01X1117665Y1539877D02*
X1121063D01*
X1124186Y1543000D01*
Y1546733D01*
G01X1121626D02*
Y1551524D01*
X1118642Y1554508D01*
X1113167D01*
G01X1115005Y1573346D02*
Y1571447D01*
X1119067Y1567385D01*
Y1565237D01*
G01X1119459Y1556343D02*
X1112546Y1563256D01*
Y1581736D01*
X1113436Y1582626D01*
X1115005D01*
G01Y1579476D02*
Y1573346D01*
G01X1115027Y1593176D02*
X1115005Y1593154D01*
Y1587936D01*
G01Y1582626D02*
Y1587936D01*
G01X1111167Y1643333D02*
X1111822Y1643988D01*
X1116166D01*
G01X1112500Y1665425D02*
X1116000D01*
G01D02*
X1116481Y1664944D01*
Y1661631D01*
G01D02*
Y1660175D01*
X1118626Y1658030D01*
Y1656291D01*
G01X1128889Y1679853D02*
X1124487D01*
X1122610Y1677976D01*
G01X1128889Y1682412D02*
X1125662D01*
X1124091Y1683983D01*
G01X1111439Y1711244D02*
X1113948D01*
G01X1119361Y1719309D02*
Y1724109D01*
G01D02*
X1114501D01*
G01Y1721550D02*
Y1724109D01*
G01X1141901Y56691D02*
X1141684Y56474D01*
X1139092D01*
X1138385Y55767D01*
Y54086D01*
X1136981Y52682D01*
Y52599D01*
G01X1133831D02*
X1131471D01*
X1131419Y52651D01*
X1129808D01*
G01X1133063Y56512D02*
X1131195D01*
X1126902Y60805D01*
G01X1142144Y63186D02*
X1139181D01*
X1136213Y60218D01*
Y58297D01*
X1136122Y58206D01*
Y56603D01*
X1136213Y56512D01*
G01X1133330Y380533D02*
X1131771D01*
X1128100Y376862D01*
G01X1133330Y385698D02*
X1133238Y385606D01*
X1128073D01*
X1127408Y386271D01*
G01X1251177Y784488D02*
Y782210D01*
X1242798Y773831D01*
X1242114Y772180D01*
Y725464D01*
X1217945Y701295D01*
Y665157D01*
X1210716Y657928D01*
Y636141D01*
X1199820Y625245D01*
X1151246D01*
X1135374Y609373D01*
X1132855D01*
G01X1134567Y766870D02*
X1130017D01*
G01X1134567Y763524D02*
X1130017D01*
G01X1129846Y1459523D02*
X1133846D01*
G01D02*
X1137846D01*
G01D02*
X1143095D01*
G01X1134183Y1483926D02*
X1166555D01*
X1174680Y1475801D01*
X1375232D01*
X1428181Y1422852D01*
X1628640D01*
X1629628Y1423840D01*
Y1424466D01*
G01X1142284Y1558549D02*
Y1559337D01*
X1141359Y1560262D01*
X1138159D01*
X1137604Y1560817D01*
Y1561627D01*
G01D02*
Y1564568D01*
X1138331Y1565295D01*
G01Y1567395D02*
X1137755Y1567971D01*
Y1569543D01*
G01X1138480Y1576364D02*
Y1574096D01*
G01X1133070Y1584453D02*
X1137585D01*
X1140035Y1582003D01*
Y1577919D01*
X1138480Y1576364D01*
G01X1132168Y1626540D02*
Y1630557D01*
G01D02*
X1130437Y1632288D01*
Y1637591D01*
G01X1136097Y1626543D02*
Y1628671D01*
X1138456Y1631030D01*
Y1632280D01*
G01D02*
Y1640281D01*
X1136717Y1642020D01*
X1134866D01*
G01X1142350Y1659564D02*
X1136617Y1653831D01*
X1134866D01*
G01X1140117Y1665577D02*
X1138300Y1663760D01*
X1135398D01*
G01D02*
X1134467D01*
X1130437Y1659730D01*
Y1656291D01*
G01X1128889Y1677293D02*
X1131811D01*
X1133206Y1675898D01*
Y1675383D01*
G01X1148486Y58186D02*
X1142463D01*
X1141901Y57624D01*
Y56691D01*
G01X1148486Y63186D02*
X1142144D01*
G01X1147243Y74738D02*
X1142643D01*
G01X1148486Y68186D02*
X1151679Y71379D01*
Y72258D01*
G01X1150393Y74738D02*
Y74324D01*
X1151679Y73038D01*
Y72258D01*
G01X1157563Y453691D02*
X1156707D01*
X1153543Y456855D01*
X1148043D01*
G01D02*
X1144934D01*
X1143986Y457803D01*
X1140662D01*
G01X1157563Y449691D02*
X1155473D01*
X1152043Y453121D01*
G01D02*
X1145797D01*
X1143674Y455244D01*
X1140662D01*
G01Y462921D02*
X1148043D01*
G01D02*
X1156333D01*
X1157563Y461691D01*
G01Y457691D02*
X1155399Y459855D01*
X1152543D01*
G01D02*
X1149054D01*
X1148547Y460362D01*
X1140662D01*
G01Y475717D02*
X1144302D01*
X1150959Y482374D01*
X1152839D01*
G01X1140662Y468039D02*
X1148043D01*
G01D02*
X1155911D01*
X1157563Y469691D01*
G01X1140662Y465480D02*
X1152543D01*
G01D02*
X1157352D01*
X1157563Y465691D01*
G01X1162144Y487630D02*
X1160205Y485691D01*
X1152379D01*
X1144964Y478276D01*
X1140662D01*
G01X1152839Y482374D02*
X1153522Y481691D01*
X1157563D01*
G01X1158764Y489516D02*
X1156439Y487191D01*
X1150879D01*
X1144523Y480835D01*
X1140662D01*
G01X1141267Y500296D02*
Y502177D01*
X1144390Y505300D01*
X1263973D01*
X1295464Y536791D01*
G01X1151036Y501627D02*
X1262844D01*
X1295486Y534269D01*
G01X1150709Y766870D02*
X1153355D01*
X1153419Y766806D01*
X1155282D01*
G01X1150709Y770217D02*
X1155259D01*
G01X1155109Y1456295D02*
X1152780Y1453966D01*
Y1449727D01*
G01X1144118Y1453467D02*
Y1458500D01*
X1143095Y1459523D01*
G01X1159422Y1544575D02*
X1157810D01*
X1154828Y1547557D01*
X1143651D01*
X1142284Y1548924D01*
Y1553509D01*
G01X1158718Y1554023D02*
X1155612Y1550917D01*
X1154667D01*
X1153022Y1549272D01*
X1145308D01*
X1144253Y1550327D01*
Y1553509D01*
G01X1146221D02*
Y1551664D01*
X1147180Y1550705D01*
X1151099D01*
X1153702Y1553308D01*
X1155561D01*
X1157255Y1555002D01*
Y1556000D01*
G01X1143410Y1565312D02*
Y1567843D01*
X1142959Y1568294D01*
G01X1144253Y1558549D02*
Y1561175D01*
X1142639Y1562789D01*
G01D02*
X1143410Y1563560D01*
Y1565312D01*
G01X1146689Y1568275D02*
Y1565377D01*
X1146627Y1565315D01*
G01D02*
Y1564010D01*
X1147814Y1562823D01*
G01D02*
X1146221Y1561230D01*
Y1558549D01*
G01X1148190D02*
Y1559797D01*
X1149999Y1561606D01*
X1152049D01*
X1152549Y1562106D01*
Y1562311D01*
G01D02*
Y1565061D01*
X1152186Y1565424D01*
G01X1148190Y1553509D02*
Y1552873D01*
X1148673Y1552390D01*
X1150747D01*
X1154336Y1555979D01*
G01X1141916Y1573597D02*
X1145189Y1576870D01*
Y1579142D01*
X1150500Y1584453D01*
X1153542D01*
G01X1142959Y1570394D02*
Y1572554D01*
X1141916Y1573597D01*
G01X1148089Y1573555D02*
Y1578143D01*
X1149399Y1579453D01*
X1153542D01*
G01X1146689Y1570375D02*
Y1572155D01*
X1148089Y1573555D01*
G01X1144107Y1665491D02*
Y1661321D01*
X1142350Y1659564D01*
G01X1146467Y1679853D02*
X1149691D01*
X1152211Y1682373D01*
G01X1146467Y1677293D02*
X1151074D01*
X1152114Y1676253D01*
Y1672517D01*
G01X1178612Y57015D02*
X1178605Y57022D01*
X1175794D01*
X1174630Y58186D01*
X1169352D01*
G01X1178632Y52815D02*
X1169723D01*
X1169352Y53186D01*
G01X1178612Y61515D02*
X1178505Y61622D01*
X1175894D01*
X1174330Y63186D01*
X1169352D01*
G01X1171854Y76008D02*
X1171223Y76639D01*
X1166916D01*
X1166203Y77352D01*
G01D02*
Y80046D01*
X1163431Y82818D01*
G01X1204849Y103434D02*
X1202696D01*
X1198430Y107700D01*
X1177753D01*
X1163431Y93378D01*
Y82818D01*
G01X1155268Y209835D02*
Y212344D01*
G01X1173858Y207205D02*
X1166886D01*
X1164256Y209835D01*
X1155268D01*
G01Y204835D02*
Y207344D01*
G01Y204835D02*
X1163228D01*
X1166912Y201151D01*
X1180346D01*
X1183858Y204663D01*
Y207205D01*
G01X1160713Y453691D02*
X1163781D01*
X1169631Y447841D01*
G01X1178340Y447734D02*
Y446734D01*
X1176606Y445000D01*
X1171000D01*
X1169631Y446369D01*
Y447841D01*
G01X1160713Y449691D02*
X1162281D01*
X1169631Y442341D01*
G01X1178340Y442234D02*
Y441234D01*
X1177041Y439935D01*
X1172037D01*
X1169631Y442341D01*
G01Y458841D02*
X1172127Y456345D01*
X1176451D01*
X1178340Y458234D01*
Y458734D01*
G01X1160713Y461691D02*
X1166781D01*
X1169631Y458841D01*
G01X1160713Y457691D02*
X1165281D01*
X1169631Y453341D01*
G01X1178254Y453142D02*
Y452148D01*
X1176721Y450615D01*
X1172357D01*
X1169631Y453341D01*
G01X1178340Y467165D02*
X1172307D01*
X1169631Y469841D01*
G01X1160713Y469691D02*
X1160863Y469841D01*
X1169631D01*
G01X1178340Y461615D02*
X1172357D01*
X1169631Y464341D01*
G01X1160713Y465691D02*
X1168281D01*
X1169631Y464341D01*
G01Y481691D02*
X1169497D01*
X1166740Y478934D01*
X1160320D01*
X1157563Y481691D01*
G01X1165807Y575602D02*
X1167760Y577555D01*
X1170238D01*
X1172107Y579424D01*
Y580602D01*
G01X1165850Y592673D02*
Y590927D01*
X1167256Y589521D01*
X1168996D01*
X1172167Y586350D01*
Y584622D01*
G01X1164268Y766870D02*
X1159718D01*
G01X1164268Y763524D02*
X1159718D01*
G01X1168037Y1445000D02*
X1163422D01*
G01X1160163Y1448740D02*
Y1454197D01*
X1160200Y1454234D01*
G01D02*
X1158139Y1456295D01*
X1155109D01*
G01X1173261Y1543800D02*
Y1544135D01*
X1170082Y1547314D01*
X1169035D01*
G01X1159422Y1544575D02*
Y1545647D01*
X1159970Y1546195D01*
X1163485D01*
G01X1161492Y1551175D02*
X1160454D01*
X1159140Y1552489D01*
Y1553601D01*
X1158718Y1554023D01*
G01X1174261Y1551040D02*
Y1551987D01*
X1173542Y1552706D01*
X1172224D01*
X1169178Y1553968D01*
X1168090D01*
X1166691Y1555367D01*
G01X1166873Y1563550D02*
X1168261D01*
X1169311Y1564600D01*
X1170423D01*
G01X1166873Y1563550D02*
Y1561431D01*
G01Y1574350D02*
X1169273D01*
X1170423Y1575500D01*
G01X1166873Y1571050D02*
X1170373D01*
X1170423Y1571000D01*
G01X1159688Y1665427D02*
Y1663152D01*
G01X1174187Y1662159D02*
Y1664176D01*
X1170269Y1668094D01*
X1162355D01*
X1159688Y1665427D01*
G01X1169098Y1666278D02*
Y1662248D01*
X1169187Y1662159D01*
G01X1163688Y1663152D02*
X1162610D01*
X1162109Y1663653D01*
Y1665513D01*
X1162874Y1666278D01*
X1169098D01*
G01X1159688Y1661052D02*
Y1659859D01*
X1158343Y1658514D01*
G01X1163688Y1661052D02*
X1165806Y1658934D01*
G01X1178612Y57015D02*
Y57540D01*
X1180362Y59290D01*
X1187206D01*
X1187374Y59122D01*
G01X1178632Y52815D02*
X1180405Y51042D01*
X1185684D01*
X1187214Y52572D01*
G01X1178612Y61515D02*
Y64040D01*
X1179694Y65122D01*
X1186734D01*
G01X1183354Y82665D02*
Y81232D01*
X1182015Y79893D01*
X1179047D01*
X1176972Y77818D01*
Y76008D01*
G01X1182766Y95864D02*
Y92374D01*
X1180777Y90385D01*
G01D02*
X1183354Y87808D01*
Y82665D01*
G01X1171854Y83488D02*
Y89556D01*
G01D02*
Y93556D01*
G01X1196187Y98316D02*
X1193266D01*
X1190814Y95864D01*
X1182766D01*
G01X1179616D02*
X1172552D01*
X1171854Y95166D01*
Y93556D01*
G01X1179616Y95864D02*
Y100129D01*
X1180280Y100793D01*
G01D02*
X1182101D01*
X1183200Y99694D01*
X1185012D01*
G01X1172000Y427425D02*
Y401197D01*
X1185197Y388000D01*
X1255724D01*
X1258724Y385000D01*
X1274000D01*
G01X1176000Y427425D02*
Y405488D01*
X1174031Y403519D01*
G01X1180000Y427425D02*
Y423000D01*
X1181000Y422000D01*
Y402500D01*
G01X1176000Y430575D02*
Y436500D01*
G01X1172000Y430575D02*
X1176000D01*
G01X1180000D02*
Y436000D01*
G01X1184000Y429000D02*
X1182501D01*
X1180926Y430575D01*
X1180000D01*
G01X1184000Y425850D02*
X1200650D01*
X1203145Y423355D01*
Y422761D01*
X1199236Y418852D01*
Y418258D01*
X1199795Y417699D01*
X1200389D01*
X1204298Y421608D01*
X1204892D01*
X1205451Y421049D01*
Y420455D01*
X1201542Y416546D01*
Y415952D01*
X1202101Y415393D01*
X1202695D01*
X1206604Y419302D01*
X1207198D01*
X1207757Y418743D01*
Y418149D01*
X1203848Y414240D01*
Y413646D01*
X1204407Y413087D01*
X1205001D01*
X1208910Y416996D01*
X1209504D01*
X1210063Y416437D01*
Y415843D01*
X1206154Y411934D01*
Y411340D01*
X1206713Y410781D01*
X1207307D01*
X1211216Y414690D01*
X1211810D01*
X1234500Y392000D01*
X1256000D01*
X1256500Y392500D01*
X1258500D01*
G01X1180849Y461615D02*
X1178340D01*
G01Y472740D02*
Y473491D01*
X1186040Y481191D01*
Y481691D01*
G01X1180849Y464765D02*
Y472259D01*
X1188080Y479490D01*
X1191251D01*
X1193040Y481279D01*
Y481691D01*
G01X1178340Y469590D02*
Y467165D01*
G01X1185672Y579369D02*
X1185289D01*
X1182950Y577030D01*
G01X1178000Y572602D02*
X1175000Y575602D01*
X1172107D01*
G01X1185672Y581338D02*
X1183067D01*
X1179136Y577407D01*
X1177336D01*
G01X1172107Y580602D02*
X1174141D01*
X1177336Y577407D01*
G01X1185672Y585275D02*
X1185078D01*
X1182594Y587759D01*
G01X1172150Y592673D02*
X1178000D01*
G01X1178536Y584307D02*
X1172482D01*
X1172167Y584622D01*
G01X1185672Y583306D02*
X1184177D01*
X1183176Y584307D01*
X1178536D01*
G01X1180410Y766870D02*
X1184960D01*
G01X1180410Y770217D02*
X1184960D01*
G01X1184175Y1433000D02*
Y1435600D01*
G01X1188025Y1433000D02*
X1184175D01*
G01X1174261Y1551040D02*
X1177161D01*
G01D02*
Y1549839D01*
X1177770Y1549230D01*
X1182521D01*
X1183296Y1550005D01*
Y1552121D01*
X1183982Y1552807D01*
X1187330D01*
G01Y1550445D02*
X1186576D01*
X1183934Y1547803D01*
Y1547248D01*
X1182296Y1545610D01*
X1177781D01*
X1177161Y1546230D01*
Y1547420D01*
G01D02*
X1174053D01*
G01X1177161Y1543800D02*
Y1542522D01*
X1177992Y1541691D01*
X1181827D01*
X1184945Y1544809D01*
Y1547568D01*
X1186641Y1549264D01*
X1189376D01*
G01X1173261Y1543800D02*
X1177161D01*
G01X1187330Y1564618D02*
X1185002D01*
X1181620Y1568000D01*
X1175773D01*
G01X1189376Y1563437D02*
X1183764D01*
X1183015Y1564186D01*
X1176959D01*
X1175773Y1563000D01*
G01D02*
X1174428Y1564345D01*
Y1565895D01*
X1172523Y1567800D01*
G01X1170423Y1564600D02*
Y1567800D01*
G01X1189376Y1565799D02*
X1185772D01*
X1182274Y1569297D01*
X1179476D01*
X1175773Y1573000D01*
G01D02*
Y1575731D01*
X1174534Y1576970D01*
X1171171D01*
X1170423Y1576222D01*
Y1575500D01*
G01X1175773Y1568000D02*
X1174310Y1569463D01*
X1171449D01*
X1170423Y1570489D01*
Y1571000D01*
G01X1174187Y1682631D02*
X1173500Y1683318D01*
Y1688501D01*
X1175828Y1690829D01*
X1181660D01*
G01D02*
X1185176D01*
X1185676Y1691329D01*
Y1692980D01*
G01X1187374Y59122D02*
X1190705D01*
X1192812Y57015D01*
G01X1187214Y52572D02*
X1192489D01*
X1192732Y52815D01*
G01X1185913Y75185D02*
Y82665D01*
G01X1195488Y83175D02*
Y82514D01*
X1191575Y78601D01*
X1189741D01*
X1188472Y77332D01*
Y75185D01*
G01X1186734Y65122D02*
X1189105D01*
X1192712Y61515D01*
G01X1185913Y82665D02*
Y87125D01*
G01D02*
Y91125D01*
G01X1195488Y83175D02*
Y87975D01*
G01X1185913Y91125D02*
Y93634D01*
G01X1196187Y103434D02*
X1188752D01*
X1185012Y99694D01*
G01X1205587Y164987D02*
X1203651Y163051D01*
X1197213D01*
X1195277Y164987D01*
G01X1205587Y160987D02*
X1202651Y158051D01*
X1198213D01*
X1195277Y160987D01*
G01X1191502Y436202D02*
Y432202D01*
G01X1205182Y436875D02*
X1200900D01*
X1196227Y432202D01*
G01X1191502D02*
X1196227D01*
G01Y448202D02*
X1191502D01*
G01X1205182Y446875D02*
X1197554D01*
X1196227Y448202D01*
G01X1191502D02*
Y452202D01*
G01X1196227Y440202D02*
X1191502D01*
G01X1205182Y441875D02*
X1197900D01*
X1196227Y440202D01*
G01X1191502D02*
Y444202D01*
G01Y460202D02*
Y461818D01*
X1192257Y462573D01*
X1200631D01*
X1203002Y460202D01*
G01X1203138Y470376D02*
X1200661Y472853D01*
X1192157D01*
X1191622Y472318D01*
Y470392D01*
G01X1191562Y465272D02*
Y467118D01*
X1192097Y467653D01*
X1200681D01*
X1203062Y465272D01*
G01X1190712Y579369D02*
X1191294D01*
X1191926Y578737D01*
Y574648D01*
X1191087Y573809D01*
G01X1190712Y581338D02*
X1191647D01*
X1194831Y578154D01*
X1199370D01*
G01X1195236Y581407D02*
X1198501D01*
X1199537Y582443D01*
G01X1190712Y583306D02*
X1193930D01*
X1195236Y582000D01*
Y581407D01*
G01X1256785Y761015D02*
X1255622D01*
X1254432Y759825D01*
Y705408D01*
X1225302Y676278D01*
Y607814D01*
X1214839Y597351D01*
X1204375D01*
X1199392Y592368D01*
Y590500D01*
G01X1199537Y587443D02*
X1196173D01*
X1195336Y586606D01*
G01D02*
X1192331D01*
X1191000Y585275D01*
X1190712D01*
G01X1199539Y638492D02*
Y644441D01*
X1208369Y653271D01*
Y658218D01*
X1216279Y666128D01*
Y701484D01*
X1240551Y725756D01*
Y772301D01*
X1241797Y775309D01*
X1247157Y780669D01*
Y782381D01*
X1248130Y783354D01*
G01X1197039Y638492D02*
Y640162D01*
X1198022Y641145D01*
Y645070D01*
X1206852Y653900D01*
Y658271D01*
X1214762Y666181D01*
Y702113D01*
X1239111Y726462D01*
Y772295D01*
X1241259Y777480D01*
X1243207Y779428D01*
G01X1241057Y782278D02*
Y780707D01*
X1237771Y772773D01*
Y727200D01*
X1213293Y702722D01*
Y666282D01*
X1205383Y658372D01*
Y654509D01*
X1196553Y645679D01*
Y642176D01*
X1194539Y640162D01*
Y638492D01*
G01X1236100Y773844D02*
Y773380D01*
X1236201Y773279D01*
Y727683D01*
X1211842Y703324D01*
Y666402D01*
X1203932Y658492D01*
Y655111D01*
X1195102Y646281D01*
Y643225D01*
X1192039Y640162D01*
Y638492D01*
G01X1193969Y766870D02*
X1188805D01*
G01X1193969Y763524D02*
X1189419D01*
G01X1276437Y885159D02*
Y843886D01*
X1229478Y796927D01*
Y795020D01*
X1216388Y781930D01*
G01X1276787Y889588D02*
X1273757Y886558D01*
Y845072D01*
X1217308Y788623D01*
X1213720D01*
G01X1276593Y901405D02*
X1275793D01*
X1264987Y890599D01*
Y854423D01*
X1245916Y835352D01*
Y832135D01*
X1219136Y805355D01*
X1215002D01*
G01X1276531Y908935D02*
X1275073D01*
X1259167Y893029D01*
Y856851D01*
X1221057Y818741D01*
X1215002D01*
G01X1275577Y904705D02*
X1275293D01*
X1262307Y891719D01*
Y855535D01*
X1226904Y820132D01*
Y816915D01*
X1221044Y811055D01*
X1220450D01*
X1220124Y811381D01*
X1219530D01*
X1219013Y810864D01*
Y810270D01*
X1219339Y809944D01*
Y809350D01*
X1218690Y808701D01*
X1215002D01*
G01X1277011Y911805D02*
X1274151D01*
X1256487Y894141D01*
Y862835D01*
X1253258Y855042D01*
X1230301Y832085D01*
X1227634Y830303D01*
X1215879Y825434D01*
X1213720D01*
G01X1275471Y922065D02*
X1271825D01*
X1247717Y897957D01*
Y866361D01*
X1232300Y850944D01*
X1228901D01*
X1220123Y842166D01*
X1218863D01*
X1218443Y841746D01*
Y839518D01*
X1218023Y839098D01*
X1217292D01*
X1216872Y839518D01*
Y841746D01*
X1216452Y842166D01*
X1215002D01*
G01X1275601Y925525D02*
X1271493D01*
X1245037Y899069D01*
Y870873D01*
X1221974Y847810D01*
X1221380D01*
X1220992Y848198D01*
X1220398D01*
X1219881Y847681D01*
Y847087D01*
X1220269Y846699D01*
Y846105D01*
X1219676Y845512D01*
X1215002D01*
G01X1275141Y929015D02*
X1270541D01*
X1241897Y900371D01*
Y872240D01*
X1225209Y855552D01*
X1215002D01*
G01X1275101Y931835D02*
X1269569D01*
X1239217Y901483D01*
Y874674D01*
X1230286Y865743D01*
X1221838Y862245D01*
X1213720D01*
G01X1275231Y942225D02*
X1267373D01*
X1230447Y905299D01*
Y889844D01*
X1219580Y878977D01*
X1218409D01*
X1217949Y878517D01*
Y877615D01*
X1217489Y877155D01*
X1216838D01*
X1216378Y877615D01*
Y878517D01*
X1215918Y878977D01*
X1215002D01*
G01X1275221Y944915D02*
X1266271D01*
X1227767Y906411D01*
Y895088D01*
X1219861Y887182D01*
X1219267D01*
X1218031Y888418D01*
X1217437D01*
X1216920Y887901D01*
Y887307D01*
X1218156Y886071D01*
Y885477D01*
X1217639Y884960D01*
X1217045D01*
X1215809Y886196D01*
X1215215D01*
X1214698Y885679D01*
Y885085D01*
X1215934Y883849D01*
Y883255D01*
X1215002Y882323D01*
G01X1275241Y948065D02*
X1264979D01*
X1224627Y907713D01*
Y901111D01*
X1217916Y894400D01*
Y892697D01*
X1217582Y892363D01*
X1215002D01*
G01X1276438Y950788D02*
X1263458D01*
X1221947Y909277D01*
Y906137D01*
X1214866Y899056D01*
X1213720D01*
G01X1275291Y959805D02*
X1253868D01*
X1227272Y933209D01*
Y932615D01*
X1227736Y932151D01*
Y931557D01*
X1227219Y931040D01*
X1226625D01*
X1226161Y931504D01*
X1225567D01*
X1225050Y930987D01*
Y930393D01*
X1225514Y929929D01*
Y929335D01*
X1224997Y928818D01*
X1224403D01*
X1223939Y929282D01*
X1223345D01*
X1222828Y928765D01*
Y928171D01*
X1223292Y927707D01*
Y927113D01*
X1222775Y926596D01*
X1222181D01*
X1221717Y927060D01*
X1221123D01*
X1220437Y926374D01*
Y924233D01*
X1217391Y921187D01*
Y917525D01*
X1215654Y915788D01*
X1215002D01*
G01X1276941Y962495D02*
X1252765D01*
X1233921Y943651D01*
X1231159D01*
X1219031Y931523D01*
Y928761D01*
X1214711Y924441D01*
Y920303D01*
X1214202Y919794D01*
G01X1276151Y965705D02*
X1248771D01*
X1234420Y951354D01*
X1233826D01*
X1233567Y951613D01*
X1232973Y951612D01*
X1232456Y951095D01*
Y950501D01*
X1232715Y950242D01*
X1232716Y949650D01*
X1215891Y932825D01*
Y930063D01*
X1215002Y929174D01*
G01X1277111Y968855D02*
X1246457D01*
X1231778Y954176D01*
X1230018D01*
X1222172Y946330D01*
Y943168D01*
X1214871Y935867D01*
X1213720D01*
G01X1275281Y979745D02*
X1270397D01*
X1269427Y978775D01*
X1232770D01*
X1229705Y975710D01*
Y972968D01*
X1227759Y971022D01*
X1227165D01*
X1226300Y971887D01*
X1225706D01*
X1225189Y971370D01*
Y970776D01*
X1226054Y969911D01*
Y969317D01*
X1219067Y962330D01*
Y956664D01*
X1215002Y952599D01*
G01X1282984Y985906D02*
X1281605Y987285D01*
X1267955D01*
X1266948Y986278D01*
X1227092D01*
X1221667Y980853D01*
Y978518D01*
X1218897Y975748D01*
Y971200D01*
X1215002Y967305D01*
G01X1276571Y982515D02*
X1269375D01*
X1268315Y981455D01*
X1240860D01*
X1237907Y982678D01*
X1228585D01*
X1225267Y979360D01*
Y977025D01*
X1222497Y974255D01*
Y969552D01*
X1216387Y963442D01*
Y958362D01*
X1214660Y956635D01*
G01X1275316Y998500D02*
X1274321Y999495D01*
X1268583D01*
X1261916Y992828D01*
X1224729D01*
X1215387Y983486D01*
Y981138D01*
X1214384Y980135D01*
G01X1276366Y1001250D02*
X1275441Y1002175D01*
X1267471D01*
X1260804Y995508D01*
X1220737D01*
X1215396Y990167D01*
Y987768D01*
X1214351Y986723D01*
G01X1278061Y993975D02*
X1277031Y992945D01*
X1265825D01*
X1262758Y989878D01*
X1225572D01*
X1218067Y982373D01*
Y980012D01*
X1215297Y977242D01*
Y973908D01*
G01X1273795Y1007711D02*
X1269215D01*
X1259692Y998188D01*
X1242329D01*
X1239569Y1000948D01*
X1221998D01*
X1214466Y993416D01*
G01X1275741Y1033006D02*
X1262412D01*
X1259751Y1035667D01*
X1243081D01*
X1236981Y1029567D01*
X1215002D01*
G01X1275741Y1035763D02*
X1263447D01*
X1260863Y1038347D01*
X1241931D01*
X1239844Y1036260D01*
X1215002D01*
G01X1275741Y1038443D02*
X1264559D01*
X1261975Y1041027D01*
X1229432D01*
X1227506Y1042953D01*
X1215002D01*
G01X1278111Y1048665D02*
X1275759D01*
X1273706Y1046612D01*
X1233310D01*
X1226234Y1053688D01*
X1217141D01*
X1215737Y1055092D01*
Y1058950D01*
X1215002Y1059685D01*
G01X1277211Y1041485D02*
X1265309D01*
X1263087Y1043707D01*
X1232419D01*
X1227319Y1048807D01*
X1215840D01*
X1215002Y1049645D01*
G01X1275692Y1061435D02*
X1273224D01*
X1268267Y1056478D01*
X1233040D01*
X1231850Y1057668D01*
X1231849Y1058262D01*
X1232318Y1058731D01*
Y1059325D01*
X1231800Y1059843D01*
X1231208Y1059842D01*
X1230739Y1059373D01*
X1230145D01*
X1229628Y1059890D01*
X1229627Y1060484D01*
X1230096Y1060953D01*
Y1061547D01*
X1229578Y1062065D01*
X1228986Y1062064D01*
X1228517Y1061595D01*
X1227923D01*
X1219513Y1070005D01*
X1217972D01*
X1217438Y1070539D01*
Y1071133D01*
X1218158Y1071853D01*
Y1072447D01*
X1217641Y1072964D01*
X1217047D01*
X1216327Y1072244D01*
X1215733D01*
X1214906Y1073071D01*
G01X1274910Y1064115D02*
X1272112D01*
X1267155Y1059158D01*
X1237542D01*
X1216935Y1079765D01*
X1215220D01*
G01X1275180Y1073185D02*
X1249513D01*
X1249093Y1072765D01*
Y1071558D01*
X1248673Y1071138D01*
X1247942D01*
X1247522Y1071558D01*
Y1072765D01*
X1247102Y1073185D01*
X1246371D01*
X1245951Y1072765D01*
Y1071558D01*
X1245531Y1071138D01*
X1244800D01*
X1244380Y1071558D01*
Y1072765D01*
X1243960Y1073185D01*
X1240057D01*
X1216746Y1096496D01*
X1215220D01*
G01X1275231Y1076235D02*
X1242495D01*
X1215541Y1103189D01*
X1215220D01*
G01X1275201Y1079565D02*
X1245917D01*
X1215600Y1109882D01*
X1215220D01*
G01X1276869Y1082245D02*
X1248795D01*
X1217857Y1113183D01*
X1217263Y1113184D01*
X1216710Y1112631D01*
X1216116D01*
X1215598Y1113149D01*
X1215599Y1113741D01*
X1216152Y1114294D01*
Y1114888D01*
X1215174Y1115866D01*
G01X1275221Y1099310D02*
X1259336D01*
X1225750Y1132896D01*
Y1139980D01*
X1218226Y1147504D01*
X1215732D01*
G01X1276002Y1092123D02*
X1256327D01*
X1223120Y1125330D01*
Y1126286D01*
X1216099Y1133307D01*
X1215220D01*
G01X1275201Y1096081D02*
X1258123D01*
X1214864Y1139340D01*
G01X1276342Y1101990D02*
X1260448D01*
X1228430Y1134008D01*
Y1140822D01*
X1229332Y1141724D01*
Y1144634D01*
X1222751Y1151215D01*
X1221044D01*
X1220013Y1150184D01*
X1216903D01*
X1214570Y1152517D01*
G01X1275406Y1110963D02*
X1266065D01*
X1239124Y1137904D01*
Y1151946D01*
X1222219Y1168851D01*
X1216269D01*
X1215220Y1169900D01*
G01X1275001Y1115535D02*
X1265285D01*
X1241804Y1139016D01*
Y1153092D01*
X1221136Y1173760D01*
X1215220Y1176211D01*
G01X1275201Y1118710D02*
X1266552D01*
X1244975Y1140287D01*
Y1156967D01*
X1218438Y1183504D01*
X1215220D01*
G01X1275426Y1121390D02*
X1267664D01*
X1247655Y1141399D01*
Y1160075D01*
X1220104Y1187626D01*
X1219510D01*
X1218082Y1186198D01*
X1217490Y1186197D01*
X1216972Y1186715D01*
Y1187309D01*
X1218400Y1188737D01*
X1218399Y1189331D01*
X1217533Y1190197D01*
X1215220D01*
G01X1275201Y1130565D02*
X1271163D01*
X1256530Y1145198D01*
Y1169452D01*
X1222933Y1203049D01*
X1221180Y1203046D01*
X1220780Y1203446D01*
Y1204040D01*
X1221056Y1204316D01*
Y1204910D01*
X1220539Y1205427D01*
X1219945D01*
X1219669Y1205151D01*
X1219075D01*
X1218124Y1206102D01*
Y1207648D01*
X1217704Y1208068D01*
X1216973D01*
X1216553Y1207648D01*
Y1207349D01*
X1216133Y1206929D01*
X1215221D01*
X1215220Y1206930D01*
G01X1275301Y1133765D02*
X1271755D01*
X1259210Y1146310D01*
Y1171750D01*
X1217338Y1213622D01*
X1215220D01*
G01X1275301Y1136965D02*
X1273301D01*
X1262350Y1147916D01*
Y1174252D01*
X1231648Y1204954D01*
Y1209398D01*
X1220731Y1220315D01*
X1215220D01*
G01X1275301Y1140165D02*
X1274101D01*
X1265030Y1149236D01*
Y1175364D01*
X1243664Y1196730D01*
Y1201174D01*
X1232447Y1212391D01*
Y1213497D01*
X1231889Y1214055D01*
X1230783D01*
X1230225Y1214613D01*
Y1215719D01*
X1229667Y1216277D01*
X1228561D01*
X1228003Y1216835D01*
Y1217941D01*
X1227445Y1218499D01*
X1226339D01*
X1225781Y1219057D01*
Y1220163D01*
X1225223Y1220721D01*
X1224117D01*
X1223559Y1221279D01*
Y1222385D01*
X1223001Y1222943D01*
X1221895D01*
X1221337Y1223501D01*
Y1224607D01*
X1220779Y1225165D01*
X1219673D01*
X1217830Y1227008D01*
X1215220D01*
G01X1275211Y1152775D02*
Y1184173D01*
X1231719Y1227665D01*
Y1228315D01*
X1232725Y1229321D01*
Y1229971D01*
X1232264Y1230432D01*
X1231614D01*
X1230608Y1229426D01*
X1229958D01*
X1229295Y1230089D01*
Y1234533D01*
X1220088Y1243740D01*
X1215220D01*
G01X1278001Y1155427D02*
Y1184731D01*
X1274545Y1193075D01*
X1251937Y1215683D01*
X1251287D01*
X1250750Y1215146D01*
X1250100D01*
X1249639Y1215607D01*
Y1216257D01*
X1250176Y1216794D01*
Y1217444D01*
X1249715Y1217905D01*
X1249065D01*
X1248528Y1217368D01*
X1247878D01*
X1247417Y1217829D01*
Y1218479D01*
X1247954Y1219016D01*
Y1219666D01*
X1247493Y1220127D01*
X1246843D01*
X1246306Y1219590D01*
X1245656D01*
X1245195Y1220051D01*
Y1220701D01*
X1245732Y1221238D01*
Y1221888D01*
X1217187Y1250433D01*
X1215220D01*
G01X1196925Y1396500D02*
X1194296D01*
G01D02*
X1191075D01*
G01X1196925Y1401000D02*
X1194000D01*
G01D02*
X1191075D01*
G01X1196925Y1405500D02*
X1194366D01*
G01D02*
X1191075D01*
G01X1196925Y1410000D02*
X1193929D01*
G01D02*
X1191075D01*
G01X1194000Y1424000D02*
X1196925D01*
G01X1191175Y1428500D02*
Y1433000D01*
G01X1200075D02*
X1198075Y1431000D01*
X1193675D01*
X1191175Y1428500D01*
G01X1191075Y1437500D02*
X1194000D01*
G01X1196925D02*
X1194000D01*
G01X1196925Y1442500D02*
X1194000D01*
G01X1196925Y1447500D02*
X1194000D01*
G01X1186618Y1546218D02*
X1188692D01*
X1189376Y1546902D01*
G01X1184959Y1551121D02*
X1185954D01*
X1186459Y1551626D01*
X1189376D01*
G01Y1553988D02*
X1185984D01*
X1185360Y1554612D01*
G01X1189376Y1568162D02*
X1185942D01*
X1185406Y1568698D01*
G01X1187330Y1569343D02*
X1185775Y1570898D01*
X1185406D01*
G01X1195171Y1685390D02*
Y1689259D01*
X1195762Y1689850D01*
G01X1192612Y1685390D02*
Y1689850D01*
G01X1195171Y1677910D02*
X1197730D01*
G01D02*
Y1677102D01*
X1196988Y1676360D01*
Y1673050D01*
G01D02*
X1192930D01*
G01X1196462Y1693850D02*
Y1690550D01*
X1195762Y1689850D01*
G01X1196462Y1697850D02*
Y1693850D01*
G01X1197612Y1703334D02*
X1197396Y1703118D01*
Y1698784D01*
X1196462Y1697850D01*
G01X1192612Y1693850D02*
Y1689850D01*
G01Y1697850D02*
Y1693850D01*
G01Y1703334D02*
X1191800Y1702522D01*
Y1698662D01*
X1192612Y1697850D01*
G01X1194267Y1707143D02*
X1189407D01*
G01X1194267Y1709702D02*
Y1707143D01*
G01X1189407Y1711943D02*
Y1707143D01*
G01X1194314Y1723702D02*
Y1721143D01*
G01X1189454Y1723702D02*
X1194314D01*
G01X1199902Y1731803D02*
X1194502D01*
X1189454Y1726755D01*
Y1723702D01*
G01X1205929Y86872D02*
X1207030Y85771D01*
X1215581D01*
G01X1284764Y95379D02*
Y97695D01*
X1283159Y99300D01*
X1271211D01*
X1262346Y108165D01*
X1214500D01*
X1209769Y103434D01*
X1204849D01*
G01X1206580Y94846D02*
X1210006D01*
G01X1204849Y98316D02*
X1203573D01*
X1203073Y97816D01*
Y95831D01*
X1204058Y94846D01*
X1206580D01*
G01X1213107Y161551D02*
X1216273Y164717D01*
X1220178D01*
G01X1205587Y164987D02*
X1209023Y161551D01*
X1213107D01*
G01X1210607Y157051D02*
X1212107D01*
X1217214Y162158D01*
X1220178D01*
G01X1205587Y160987D02*
X1209523Y157051D01*
X1210607D01*
G01X1202437Y177187D02*
X1200037D01*
G01X1220178Y174954D02*
X1214404D01*
X1212888Y176470D01*
G01D02*
X1212171Y177187D01*
X1205587D01*
G01X1209059Y181187D02*
X1213093D01*
X1216767Y177513D01*
X1220178D01*
G01X1210607Y166051D02*
X1211832Y167276D01*
X1220178D01*
G01X1205618Y188942D02*
Y187218D01*
X1205587Y185187D01*
G01D02*
X1212182D01*
G01D02*
X1212736D01*
X1217851Y180072D01*
X1220178D01*
G01X1202437Y181187D02*
X1200012D01*
G01X1205587D02*
X1209059D01*
G01X1214094Y269008D02*
Y274108D01*
G01Y277848D02*
Y282948D01*
G01X1202508Y341424D02*
Y334620D01*
X1200161Y332273D01*
Y307847D01*
X1212941Y295067D01*
X1219093D01*
X1222094Y292066D01*
G01X1207447Y341381D02*
Y334036D01*
X1202416Y329005D01*
Y309377D01*
X1210048Y301745D01*
X1225140D01*
X1228175Y298710D01*
Y289867D01*
X1230094Y287948D01*
G01X1205625Y313758D02*
Y311893D01*
X1208574Y308944D01*
X1254801D01*
X1258877Y304868D01*
Y291165D01*
X1262094Y287948D01*
G01X1302069Y303184D02*
X1286855Y318398D01*
X1214992D01*
X1210698Y314104D01*
Y313671D01*
G01X1217866Y460376D02*
X1209937D01*
G01X1203002Y460202D02*
X1203176Y460376D01*
X1209937D01*
G01Y470376D02*
X1203138D01*
G01X1217866D02*
X1209937D01*
G01X1217866Y465376D02*
X1209937D01*
G01X1203062Y465272D02*
X1203166Y465376D01*
X1209937D01*
G01X1263706Y761015D02*
X1265026D01*
X1266307Y759734D01*
Y707807D01*
X1232000Y673500D01*
Y604554D01*
X1213432Y585986D01*
X1208733D01*
G01X1263706Y754715D02*
X1261500Y752509D01*
Y706000D01*
X1229847Y674347D01*
Y605847D01*
X1212400Y588400D01*
X1206191D01*
G01X1256785Y754715D02*
X1259075Y752425D01*
Y707005D01*
X1227422Y675352D01*
Y606852D01*
X1215698Y595128D01*
X1206659D01*
X1205679Y594148D01*
G01X1210111Y766870D02*
X1214661D01*
G01X1214841Y772277D02*
Y772253D01*
X1212805Y770217D01*
X1210111D01*
G01X1277777Y882481D02*
Y843330D01*
X1275756Y841309D01*
Y840659D01*
X1276377Y840038D01*
Y839388D01*
X1275916Y838927D01*
X1275266D01*
X1274645Y839548D01*
X1273995D01*
X1273534Y839087D01*
Y838437D01*
X1274155Y837816D01*
Y837166D01*
X1273694Y836705D01*
X1273044D01*
X1272423Y837326D01*
X1271773D01*
X1271312Y836865D01*
Y836215D01*
X1271933Y835594D01*
Y834944D01*
X1271472Y834483D01*
X1270822D01*
X1270201Y835104D01*
X1269551D01*
X1269090Y834643D01*
Y833993D01*
X1269711Y833372D01*
Y832722D01*
X1269250Y832261D01*
X1268600D01*
X1267979Y832882D01*
X1267329D01*
X1266868Y832421D01*
Y831771D01*
X1267489Y831150D01*
Y830500D01*
X1267028Y830039D01*
X1266378D01*
X1265757Y830660D01*
X1265107D01*
X1264646Y830199D01*
Y829549D01*
X1265267Y828928D01*
Y828278D01*
X1264806Y827817D01*
X1264156D01*
X1263535Y828438D01*
X1262885D01*
X1262424Y827977D01*
Y827327D01*
X1263045Y826706D01*
Y826056D01*
X1262584Y825595D01*
X1261934D01*
X1261313Y826216D01*
X1260663D01*
X1230818Y796371D01*
Y794464D01*
X1213264Y776910D01*
X1210111D01*
G01X1277844Y888668D02*
X1275097Y885921D01*
Y844516D01*
X1227761Y797180D01*
Y796548D01*
X1228138Y796171D01*
Y795577D01*
X1227621Y795060D01*
X1227027D01*
X1226650Y795437D01*
X1226056D01*
X1225539Y794920D01*
Y794326D01*
X1225916Y793949D01*
Y793355D01*
X1225399Y792838D01*
X1224805D01*
X1224428Y793215D01*
X1223834D01*
X1223317Y792698D01*
Y792104D01*
X1223694Y791727D01*
Y791133D01*
X1223177Y790616D01*
X1222583D01*
X1222206Y790993D01*
X1221612D01*
X1221095Y790476D01*
Y789882D01*
X1221472Y789505D01*
Y788911D01*
X1220955Y788394D01*
X1220361D01*
X1219984Y788771D01*
X1219390D01*
X1218873Y788254D01*
Y787660D01*
X1219250Y787283D01*
Y786689D01*
X1218733Y786172D01*
X1218139D01*
X1217762Y786549D01*
X1217168D01*
X1216651Y786032D01*
Y785438D01*
X1217028Y785061D01*
Y784467D01*
X1216164Y783603D01*
X1210111D01*
G01X1277451Y900505D02*
X1277034Y900088D01*
X1276478D01*
X1266327Y889937D01*
Y853866D01*
X1258402Y845941D01*
Y845347D01*
X1258977Y844772D01*
Y844178D01*
X1258460Y843661D01*
X1257866D01*
X1257291Y844236D01*
X1256697D01*
X1256180Y843719D01*
Y843125D01*
X1256810Y842495D01*
Y841901D01*
X1256293Y841384D01*
X1255699D01*
X1255069Y842014D01*
X1254475D01*
X1253958Y841497D01*
Y840903D01*
X1254973Y839888D01*
Y839294D01*
X1254456Y838777D01*
X1253862D01*
X1252847Y839792D01*
X1252253D01*
X1251736Y839275D01*
Y838681D01*
X1252751Y837666D01*
Y837072D01*
X1252234Y836555D01*
X1251640D01*
X1250625Y837570D01*
X1250031D01*
X1249514Y837053D01*
Y836459D01*
X1250529Y835444D01*
Y834850D01*
X1250012Y834333D01*
X1249418D01*
X1248403Y835348D01*
X1247809D01*
X1247293Y834832D01*
Y834237D01*
X1248317Y833213D01*
Y832618D01*
X1218579Y802880D01*
X1217985D01*
X1216860Y804005D01*
X1216266D01*
X1215749Y803488D01*
Y802894D01*
X1216874Y801769D01*
Y801175D01*
X1216034Y800335D01*
X1210111D01*
G01X1276175Y902986D02*
X1275474D01*
X1263647Y891159D01*
Y854979D01*
X1243979Y835311D01*
Y834717D01*
X1244575Y834121D01*
X1244576Y833529D01*
X1244058Y833011D01*
X1243464D01*
X1242868Y833607D01*
X1242274Y833606D01*
X1241757Y833089D01*
Y832495D01*
X1242353Y831899D01*
X1242354Y831307D01*
X1241836Y830789D01*
X1241242D01*
X1240646Y831385D01*
X1240052Y831384D01*
X1239535Y830867D01*
Y830273D01*
X1240131Y829677D01*
X1240132Y829085D01*
X1239614Y828567D01*
X1239020D01*
X1238424Y829163D01*
X1237830Y829162D01*
X1237313Y828645D01*
Y828051D01*
X1237909Y827455D01*
X1237910Y826863D01*
X1237392Y826345D01*
X1236798D01*
X1236202Y826941D01*
X1235608Y826940D01*
X1235091Y826423D01*
Y825829D01*
X1235687Y825233D01*
X1235688Y824641D01*
X1235170Y824123D01*
X1234576D01*
X1233980Y824719D01*
X1233386Y824718D01*
X1232869Y824201D01*
Y823607D01*
X1233465Y823011D01*
X1233466Y822419D01*
X1232948Y821901D01*
X1232354D01*
X1231758Y822497D01*
X1231164Y822496D01*
X1230647Y821979D01*
Y821385D01*
X1231243Y820789D01*
X1231244Y820197D01*
X1230726Y819679D01*
X1230132D01*
X1229536Y820275D01*
X1228942Y820274D01*
X1228244Y819576D01*
Y816359D01*
X1218913Y807028D01*
X1210111D01*
G01X1276751Y907155D02*
X1275189D01*
X1260507Y892473D01*
Y856281D01*
X1224096Y819870D01*
Y819276D01*
X1225103Y818269D01*
X1225104Y817677D01*
X1224586Y817159D01*
X1223992Y817158D01*
X1222978Y818172D01*
X1222384Y818171D01*
X1221866Y817653D01*
X1221867Y817061D01*
X1222881Y816047D01*
X1222882Y815455D01*
X1222364Y814937D01*
X1221770Y814936D01*
X1219305Y817401D01*
X1218711Y817400D01*
X1218193Y816882D01*
X1218194Y816290D01*
X1220180Y814304D01*
X1220181Y813712D01*
X1219663Y813194D01*
X1219069Y813193D01*
X1218540Y813722D01*
X1217947Y813721D01*
X1210111D01*
G01X1276166Y910340D02*
X1274582D01*
X1257827Y893585D01*
Y857651D01*
X1225321Y825145D01*
X1224727D01*
X1223131Y826741D01*
X1222537Y826740D01*
X1222020Y826223D01*
Y825629D01*
X1223616Y824033D01*
X1223617Y823441D01*
X1223099Y822923D01*
X1222505D01*
X1220891Y824537D01*
X1220297Y824536D01*
X1219780Y824019D01*
Y823425D01*
X1221394Y821811D01*
X1221395Y821219D01*
X1220590Y820414D01*
X1210111D01*
G01X1275211Y920435D02*
X1272091D01*
X1249057Y897401D01*
Y865572D01*
X1231754Y848269D01*
X1231160D01*
X1229976Y849453D01*
X1229382D01*
X1228865Y848936D01*
Y848342D01*
X1230049Y847158D01*
Y846564D01*
X1229532Y846047D01*
X1228938D01*
X1227754Y847231D01*
X1227160D01*
X1226643Y846714D01*
Y846120D01*
X1227827Y844936D01*
Y844342D01*
X1227310Y843825D01*
X1226716D01*
X1225532Y845009D01*
X1224938D01*
X1224421Y844492D01*
Y843898D01*
X1225605Y842714D01*
Y842120D01*
X1225088Y841603D01*
X1224494D01*
X1223310Y842787D01*
X1222716D01*
X1222199Y842270D01*
Y841676D01*
X1223383Y840492D01*
Y839898D01*
X1222866Y839381D01*
X1222272D01*
X1221088Y840565D01*
X1220494D01*
X1219977Y840048D01*
Y839454D01*
X1221161Y838270D01*
Y837676D01*
X1220631Y837146D01*
X1210111D01*
G01X1275171Y923835D02*
X1271699D01*
X1246377Y898513D01*
Y870317D01*
X1243755Y867695D01*
Y867045D01*
X1244609Y866191D01*
Y865541D01*
X1244148Y865080D01*
X1243498D01*
X1242644Y865934D01*
X1241994D01*
X1241533Y865473D01*
Y864823D01*
X1242387Y863969D01*
Y863319D01*
X1241926Y862858D01*
X1241276D01*
X1240422Y863712D01*
X1239772D01*
X1239311Y863251D01*
Y862601D01*
X1240165Y861747D01*
Y861097D01*
X1239704Y860636D01*
X1239054D01*
X1238200Y861490D01*
X1237550D01*
X1237089Y861029D01*
Y860379D01*
X1237943Y859525D01*
Y858875D01*
X1237482Y858414D01*
X1236832D01*
X1235978Y859268D01*
X1235328D01*
X1234867Y858807D01*
Y858157D01*
X1235721Y857303D01*
Y856653D01*
X1235260Y856192D01*
X1234610D01*
X1233756Y857046D01*
X1233106D01*
X1232645Y856585D01*
Y855935D01*
X1233293Y855287D01*
Y854637D01*
X1232832Y854176D01*
X1232182D01*
X1231534Y854824D01*
X1230884D01*
X1230423Y854363D01*
Y853713D01*
X1230741Y853395D01*
Y852745D01*
X1230280Y852284D01*
X1229630D01*
X1229312Y852602D01*
X1228662D01*
X1219899Y843839D01*
X1210111D01*
G01X1275261Y927495D02*
X1270917D01*
X1243237Y899815D01*
Y871620D01*
X1222149Y850532D01*
X1220830D01*
X1220410Y850952D01*
Y853768D01*
X1219990Y854188D01*
X1219259D01*
X1218839Y853768D01*
Y850448D01*
X1218419Y850028D01*
X1217688D01*
X1217268Y850448D01*
Y853768D01*
X1216848Y854188D01*
X1216117D01*
X1215697Y853768D01*
Y850952D01*
X1215277Y850532D01*
X1210111D01*
G01X1275111Y930485D02*
X1270115D01*
X1240557Y900927D01*
Y874118D01*
X1223664Y857225D01*
X1221941D01*
X1221521Y857645D01*
Y860118D01*
X1221101Y860538D01*
X1220370D01*
X1219950Y860118D01*
Y857645D01*
X1219530Y857225D01*
X1218799D01*
X1218379Y857645D01*
Y860118D01*
X1217959Y860538D01*
X1217228D01*
X1216808Y860118D01*
Y857645D01*
X1216388Y857225D01*
X1210111D01*
G01X1275081Y940805D02*
X1267849D01*
X1231787Y904743D01*
Y889288D01*
X1230180Y887681D01*
Y887087D01*
X1231486Y885781D01*
Y885187D01*
X1230969Y884670D01*
X1230375D01*
X1229069Y885976D01*
X1228475D01*
X1227958Y885459D01*
Y884865D01*
X1229264Y883559D01*
Y882965D01*
X1228747Y882448D01*
X1228153D01*
X1226847Y883754D01*
X1226253D01*
X1225736Y883237D01*
Y882643D01*
X1227042Y881337D01*
Y880743D01*
X1226525Y880226D01*
X1225931D01*
X1224625Y881532D01*
X1224031D01*
X1223514Y881015D01*
Y880421D01*
X1224820Y879115D01*
Y878521D01*
X1224303Y878004D01*
X1223709D01*
X1222403Y879310D01*
X1221809D01*
X1221292Y878793D01*
Y878199D01*
X1222598Y876893D01*
Y876299D01*
X1222081Y875782D01*
X1221487D01*
X1220181Y877088D01*
X1219587D01*
X1219070Y876571D01*
Y875977D01*
X1220376Y874671D01*
Y874077D01*
X1219859Y873560D01*
X1219265D01*
X1217959Y874866D01*
X1217365D01*
X1216456Y873957D01*
X1210111D01*
G01X1275261Y943565D02*
X1266817D01*
X1229107Y905855D01*
Y894481D01*
X1227441Y892815D01*
Y892221D01*
X1228888Y890774D01*
X1228887Y890180D01*
X1228370Y889663D01*
X1227776D01*
X1226329Y891110D01*
X1225737Y891111D01*
X1225219Y890593D01*
Y889999D01*
X1226666Y888552D01*
X1226665Y887958D01*
X1226148Y887441D01*
X1225554D01*
X1224107Y888888D01*
X1223515Y888889D01*
X1222997Y888371D01*
Y887777D01*
X1224444Y886330D01*
X1224443Y885736D01*
X1223926Y885219D01*
X1223332D01*
X1221885Y886666D01*
X1221293Y886667D01*
X1220775Y886149D01*
Y885555D01*
X1222222Y884108D01*
X1222221Y883514D01*
X1221704Y882997D01*
X1221110D01*
X1219663Y884444D01*
X1219071Y884445D01*
X1218553Y883927D01*
Y883333D01*
X1220000Y881886D01*
X1219999Y881292D01*
X1219482Y880775D01*
X1218888D01*
X1217441Y882222D01*
X1216849Y882223D01*
X1215276Y880650D01*
X1210111D01*
G01X1275241Y946715D02*
X1265525D01*
X1225967Y907157D01*
Y899398D01*
X1225357Y898788D01*
X1224234D01*
X1223700Y898254D01*
X1223701Y897662D01*
X1225378Y895985D01*
Y895391D01*
X1224861Y894874D01*
X1224267Y894873D01*
X1222590Y896550D01*
X1221996D01*
X1221478Y896032D01*
X1221479Y895440D01*
X1223156Y893763D01*
Y893169D01*
X1222639Y892652D01*
X1222045Y892651D01*
X1220368Y894328D01*
X1219774D01*
X1219256Y893810D01*
X1219257Y893218D01*
X1220934Y891541D01*
Y890947D01*
X1220417Y890430D01*
X1219823Y890429D01*
X1215875D01*
X1212789Y887343D01*
X1210111D01*
G01X1275221Y949445D02*
X1264011D01*
X1223287Y908721D01*
Y904729D01*
X1222577Y904019D01*
Y903158D01*
X1223287Y902448D01*
Y901691D01*
X1222447Y900851D01*
X1221853Y900850D01*
X1220524Y902179D01*
X1219930D01*
X1219412Y901661D01*
X1219413Y901069D01*
X1220742Y899740D01*
Y899146D01*
X1220225Y898629D01*
X1219631Y898628D01*
X1218302Y899957D01*
X1217708D01*
X1217190Y899439D01*
X1217191Y898847D01*
X1218520Y897518D01*
Y896924D01*
X1217529Y895933D01*
X1216541D01*
X1215155Y897319D01*
X1214505D01*
X1213831Y896645D01*
Y895785D01*
X1212082Y894036D01*
X1210111D01*
G01X1275981Y958465D02*
X1256565D01*
X1254763Y956663D01*
X1254169Y956662D01*
X1253698Y957133D01*
X1253104D01*
X1252586Y956615D01*
X1252587Y956023D01*
X1253058Y955552D01*
Y954958D01*
X1252541Y954441D01*
X1251947Y954440D01*
X1251476Y954911D01*
X1250882D01*
X1250364Y954393D01*
X1250365Y953801D01*
X1250836Y953330D01*
Y952736D01*
X1250319Y952219D01*
X1249725Y952218D01*
X1249254Y952689D01*
X1248660D01*
X1248142Y952171D01*
X1248143Y951579D01*
X1248614Y951108D01*
Y950514D01*
X1248097Y949997D01*
X1247503Y949996D01*
X1247032Y950467D01*
X1246438D01*
X1245920Y949949D01*
X1245921Y949357D01*
X1246392Y948886D01*
Y948292D01*
X1245875Y947775D01*
X1245281Y947774D01*
X1244810Y948245D01*
X1244216D01*
X1243698Y947727D01*
X1243699Y947135D01*
X1244170Y946664D01*
Y946070D01*
X1243653Y945553D01*
X1243059Y945552D01*
X1242588Y946023D01*
X1241994D01*
X1241476Y945505D01*
X1241477Y944913D01*
X1241948Y944442D01*
Y943848D01*
X1241431Y943331D01*
X1240837Y943330D01*
X1240366Y943801D01*
X1239772D01*
X1239254Y943283D01*
X1239255Y942691D01*
X1239726Y942220D01*
Y941626D01*
X1239209Y941109D01*
X1238615Y941108D01*
X1238144Y941579D01*
X1237550D01*
X1237032Y941061D01*
X1237033Y940469D01*
X1237504Y939998D01*
Y939404D01*
X1236987Y938887D01*
X1236393Y938886D01*
X1235922Y939357D01*
X1235328D01*
X1234810Y938839D01*
X1234811Y938247D01*
X1235282Y937776D01*
Y937182D01*
X1234765Y936665D01*
X1234171Y936664D01*
X1233700Y937135D01*
X1233106D01*
X1232588Y936617D01*
X1232589Y936025D01*
X1233060Y935554D01*
Y934960D01*
X1232543Y934443D01*
X1231949Y934442D01*
X1231478Y934913D01*
X1230884D01*
X1230366Y934395D01*
X1230367Y933803D01*
X1230838Y933332D01*
Y932738D01*
X1218731Y920631D01*
Y916935D01*
X1212564Y910768D01*
X1210111D01*
G01X1276921Y964365D02*
X1249327D01*
X1248282Y963320D01*
X1248281Y962726D01*
X1248890Y962117D01*
Y961523D01*
X1248372Y961005D01*
X1247780Y961006D01*
X1247171Y961615D01*
X1246577D01*
X1246060Y961098D01*
X1246059Y960504D01*
X1246668Y959895D01*
Y959301D01*
X1246150Y958783D01*
X1245558Y958784D01*
X1244949Y959393D01*
X1244355D01*
X1243838Y958876D01*
X1243837Y958282D01*
X1244446Y957673D01*
Y957079D01*
X1243928Y956561D01*
X1243336Y956562D01*
X1242727Y957171D01*
X1242133D01*
X1241616Y956654D01*
X1241615Y956060D01*
X1242224Y955451D01*
Y954857D01*
X1241706Y954339D01*
X1241114Y954340D01*
X1240505Y954949D01*
X1239911D01*
X1239394Y954432D01*
X1239393Y953838D01*
X1240002Y953229D01*
Y952635D01*
X1239484Y952117D01*
X1238892Y952118D01*
X1238283Y952727D01*
X1237689D01*
X1237172Y952210D01*
X1237171Y951616D01*
X1237780Y951007D01*
Y950413D01*
X1237262Y949895D01*
X1236670Y949896D01*
X1236061Y950505D01*
X1235467D01*
X1234950Y949988D01*
X1234949Y949394D01*
X1235558Y948785D01*
Y948191D01*
X1235040Y947673D01*
X1234448Y947674D01*
X1233839Y948283D01*
X1233245D01*
X1232728Y947766D01*
X1232727Y947172D01*
X1233336Y946563D01*
Y945969D01*
X1232818Y945451D01*
X1232226Y945452D01*
X1231617Y946061D01*
X1231023D01*
X1217231Y932269D01*
Y929507D01*
X1211878Y924154D01*
X1210111D01*
G01X1275241Y961145D02*
X1253311D01*
X1234098Y941932D01*
X1233504D01*
X1233126Y942310D01*
X1232534Y942311D01*
X1232016Y941793D01*
Y941199D01*
X1232394Y940821D01*
X1232393Y940227D01*
X1231876Y939710D01*
X1231282D01*
X1230508Y940484D01*
X1229916Y940485D01*
X1229398Y939967D01*
Y939373D01*
X1230172Y938599D01*
X1230171Y938005D01*
X1229654Y937488D01*
X1229060D01*
X1228286Y938262D01*
X1227694Y938263D01*
X1227176Y937745D01*
Y937151D01*
X1227950Y936377D01*
X1227949Y935783D01*
X1227432Y935266D01*
X1226838D01*
X1226064Y936040D01*
X1225472Y936041D01*
X1224954Y935523D01*
Y934929D01*
X1225728Y934155D01*
X1225727Y933561D01*
X1225210Y933044D01*
X1224616D01*
X1223842Y933818D01*
X1223250Y933819D01*
X1222732Y933301D01*
Y932707D01*
X1223506Y931933D01*
X1223505Y931339D01*
X1222988Y930822D01*
X1222394D01*
X1221620Y931596D01*
X1221028Y931597D01*
X1220510Y931079D01*
Y930485D01*
X1221284Y929711D01*
X1221283Y929117D01*
X1218221Y926055D01*
Y925461D01*
X1218533Y925149D01*
X1218534Y924557D01*
X1218016Y924039D01*
X1217422D01*
X1217110Y924351D01*
X1216516Y924350D01*
X1216051Y923885D01*
Y918082D01*
X1215430Y917461D01*
X1210111D01*
G01X1275341Y967305D02*
X1246803D01*
X1246253Y966755D01*
Y965653D01*
X1245693Y965093D01*
X1244591D01*
X1244031Y964533D01*
Y963431D01*
X1243471Y962871D01*
X1242369D01*
X1241809Y962311D01*
Y961209D01*
X1241249Y960649D01*
X1240147D01*
X1239587Y960089D01*
Y958987D01*
X1239027Y958427D01*
X1237925D01*
X1237365Y957867D01*
Y956765D01*
X1236805Y956205D01*
X1235703D01*
X1235143Y955645D01*
Y954543D01*
X1234583Y953983D01*
X1233481D01*
X1232334Y952836D01*
X1230574D01*
X1229920Y952182D01*
Y951588D01*
X1230947Y950561D01*
Y949967D01*
X1230430Y949450D01*
X1229836D01*
X1228809Y950477D01*
X1228215D01*
X1227698Y949960D01*
Y949366D01*
X1228725Y948339D01*
Y947745D01*
X1228208Y947228D01*
X1227614D01*
X1226587Y948255D01*
X1225993D01*
X1225476Y947738D01*
Y947144D01*
X1226503Y946117D01*
Y945523D01*
X1225986Y945006D01*
X1225392D01*
X1224365Y946033D01*
X1223771D01*
X1223512Y945774D01*
Y942386D01*
X1211973Y930847D01*
X1210111D01*
G01X1276243Y977435D02*
X1275788D01*
X1275085Y978138D01*
X1274217D01*
X1273514Y977435D01*
X1272646D01*
X1271943Y978138D01*
X1271075D01*
X1270372Y977435D01*
X1233994D01*
X1233443Y976884D01*
Y976290D01*
X1235124Y974609D01*
Y974015D01*
X1234607Y973498D01*
X1234013D01*
X1232156Y975355D01*
X1231562D01*
X1231045Y974838D01*
Y974244D01*
X1231664Y973625D01*
Y972437D01*
X1232308Y971793D01*
Y971199D01*
X1231791Y970682D01*
X1231197D01*
X1230553Y971326D01*
X1229959D01*
X1229442Y970809D01*
Y970215D01*
X1230086Y969571D01*
Y968977D01*
X1229569Y968460D01*
X1228975D01*
X1228331Y969104D01*
X1227737D01*
X1227220Y968587D01*
Y967993D01*
X1227864Y967349D01*
Y966755D01*
X1227347Y966238D01*
X1226753D01*
X1226109Y966882D01*
X1225515D01*
X1224998Y966365D01*
Y965771D01*
X1225642Y965127D01*
Y964533D01*
X1225125Y964016D01*
X1224531D01*
X1223887Y964660D01*
X1223293D01*
X1222776Y964143D01*
Y963549D01*
X1223420Y962905D01*
Y962311D01*
X1222903Y961794D01*
X1222309D01*
X1221665Y962438D01*
X1221071D01*
X1220407Y961774D01*
Y955792D01*
X1212195Y947579D01*
X1210111D01*
G01X1276061Y981115D02*
X1269871D01*
X1268871Y980115D01*
X1240593D01*
X1237640Y981338D01*
X1236105D01*
X1235375Y980608D01*
X1234534D01*
X1233804Y981338D01*
X1232963D01*
X1232233Y980608D01*
X1231392D01*
X1230662Y981338D01*
X1229141D01*
X1228759Y980956D01*
Y980362D01*
X1230313Y978808D01*
Y978214D01*
X1229796Y977697D01*
X1229202D01*
X1227648Y979251D01*
X1227054D01*
X1226607Y978804D01*
Y975876D01*
X1228365Y974118D01*
Y973524D01*
X1227848Y973007D01*
X1227254Y973006D01*
X1225496Y974764D01*
X1224902D01*
X1223837Y973699D01*
Y968996D01*
X1217727Y962886D01*
Y957781D01*
X1214218Y954272D01*
X1210111D01*
G01X1278491Y985165D02*
X1276002Y985164D01*
X1275498Y985668D01*
X1268737D01*
X1268007Y984938D01*
X1227648D01*
X1223007Y980297D01*
Y977962D01*
X1220237Y975192D01*
Y970489D01*
X1214127Y964379D01*
Y963298D01*
G01X1205002Y962285D02*
X1203682Y960965D01*
G01X1276571Y991605D02*
X1273896D01*
X1273476Y991185D01*
Y990068D01*
X1273056Y989648D01*
X1272325D01*
X1271905Y990068D01*
Y991185D01*
X1271485Y991605D01*
X1270754D01*
X1270334Y991185D01*
Y990068D01*
X1269914Y989648D01*
X1269183D01*
X1268763Y990068D01*
Y991185D01*
X1268343Y991605D01*
X1266381D01*
X1263314Y988538D01*
X1226128D01*
X1219407Y981817D01*
Y979455D01*
X1216637Y976685D01*
Y972138D01*
G01X1213190Y968691D02*
X1212747Y968248D01*
X1210701D01*
X1210111Y967658D01*
G01X1274811Y996965D02*
X1274341Y997435D01*
X1273454D01*
X1273034Y997015D01*
Y994868D01*
X1272614Y994448D01*
X1271883D01*
X1271463Y994868D01*
Y997015D01*
X1271043Y997435D01*
X1268419D01*
X1267851Y996867D01*
X1267852Y996275D01*
X1268640Y995487D01*
Y994893D01*
X1268123Y994376D01*
X1267529Y994375D01*
X1266741Y995163D01*
X1266147D01*
X1262472Y991488D01*
X1225286D01*
X1216727Y982929D01*
Y980568D01*
X1215002Y978843D01*
G01X1214889Y978730D02*
X1213957Y977798D01*
Y976321D01*
X1211987Y974351D01*
X1210111D01*
G01X1275446Y1000270D02*
X1274881Y1000835D01*
X1268027D01*
X1261360Y994168D01*
X1224173D01*
X1222680Y992675D01*
X1222086D01*
X1221447Y993314D01*
X1220853D01*
X1220336Y992797D01*
Y992203D01*
X1220975Y991564D01*
Y990970D01*
X1220458Y990453D01*
X1219864D01*
X1219225Y991092D01*
X1218631D01*
X1218114Y990575D01*
Y989981D01*
X1218753Y989342D01*
Y988748D01*
X1214047Y984042D01*
Y981694D01*
X1213397Y981044D01*
X1210111D01*
G01X1276153Y1003373D02*
X1276011Y1003515D01*
X1273757D01*
X1273337Y1003935D01*
Y1005098D01*
X1272917Y1005518D01*
X1272186D01*
X1271766Y1005098D01*
Y1003935D01*
X1271346Y1003515D01*
X1270615D01*
X1270195Y1003935D01*
Y1005098D01*
X1269775Y1005518D01*
X1269044D01*
X1268624Y1005098D01*
Y1003935D01*
X1268204Y1003515D01*
X1266915D01*
X1260248Y996848D01*
X1235726D01*
X1235306Y997268D01*
Y998778D01*
X1234886Y999198D01*
X1234155D01*
X1233735Y998778D01*
Y997268D01*
X1233315Y996848D01*
X1232584D01*
X1232164Y997268D01*
Y998778D01*
X1231744Y999198D01*
X1231013D01*
X1230593Y998778D01*
Y997268D01*
X1230173Y996848D01*
X1229442D01*
X1229022Y997268D01*
Y998778D01*
X1228602Y999198D01*
X1227871D01*
X1227451Y998778D01*
Y997268D01*
X1227031Y996848D01*
X1220179D01*
X1214056Y990725D01*
Y989550D01*
X1212242Y987736D01*
X1210111D01*
G01X1275671Y1007805D02*
X1274425Y1009051D01*
X1268659D01*
X1259136Y999528D01*
X1242886D01*
X1238019Y1004395D01*
X1235369D01*
X1234949Y1003975D01*
Y1002958D01*
X1234529Y1002538D01*
X1233798D01*
X1233378Y1002958D01*
Y1003975D01*
X1232958Y1004395D01*
X1232227D01*
X1231807Y1003975D01*
Y1002958D01*
X1231387Y1002538D01*
X1230656D01*
X1230236Y1002958D01*
Y1003975D01*
X1229816Y1004395D01*
X1229085D01*
X1228665Y1003975D01*
Y1002958D01*
X1228245Y1002538D01*
X1227514D01*
X1227094Y1002958D01*
Y1003975D01*
X1226674Y1004395D01*
X1223549D01*
X1213583Y994429D01*
X1210111D01*
G01X1277155Y1008771D02*
X1275115Y1010811D01*
Y1011548D01*
X1274695Y1011968D01*
X1273964D01*
X1273544Y1011548D01*
Y1010811D01*
X1273124Y1010391D01*
X1272393D01*
X1271973Y1010811D01*
Y1011548D01*
X1271553Y1011968D01*
X1270822D01*
X1270402Y1011548D01*
Y1010811D01*
X1269982Y1010391D01*
X1268103D01*
X1258580Y1000868D01*
X1243442D01*
X1238575Y1005735D01*
X1222855D01*
X1218242Y1001122D01*
X1210111D01*
G01X1275741Y1031666D02*
X1261856D01*
X1259195Y1034327D01*
X1243637D01*
X1237204Y1027894D01*
X1233457D01*
X1233037Y1027474D01*
Y1026588D01*
X1232617Y1026168D01*
X1231886D01*
X1231466Y1026588D01*
Y1027474D01*
X1231046Y1027894D01*
X1230315D01*
X1229895Y1027474D01*
Y1026588D01*
X1229475Y1026168D01*
X1228744D01*
X1228324Y1026588D01*
Y1027474D01*
X1227904Y1027894D01*
X1227173D01*
X1226753Y1027474D01*
Y1026588D01*
X1226333Y1026168D01*
X1225602D01*
X1225182Y1026588D01*
Y1027474D01*
X1224762Y1027894D01*
X1224031D01*
X1223611Y1027474D01*
Y1026588D01*
X1223191Y1026168D01*
X1222460D01*
X1222040Y1026588D01*
Y1027474D01*
X1221620Y1027894D01*
X1210111D01*
G01X1275741Y1034346D02*
X1262968D01*
X1260307Y1037007D01*
X1242487D01*
X1236485Y1031005D01*
X1218868D01*
X1218408Y1031465D01*
Y1032116D01*
X1218868Y1032576D01*
X1225571D01*
X1226031Y1033036D01*
Y1033687D01*
X1225571Y1034147D01*
X1217297D01*
X1216631Y1033481D01*
Y1032086D01*
X1216120Y1031575D01*
X1215001D01*
X1211989Y1034587D01*
X1210111D01*
G01X1275741Y1037103D02*
X1264003D01*
X1261419Y1039687D01*
X1241375D01*
X1239333Y1037645D01*
X1220098D01*
X1219638Y1038105D01*
Y1038756D01*
X1220098Y1039216D01*
X1226031D01*
X1226491Y1039676D01*
Y1040327D01*
X1226031Y1040787D01*
X1218527D01*
X1218067Y1040327D01*
Y1038105D01*
X1217607Y1037645D01*
X1215690D01*
X1212055Y1041280D01*
X1210111D01*
G01X1275971Y1039783D02*
X1265115D01*
X1262531Y1042367D01*
X1229988D01*
X1228030Y1044325D01*
X1219985D01*
X1219525Y1044785D01*
Y1045436D01*
X1219985Y1045896D01*
X1226581D01*
X1227041Y1046356D01*
Y1047007D01*
X1226581Y1047467D01*
X1218414D01*
X1217954Y1047007D01*
Y1044785D01*
X1217494Y1044325D01*
X1215319D01*
X1211671Y1047973D01*
X1210111D01*
G01X1277644Y1045272D02*
X1232751D01*
X1231278Y1046745D01*
Y1046744D01*
X1227875Y1050147D01*
X1225176D01*
X1224756Y1050567D01*
Y1051928D01*
X1224336Y1052348D01*
X1223605D01*
X1223185Y1051928D01*
Y1050567D01*
X1222765Y1050147D01*
X1222034D01*
X1221614Y1050567D01*
Y1051928D01*
X1221194Y1052348D01*
X1220463D01*
X1220043Y1051928D01*
Y1050567D01*
X1219623Y1050147D01*
X1218786D01*
X1217449Y1051484D01*
X1216855D01*
X1216225Y1050854D01*
X1215631D01*
X1215114Y1051371D01*
Y1051965D01*
X1215744Y1052595D01*
Y1053189D01*
X1214267Y1054666D01*
X1210111D01*
G01X1278236Y1050005D02*
X1275203D01*
X1273150Y1047952D01*
X1233866D01*
X1226790Y1055028D01*
X1224777D01*
X1224357Y1055448D01*
Y1056318D01*
X1223937Y1056738D01*
X1223206D01*
X1222786Y1056318D01*
Y1055448D01*
X1222366Y1055028D01*
X1221556D01*
X1219998Y1056586D01*
X1219404Y1056587D01*
X1218194Y1055377D01*
X1217600D01*
X1217082Y1055895D01*
X1217083Y1056487D01*
X1218293Y1057697D01*
Y1058291D01*
X1215225Y1061359D01*
X1210111D01*
G01X1275071Y1060095D02*
X1273780D01*
X1272068Y1058383D01*
Y1057789D01*
X1272461Y1057396D01*
Y1056802D01*
X1271944Y1056285D01*
X1271350D01*
X1270957Y1056678D01*
X1270363D01*
X1269846Y1056161D01*
Y1055567D01*
X1270239Y1055174D01*
Y1054580D01*
X1269722Y1054063D01*
X1269128D01*
X1268735Y1054456D01*
X1268141D01*
X1267343Y1053658D01*
X1265763D01*
X1265343Y1054078D01*
Y1054718D01*
X1264923Y1055138D01*
X1264192D01*
X1263772Y1054718D01*
Y1054078D01*
X1263352Y1053658D01*
X1262621D01*
X1262201Y1054078D01*
Y1054718D01*
X1261781Y1055138D01*
X1261050D01*
X1260630Y1054718D01*
Y1054078D01*
X1260210Y1053658D01*
X1259479D01*
X1259059Y1054078D01*
Y1054718D01*
X1258639Y1055138D01*
X1257908D01*
X1257488Y1054718D01*
Y1054078D01*
X1257068Y1053658D01*
X1256337D01*
X1255917Y1054078D01*
Y1054718D01*
X1255497Y1055138D01*
X1254766D01*
X1254346Y1054718D01*
Y1054078D01*
X1253926Y1053658D01*
X1253195D01*
X1252775Y1054078D01*
Y1054718D01*
X1252355Y1055138D01*
X1251624D01*
X1251204Y1054718D01*
Y1054078D01*
X1250784Y1053658D01*
X1250053D01*
X1249633Y1054078D01*
Y1054718D01*
X1249213Y1055138D01*
X1248482D01*
X1248062Y1054718D01*
Y1054078D01*
X1247642Y1053658D01*
X1246911D01*
X1246491Y1054078D01*
Y1054718D01*
X1246071Y1055138D01*
X1245340D01*
X1244920Y1054718D01*
Y1054078D01*
X1244500Y1053658D01*
X1243769D01*
X1243349Y1054078D01*
Y1054718D01*
X1242929Y1055138D01*
X1242198D01*
X1241778Y1054718D01*
Y1054078D01*
X1241358Y1053658D01*
X1240627D01*
X1240207Y1054078D01*
Y1054718D01*
X1239787Y1055138D01*
X1239056D01*
X1238636Y1054718D01*
Y1054078D01*
X1238216Y1053658D01*
X1237485D01*
X1237065Y1054078D01*
Y1054718D01*
X1236645Y1055138D01*
X1235914D01*
X1235494Y1054718D01*
Y1054078D01*
X1235074Y1053658D01*
X1233964D01*
X1218957Y1068665D01*
X1216578D01*
X1213845Y1071398D01*
X1210111D01*
G01X1277271Y1053235D02*
X1276537D01*
X1273166Y1049864D01*
X1233850D01*
X1225216Y1058498D01*
Y1059208D01*
X1224796Y1059628D01*
X1224065D01*
X1223645Y1059208D01*
Y1058498D01*
X1223225Y1058078D01*
X1221628D01*
X1220893Y1058813D01*
X1220894Y1059405D01*
X1222254Y1060765D01*
Y1061359D01*
X1221737Y1061876D01*
X1221143Y1061877D01*
X1219783Y1060517D01*
X1219189D01*
X1218671Y1061035D01*
X1218672Y1061627D01*
X1220032Y1062987D01*
Y1063581D01*
X1219515Y1064098D01*
X1218921Y1064099D01*
X1217561Y1062739D01*
X1216967D01*
X1215001Y1064705D01*
X1210111D01*
G01X1275111Y1062775D02*
X1272668D01*
X1267711Y1057818D01*
X1236985D01*
X1230506Y1064297D01*
X1229912D01*
X1229360Y1063745D01*
X1228766Y1063746D01*
X1228249Y1064263D01*
Y1064857D01*
X1228801Y1065409D01*
X1228802Y1066001D01*
X1228284Y1066519D01*
X1227690D01*
X1227138Y1065967D01*
X1226544Y1065968D01*
X1226027Y1066485D01*
Y1067079D01*
X1226579Y1067631D01*
X1226580Y1068223D01*
X1226062Y1068741D01*
X1225468D01*
X1224916Y1068189D01*
X1224322Y1068190D01*
X1223805Y1068707D01*
Y1069301D01*
X1224357Y1069853D01*
X1224358Y1070445D01*
X1223840Y1070963D01*
X1223246D01*
X1222694Y1070411D01*
X1222100Y1070412D01*
X1221583Y1070929D01*
Y1071523D01*
X1222135Y1072075D01*
X1222136Y1072667D01*
X1221618Y1073185D01*
X1221024D01*
X1220472Y1072633D01*
X1219878Y1072634D01*
X1219361Y1073151D01*
Y1073745D01*
X1219913Y1074297D01*
X1219914Y1074889D01*
X1219396Y1075407D01*
X1218802D01*
X1217786Y1074391D01*
X1217192Y1074392D01*
X1216675Y1074909D01*
Y1075503D01*
X1217691Y1076519D01*
X1217692Y1077111D01*
X1217174Y1077629D01*
X1216580D01*
X1216028Y1077077D01*
X1215434Y1077078D01*
X1214421Y1078091D01*
X1210111D01*
G01X1275280Y1071845D02*
X1269313D01*
X1266741Y1069273D01*
X1265748D01*
X1265328Y1069693D01*
Y1071318D01*
X1264908Y1071738D01*
X1264177D01*
X1263757Y1071318D01*
Y1069693D01*
X1263337Y1069273D01*
X1262606D01*
X1262186Y1069693D01*
Y1071318D01*
X1261766Y1071738D01*
X1261035D01*
X1260615Y1071318D01*
Y1069693D01*
X1260195Y1069273D01*
X1259464D01*
X1259044Y1069693D01*
Y1071318D01*
X1258624Y1071738D01*
X1257893D01*
X1257473Y1071318D01*
Y1069693D01*
X1257053Y1069273D01*
X1256322D01*
X1255902Y1069693D01*
Y1071318D01*
X1255482Y1071738D01*
X1254751D01*
X1254331Y1071318D01*
Y1069693D01*
X1253911Y1069273D01*
X1253180D01*
X1252760Y1069693D01*
Y1071318D01*
X1252340Y1071738D01*
X1251609D01*
X1251189Y1071318D01*
Y1069693D01*
X1250769Y1069273D01*
X1242073D01*
X1216523Y1094823D01*
X1210111D01*
G01X1275201Y1074525D02*
X1240613D01*
X1239741Y1075397D01*
X1239742Y1075989D01*
X1239996Y1076243D01*
Y1076837D01*
X1239479Y1077354D01*
X1238885Y1077355D01*
X1238631Y1077101D01*
X1238037D01*
X1237519Y1077619D01*
X1237520Y1078211D01*
X1237774Y1078465D01*
Y1079059D01*
X1237257Y1079576D01*
X1236663Y1079577D01*
X1236409Y1079323D01*
X1235815D01*
X1235297Y1079841D01*
X1235298Y1080433D01*
X1235552Y1080687D01*
Y1081281D01*
X1235035Y1081798D01*
X1234441Y1081799D01*
X1234187Y1081545D01*
X1233593D01*
X1233075Y1082063D01*
X1233076Y1082655D01*
X1233330Y1082909D01*
Y1083503D01*
X1232813Y1084020D01*
X1232219Y1084021D01*
X1231965Y1083767D01*
X1231371D01*
X1230853Y1084285D01*
X1230854Y1084877D01*
X1231108Y1085131D01*
Y1085725D01*
X1230591Y1086242D01*
X1229997Y1086243D01*
X1229743Y1085989D01*
X1229149D01*
X1228631Y1086507D01*
X1228632Y1087099D01*
X1228886Y1087353D01*
Y1087947D01*
X1228369Y1088464D01*
X1227775Y1088465D01*
X1227521Y1088211D01*
X1226927D01*
X1226409Y1088729D01*
X1226410Y1089321D01*
X1226664Y1089575D01*
Y1090169D01*
X1226147Y1090686D01*
X1225553Y1090687D01*
X1225299Y1090433D01*
X1224705D01*
X1224187Y1090951D01*
X1224188Y1091543D01*
X1224442Y1091797D01*
Y1092391D01*
X1223925Y1092908D01*
X1223331Y1092909D01*
X1223077Y1092655D01*
X1222483D01*
X1221965Y1093173D01*
X1221966Y1093765D01*
X1222220Y1094019D01*
Y1094613D01*
X1221703Y1095130D01*
X1221109Y1095131D01*
X1220855Y1094877D01*
X1220261D01*
X1219743Y1095395D01*
X1219744Y1095987D01*
X1219998Y1096241D01*
Y1096835D01*
X1219481Y1097352D01*
X1218887Y1097353D01*
X1218633Y1097099D01*
X1218039D01*
X1217521Y1097617D01*
X1217522Y1098209D01*
X1217776Y1098463D01*
Y1099057D01*
X1217259Y1099574D01*
X1216665Y1099575D01*
X1216411Y1099321D01*
X1215817D01*
X1213622Y1101516D01*
X1210111D01*
G01X1275931Y1078065D02*
X1243211D01*
X1242451Y1078825D01*
Y1079419D01*
X1243012Y1079980D01*
Y1080574D01*
X1242495Y1081091D01*
X1241901D01*
X1241340Y1080530D01*
X1240746D01*
X1240229Y1081047D01*
Y1081641D01*
X1240790Y1082202D01*
Y1082796D01*
X1240273Y1083313D01*
X1239679D01*
X1239118Y1082752D01*
X1238524D01*
X1238007Y1083269D01*
Y1083863D01*
X1238568Y1084424D01*
Y1085018D01*
X1238051Y1085535D01*
X1237457D01*
X1236896Y1084974D01*
X1236302D01*
X1235785Y1085491D01*
Y1086085D01*
X1236346Y1086646D01*
Y1087240D01*
X1235829Y1087757D01*
X1235235D01*
X1234674Y1087196D01*
X1234080D01*
X1233563Y1087713D01*
Y1088307D01*
X1234124Y1088868D01*
Y1089462D01*
X1233607Y1089979D01*
X1233013D01*
X1232452Y1089418D01*
X1231858D01*
X1231341Y1089935D01*
Y1090529D01*
X1231902Y1091090D01*
Y1091684D01*
X1231385Y1092201D01*
X1230791D01*
X1230230Y1091640D01*
X1229636D01*
X1229119Y1092157D01*
Y1092751D01*
X1229680Y1093312D01*
Y1093906D01*
X1229163Y1094423D01*
X1228569D01*
X1228008Y1093862D01*
X1227414D01*
X1226897Y1094379D01*
Y1094973D01*
X1227458Y1095534D01*
Y1096128D01*
X1226941Y1096645D01*
X1226347D01*
X1225786Y1096084D01*
X1225192D01*
X1224675Y1096601D01*
Y1097195D01*
X1225236Y1097756D01*
Y1098350D01*
X1224719Y1098867D01*
X1224125D01*
X1223564Y1098306D01*
X1222970D01*
X1222453Y1098823D01*
Y1099417D01*
X1223014Y1099978D01*
Y1100572D01*
X1222497Y1101089D01*
X1221903D01*
X1221342Y1100528D01*
X1220748D01*
X1220231Y1101045D01*
Y1101639D01*
X1220792Y1102200D01*
Y1102794D01*
X1220275Y1103311D01*
X1219681D01*
X1219120Y1102750D01*
X1218526D01*
X1218009Y1103267D01*
Y1103861D01*
X1218570Y1104422D01*
Y1105016D01*
X1218053Y1105533D01*
X1217459D01*
X1217062Y1105136D01*
X1215032D01*
X1214612Y1105556D01*
Y1107749D01*
X1214152Y1108209D01*
X1210111D01*
G01X1275201Y1080905D02*
X1246473D01*
X1245674Y1081704D01*
Y1082298D01*
X1245963Y1082587D01*
Y1083181D01*
X1245446Y1083698D01*
X1244852D01*
X1244563Y1083409D01*
X1243969D01*
X1243452Y1083926D01*
Y1084520D01*
X1243741Y1084809D01*
Y1085403D01*
X1243224Y1085920D01*
X1242630D01*
X1242341Y1085631D01*
X1241747D01*
X1241230Y1086148D01*
Y1086742D01*
X1241519Y1087031D01*
Y1087625D01*
X1241002Y1088142D01*
X1240408D01*
X1240119Y1087853D01*
X1239525D01*
X1239008Y1088370D01*
Y1088964D01*
X1239297Y1089253D01*
Y1089847D01*
X1238780Y1090364D01*
X1238186D01*
X1237897Y1090075D01*
X1237303D01*
X1236786Y1090592D01*
Y1091186D01*
X1237075Y1091475D01*
Y1092069D01*
X1236558Y1092586D01*
X1235964D01*
X1235675Y1092297D01*
X1235081D01*
X1234564Y1092814D01*
Y1093408D01*
X1234853Y1093697D01*
Y1094291D01*
X1234336Y1094808D01*
X1233742D01*
X1233453Y1094519D01*
X1232859D01*
X1232342Y1095036D01*
Y1095630D01*
X1232631Y1095919D01*
Y1096513D01*
X1232114Y1097030D01*
X1231520D01*
X1231231Y1096741D01*
X1230637D01*
X1230120Y1097258D01*
Y1097852D01*
X1230409Y1098141D01*
Y1098735D01*
X1229892Y1099252D01*
X1229298D01*
X1229009Y1098963D01*
X1228415D01*
X1227898Y1099480D01*
Y1100074D01*
X1228187Y1100363D01*
Y1100957D01*
X1227670Y1101474D01*
X1227076D01*
X1226787Y1101185D01*
X1226193D01*
X1225676Y1101702D01*
Y1102296D01*
X1225965Y1102585D01*
Y1103179D01*
X1225448Y1103696D01*
X1224854D01*
X1224565Y1103407D01*
X1223971D01*
X1223454Y1103924D01*
Y1104518D01*
X1223743Y1104807D01*
Y1105401D01*
X1223226Y1105918D01*
X1222632D01*
X1222343Y1105629D01*
X1221749D01*
X1221232Y1106146D01*
Y1106740D01*
X1221521Y1107029D01*
Y1107623D01*
X1221004Y1108140D01*
X1220410D01*
X1220121Y1107851D01*
X1219527D01*
X1219010Y1108368D01*
Y1108962D01*
X1219299Y1109251D01*
Y1109845D01*
X1218782Y1110362D01*
X1218188D01*
X1217899Y1110073D01*
X1217305D01*
X1216113Y1111265D01*
X1214571D01*
X1214111Y1111725D01*
Y1114442D01*
X1213651Y1114902D01*
X1210111D01*
G01X1277333Y1090754D02*
X1254080D01*
X1253471Y1091363D01*
X1253470Y1091957D01*
X1253736Y1092223D01*
Y1092817D01*
X1253218Y1093335D01*
X1252626Y1093334D01*
X1252360Y1093068D01*
X1251766D01*
X1251249Y1093585D01*
X1251248Y1094179D01*
X1251514Y1094445D01*
Y1095039D01*
X1250996Y1095557D01*
X1250404Y1095556D01*
X1250138Y1095290D01*
X1249544D01*
X1249027Y1095807D01*
X1249026Y1096401D01*
X1249292Y1096667D01*
Y1097261D01*
X1248774Y1097779D01*
X1248182Y1097778D01*
X1247916Y1097512D01*
X1247322D01*
X1246805Y1098029D01*
X1246804Y1098623D01*
X1247070Y1098889D01*
Y1099483D01*
X1246552Y1100001D01*
X1245960Y1100000D01*
X1245694Y1099734D01*
X1245100D01*
X1244583Y1100251D01*
X1244582Y1100845D01*
X1244848Y1101111D01*
Y1101705D01*
X1244330Y1102223D01*
X1243738Y1102222D01*
X1243472Y1101956D01*
X1242878D01*
X1242361Y1102473D01*
X1242360Y1103067D01*
X1242626Y1103333D01*
Y1103927D01*
X1242108Y1104445D01*
X1241516Y1104444D01*
X1241250Y1104178D01*
X1240656D01*
X1240139Y1104695D01*
X1240138Y1105289D01*
X1240404Y1105555D01*
Y1106149D01*
X1239886Y1106667D01*
X1239294Y1106666D01*
X1239028Y1106400D01*
X1238434D01*
X1237917Y1106917D01*
X1237916Y1107511D01*
X1238182Y1107777D01*
Y1108371D01*
X1237664Y1108889D01*
X1237072Y1108888D01*
X1236806Y1108622D01*
X1236212D01*
X1235695Y1109139D01*
X1235694Y1109733D01*
X1235960Y1109999D01*
Y1110593D01*
X1235442Y1111111D01*
X1234850Y1111110D01*
X1234584Y1110844D01*
X1233990D01*
X1233473Y1111361D01*
X1233472Y1111955D01*
X1233738Y1112221D01*
Y1112815D01*
X1233220Y1113333D01*
X1232628Y1113332D01*
X1232362Y1113066D01*
X1231768D01*
X1231251Y1113583D01*
X1231250Y1114177D01*
X1231516Y1114443D01*
Y1115037D01*
X1230998Y1115555D01*
X1230406Y1115554D01*
X1230140Y1115288D01*
X1229546D01*
X1229029Y1115805D01*
X1229028Y1116399D01*
X1229294Y1116665D01*
Y1117259D01*
X1228776Y1117777D01*
X1228184Y1117776D01*
X1227918Y1117510D01*
X1227324D01*
X1226807Y1118027D01*
X1226806Y1118621D01*
X1227072Y1118887D01*
Y1119481D01*
X1226554Y1119999D01*
X1225962Y1119998D01*
X1225696Y1119732D01*
X1225102D01*
X1224585Y1120249D01*
X1224584Y1120843D01*
X1224850Y1121109D01*
Y1121703D01*
X1224332Y1122221D01*
X1223740Y1122220D01*
X1223474Y1121954D01*
X1222880D01*
X1221780Y1123054D01*
Y1125730D01*
X1215876Y1131634D01*
X1210111D01*
G01X1275359Y1093523D02*
X1274388D01*
X1273968Y1093943D01*
Y1094288D01*
X1273548Y1094708D01*
X1272817D01*
X1272397Y1094288D01*
Y1093943D01*
X1271977Y1093523D01*
X1271246D01*
X1270826Y1093943D01*
Y1094288D01*
X1270406Y1094708D01*
X1269675D01*
X1269255Y1094288D01*
Y1093943D01*
X1268835Y1093523D01*
X1268104D01*
X1267684Y1093943D01*
Y1094288D01*
X1267264Y1094708D01*
X1266533D01*
X1266113Y1094288D01*
Y1093943D01*
X1265693Y1093523D01*
X1264962D01*
X1264542Y1093943D01*
Y1094288D01*
X1264122Y1094708D01*
X1263391D01*
X1262971Y1094288D01*
Y1093943D01*
X1262551Y1093523D01*
X1261820D01*
X1261400Y1093943D01*
Y1094288D01*
X1260980Y1094708D01*
X1260249D01*
X1259829Y1094288D01*
Y1093943D01*
X1259409Y1093523D01*
X1256823D01*
X1256329Y1094017D01*
Y1094885D01*
X1255652Y1095562D01*
X1254784D01*
X1254107Y1096239D01*
Y1097107D01*
X1253430Y1097784D01*
X1252562D01*
X1251885Y1098461D01*
Y1099329D01*
X1251208Y1100006D01*
X1250340D01*
X1249663Y1100683D01*
Y1101551D01*
X1248986Y1102228D01*
X1248118D01*
X1247441Y1102905D01*
Y1103773D01*
X1246764Y1104450D01*
X1245896D01*
X1245219Y1105127D01*
Y1105995D01*
X1244542Y1106672D01*
X1243674D01*
X1242997Y1107349D01*
Y1108217D01*
X1242320Y1108894D01*
X1241452D01*
X1240775Y1109571D01*
Y1110439D01*
X1240098Y1111116D01*
X1239230D01*
X1238553Y1111793D01*
Y1112661D01*
X1237876Y1113338D01*
X1237008D01*
X1236331Y1114015D01*
Y1114883D01*
X1235654Y1115560D01*
X1234786D01*
X1234109Y1116237D01*
Y1117105D01*
X1233432Y1117782D01*
X1232564D01*
X1231887Y1118459D01*
Y1119327D01*
X1231210Y1120004D01*
X1230342D01*
X1229665Y1120681D01*
Y1121549D01*
X1228988Y1122226D01*
X1228120D01*
X1227443Y1122903D01*
Y1123771D01*
X1226766Y1124448D01*
X1225898D01*
X1224460Y1125886D01*
Y1126843D01*
X1216116Y1135187D01*
X1214822D01*
X1214362Y1135647D01*
Y1137867D01*
X1213902Y1138327D01*
X1210111D01*
G01X1275112Y1097881D02*
X1258869D01*
X1224285Y1132465D01*
X1224287Y1133508D01*
X1223769Y1134026D01*
X1222724D01*
X1222135Y1134615D01*
Y1135209D01*
X1224409Y1137483D01*
X1224410Y1138075D01*
X1223892Y1138593D01*
X1223298D01*
X1221024Y1136319D01*
X1220430Y1136320D01*
X1219913Y1136837D01*
Y1137431D01*
X1222861Y1140379D01*
X1222862Y1140971D01*
X1222344Y1141489D01*
X1221750D01*
X1218802Y1138541D01*
X1218208Y1138542D01*
X1217691Y1139059D01*
Y1139653D01*
X1220639Y1142601D01*
X1220640Y1143193D01*
X1220122Y1143711D01*
X1219528D01*
X1216580Y1140763D01*
X1215986Y1140764D01*
X1215352Y1141398D01*
Y1141993D01*
X1217987Y1144628D01*
Y1145278D01*
X1217337Y1145928D01*
X1216037D01*
X1215129Y1145020D01*
X1210111D01*
G01X1275201Y1100650D02*
X1259892D01*
X1227090Y1133452D01*
Y1141378D01*
X1227942Y1142230D01*
Y1144128D01*
X1222195Y1149875D01*
X1221600D01*
X1221084Y1149359D01*
Y1148764D01*
X1226372Y1143476D01*
Y1142882D01*
X1225855Y1142365D01*
X1225261D01*
X1218782Y1148844D01*
X1215032D01*
X1212163Y1151713D01*
X1210111D01*
G01X1275234Y1109594D02*
X1265538D01*
X1237757Y1137375D01*
Y1148913D01*
X1237076Y1149594D01*
Y1150188D01*
X1237734Y1150846D01*
Y1151440D01*
X1237217Y1151957D01*
X1236623D01*
X1235965Y1151299D01*
X1235371D01*
X1234854Y1151816D01*
Y1152410D01*
X1235512Y1153068D01*
Y1153662D01*
X1234995Y1154179D01*
X1234401D01*
X1233743Y1153521D01*
X1233149D01*
X1232632Y1154038D01*
Y1154632D01*
X1233290Y1155290D01*
Y1155884D01*
X1232773Y1156401D01*
X1232179D01*
X1231521Y1155743D01*
X1230927D01*
X1230410Y1156260D01*
Y1156854D01*
X1231068Y1157512D01*
Y1158106D01*
X1230551Y1158623D01*
X1229957D01*
X1229299Y1157965D01*
X1228705D01*
X1228188Y1158482D01*
Y1159076D01*
X1228846Y1159734D01*
Y1160328D01*
X1228329Y1160845D01*
X1227735D01*
X1227077Y1160187D01*
X1226483D01*
X1225966Y1160704D01*
Y1161298D01*
X1226624Y1161956D01*
Y1162550D01*
X1226107Y1163067D01*
X1225513D01*
X1224855Y1162409D01*
X1224261D01*
X1223744Y1162926D01*
Y1163520D01*
X1224402Y1164178D01*
Y1164772D01*
X1223885Y1165289D01*
X1223291D01*
X1222633Y1164631D01*
X1222039D01*
X1221522Y1165148D01*
Y1165742D01*
X1222180Y1166400D01*
Y1166994D01*
X1221663Y1167511D01*
X1221069D01*
X1220411Y1166853D01*
X1219817D01*
X1219264Y1167406D01*
X1215190D01*
X1214151Y1168445D01*
X1210111D01*
G01X1275201Y1114195D02*
X1274077D01*
X1273657Y1113775D01*
Y1112738D01*
X1273237Y1112318D01*
X1272506D01*
X1272086Y1112738D01*
Y1113775D01*
X1271666Y1114195D01*
X1270935D01*
X1270515Y1113775D01*
Y1112738D01*
X1270095Y1112318D01*
X1269364D01*
X1268944Y1112738D01*
Y1113775D01*
X1268524Y1114195D01*
X1267793D01*
X1267373Y1113775D01*
Y1113122D01*
X1266953Y1112702D01*
X1266222D01*
X1265802Y1113122D01*
Y1113775D01*
X1265382Y1114195D01*
X1264729D01*
X1240464Y1138460D01*
Y1152536D01*
X1222301Y1170699D01*
X1219538D01*
X1219118Y1171119D01*
Y1172748D01*
X1218698Y1173168D01*
X1217967D01*
X1217547Y1172748D01*
Y1171119D01*
X1217127Y1170699D01*
X1216418D01*
X1214661Y1172456D01*
Y1174678D01*
X1214201Y1175138D01*
X1210111D01*
G01X1276296Y1117370D02*
X1265996D01*
X1243635Y1139731D01*
Y1153808D01*
X1242512Y1154931D01*
Y1155525D01*
X1243219Y1156232D01*
Y1156826D01*
X1242702Y1157343D01*
X1242108D01*
X1241401Y1156636D01*
X1240807D01*
X1240290Y1157153D01*
Y1157747D01*
X1240997Y1158454D01*
Y1159048D01*
X1240480Y1159565D01*
X1239886D01*
X1239179Y1158858D01*
X1238585D01*
X1238068Y1159375D01*
Y1159969D01*
X1238775Y1160676D01*
Y1161270D01*
X1238258Y1161787D01*
X1237664D01*
X1236957Y1161080D01*
X1236363D01*
X1235846Y1161597D01*
Y1162191D01*
X1236553Y1162898D01*
Y1163492D01*
X1236036Y1164009D01*
X1235442D01*
X1234735Y1163302D01*
X1234141D01*
X1233624Y1163819D01*
Y1164413D01*
X1234331Y1165120D01*
Y1165714D01*
X1233814Y1166231D01*
X1233220D01*
X1232513Y1165524D01*
X1231919D01*
X1231402Y1166041D01*
Y1166635D01*
X1232109Y1167342D01*
Y1167936D01*
X1231592Y1168453D01*
X1230998D01*
X1230291Y1167746D01*
X1229697D01*
X1229180Y1168263D01*
Y1168857D01*
X1229887Y1169564D01*
Y1170158D01*
X1229370Y1170675D01*
X1228776D01*
X1228069Y1169968D01*
X1227475D01*
X1226958Y1170485D01*
Y1171079D01*
X1227665Y1171786D01*
Y1172380D01*
X1227148Y1172897D01*
X1226554D01*
X1225847Y1172190D01*
X1225253D01*
X1224736Y1172707D01*
Y1173301D01*
X1225443Y1174008D01*
Y1174602D01*
X1224926Y1175119D01*
X1224332D01*
X1223625Y1174412D01*
X1223031D01*
X1222514Y1174929D01*
Y1175523D01*
X1223221Y1176230D01*
Y1176824D01*
X1222704Y1177341D01*
X1222110D01*
X1221403Y1176634D01*
X1220809D01*
X1220292Y1177151D01*
Y1177745D01*
X1220999Y1178452D01*
Y1179046D01*
X1220482Y1179563D01*
X1219888D01*
X1219181Y1178856D01*
X1218587D01*
X1218070Y1179373D01*
Y1179967D01*
X1218777Y1180674D01*
Y1181268D01*
X1218260Y1181785D01*
X1217666D01*
X1216959Y1181078D01*
X1216365D01*
X1215612Y1181831D01*
X1210111D01*
G01X1275201Y1120050D02*
X1267108D01*
X1246315Y1140843D01*
Y1157523D01*
X1245509Y1158329D01*
X1245510Y1158921D01*
X1245914Y1159325D01*
Y1159919D01*
X1245397Y1160436D01*
X1244803Y1160437D01*
X1244399Y1160033D01*
X1243805D01*
X1243287Y1160551D01*
X1243288Y1161143D01*
X1243692Y1161547D01*
Y1162141D01*
X1243175Y1162658D01*
X1242581Y1162659D01*
X1242177Y1162255D01*
X1241583D01*
X1241065Y1162773D01*
X1241066Y1163365D01*
X1241470Y1163769D01*
Y1164363D01*
X1240953Y1164880D01*
X1240359Y1164881D01*
X1239955Y1164477D01*
X1239361D01*
X1238843Y1164995D01*
X1238844Y1165587D01*
X1239248Y1165991D01*
Y1166585D01*
X1238731Y1167102D01*
X1238137Y1167103D01*
X1237733Y1166699D01*
X1237139D01*
X1236621Y1167217D01*
X1236622Y1167809D01*
X1237026Y1168213D01*
Y1168807D01*
X1236509Y1169324D01*
X1235915Y1169325D01*
X1235511Y1168921D01*
X1234917D01*
X1234399Y1169439D01*
X1234400Y1170031D01*
X1234804Y1170435D01*
Y1171029D01*
X1234287Y1171546D01*
X1233693Y1171547D01*
X1233289Y1171143D01*
X1232695D01*
X1232177Y1171661D01*
X1232178Y1172253D01*
X1232582Y1172657D01*
Y1173251D01*
X1232065Y1173768D01*
X1231471Y1173769D01*
X1231067Y1173365D01*
X1230473D01*
X1229955Y1173883D01*
X1229956Y1174475D01*
X1230360Y1174879D01*
Y1175473D01*
X1229843Y1175990D01*
X1229249Y1175991D01*
X1228845Y1175587D01*
X1228251D01*
X1227733Y1176105D01*
X1227734Y1176697D01*
X1228138Y1177101D01*
Y1177695D01*
X1227621Y1178212D01*
X1227027Y1178213D01*
X1226623Y1177809D01*
X1226029D01*
X1225511Y1178327D01*
X1225512Y1178919D01*
X1225916Y1179323D01*
Y1179917D01*
X1225399Y1180434D01*
X1224805Y1180435D01*
X1224401Y1180031D01*
X1223807D01*
X1223289Y1180549D01*
X1223290Y1181141D01*
X1223694Y1181545D01*
Y1182139D01*
X1223177Y1182656D01*
X1222583Y1182657D01*
X1222179Y1182253D01*
X1221585D01*
X1221067Y1182771D01*
X1221068Y1183363D01*
X1221472Y1183767D01*
Y1184361D01*
X1220955Y1184878D01*
X1220361Y1184879D01*
X1219957Y1184475D01*
X1219362D01*
X1218993Y1184844D01*
X1215951D01*
X1215367Y1185428D01*
Y1187279D01*
X1214122Y1188524D01*
X1210111D01*
G01X1275741Y1129065D02*
X1270767D01*
X1255190Y1144642D01*
Y1167137D01*
X1253718Y1168609D01*
Y1169203D01*
X1254003Y1169488D01*
Y1170082D01*
X1253486Y1170599D01*
X1252892D01*
X1252607Y1170314D01*
X1252013D01*
X1251496Y1170831D01*
Y1171425D01*
X1251781Y1171710D01*
Y1172304D01*
X1251264Y1172821D01*
X1250670D01*
X1250385Y1172536D01*
X1249791D01*
X1249274Y1173053D01*
Y1173647D01*
X1249559Y1173932D01*
Y1174526D01*
X1249042Y1175043D01*
X1248448D01*
X1248163Y1174758D01*
X1247569D01*
X1247052Y1175275D01*
Y1175869D01*
X1247337Y1176154D01*
Y1176748D01*
X1246820Y1177265D01*
X1246226D01*
X1245941Y1176980D01*
X1245347D01*
X1244830Y1177497D01*
Y1178091D01*
X1245115Y1178376D01*
Y1178970D01*
X1244598Y1179487D01*
X1244004D01*
X1243719Y1179202D01*
X1243125D01*
X1242608Y1179719D01*
Y1180313D01*
X1242893Y1180598D01*
Y1181192D01*
X1242376Y1181709D01*
X1241782D01*
X1241497Y1181424D01*
X1240903D01*
X1240386Y1181941D01*
Y1182535D01*
X1240671Y1182820D01*
Y1183414D01*
X1240154Y1183931D01*
X1239560D01*
X1239275Y1183646D01*
X1238681D01*
X1238164Y1184163D01*
Y1184757D01*
X1238449Y1185042D01*
Y1185636D01*
X1237932Y1186153D01*
X1237338D01*
X1237053Y1185868D01*
X1236459D01*
X1235942Y1186385D01*
Y1186979D01*
X1236227Y1187264D01*
Y1187858D01*
X1235710Y1188375D01*
X1235116D01*
X1234831Y1188090D01*
X1234237D01*
X1233720Y1188607D01*
Y1189201D01*
X1234005Y1189486D01*
Y1190080D01*
X1233488Y1190597D01*
X1232894D01*
X1232609Y1190312D01*
X1232015D01*
X1231498Y1190829D01*
Y1191423D01*
X1231783Y1191708D01*
Y1192302D01*
X1231266Y1192819D01*
X1230672D01*
X1230387Y1192534D01*
X1229793D01*
X1229276Y1193051D01*
Y1193645D01*
X1229561Y1193930D01*
Y1194524D01*
X1229044Y1195041D01*
X1228450D01*
X1228165Y1194756D01*
X1227571D01*
X1227054Y1195273D01*
Y1195867D01*
X1227339Y1196152D01*
Y1196746D01*
X1226822Y1197263D01*
X1226228D01*
X1225943Y1196978D01*
X1225349D01*
X1224832Y1197495D01*
Y1198089D01*
X1225117Y1198374D01*
Y1198968D01*
X1224600Y1199485D01*
X1224006D01*
X1223721Y1199200D01*
X1223127D01*
X1222610Y1199717D01*
Y1200311D01*
X1222895Y1200596D01*
Y1201190D01*
X1222378Y1201707D01*
X1221784D01*
X1221499Y1201422D01*
X1220905D01*
X1217071Y1205256D01*
X1210111D01*
G01X1275201Y1132266D02*
X1271358D01*
X1257870Y1145754D01*
Y1170008D01*
X1257004Y1170874D01*
Y1172060D01*
X1256486Y1172578D01*
X1255300D01*
X1254782Y1173096D01*
Y1174282D01*
X1254264Y1174800D01*
X1253078D01*
X1252560Y1175318D01*
Y1176504D01*
X1252042Y1177022D01*
X1250856D01*
X1250338Y1177540D01*
Y1178726D01*
X1249820Y1179244D01*
X1248634D01*
X1248116Y1179762D01*
Y1180948D01*
X1247598Y1181466D01*
X1246412D01*
X1245894Y1181984D01*
Y1183170D01*
X1245376Y1183688D01*
X1244190D01*
X1243672Y1184206D01*
Y1185392D01*
X1243154Y1185910D01*
X1241968D01*
X1241450Y1186428D01*
Y1187614D01*
X1240932Y1188132D01*
X1239746D01*
X1239228Y1188650D01*
Y1189836D01*
X1238710Y1190354D01*
X1237524D01*
X1237006Y1190872D01*
Y1192058D01*
X1236488Y1192576D01*
X1235302D01*
X1234784Y1193094D01*
Y1194280D01*
X1234266Y1194798D01*
X1233080D01*
X1232562Y1195316D01*
Y1196502D01*
X1232044Y1197020D01*
X1230858D01*
X1230340Y1197538D01*
Y1198724D01*
X1229822Y1199242D01*
X1228636D01*
X1228118Y1199760D01*
Y1200946D01*
X1227600Y1201464D01*
X1226414D01*
X1225896Y1201982D01*
Y1203168D01*
X1225378Y1203686D01*
X1224192D01*
X1223674Y1204204D01*
Y1205390D01*
X1223156Y1205908D01*
X1221970D01*
X1221452Y1206426D01*
Y1207612D01*
X1220934Y1208130D01*
X1219748D01*
X1217990Y1209888D01*
X1217396D01*
X1216943Y1209435D01*
X1216349Y1209436D01*
X1215832Y1209953D01*
Y1210547D01*
X1216285Y1211000D01*
X1216286Y1211592D01*
X1215929Y1211949D01*
X1210111D01*
G01X1275301Y1135565D02*
X1272501D01*
X1261010Y1147056D01*
Y1173696D01*
X1220027Y1214679D01*
Y1215329D01*
X1220488Y1215790D01*
X1221138D01*
X1229197Y1207731D01*
X1229847D01*
X1230308Y1208192D01*
Y1208842D01*
X1221138Y1218012D01*
X1220488D01*
X1218916Y1216440D01*
X1218266D01*
X1216064Y1218642D01*
X1210111D01*
G01X1275201Y1138765D02*
X1273501D01*
X1263690Y1148576D01*
Y1174808D01*
X1235227Y1203271D01*
Y1203921D01*
X1235688Y1204382D01*
X1236338D01*
X1241213Y1199507D01*
X1241863D01*
X1242324Y1199968D01*
Y1200618D01*
X1236338Y1206604D01*
X1235688D01*
X1234116Y1205032D01*
X1233466D01*
X1232988Y1205510D01*
Y1209954D01*
X1217607Y1225335D01*
X1210111D01*
G01X1275454Y1151030D02*
X1273871Y1152613D01*
Y1183617D01*
X1220345Y1237143D01*
Y1237737D01*
X1220862Y1238254D01*
X1221456D01*
X1226844Y1232866D01*
X1227494D01*
X1227955Y1233327D01*
Y1233977D01*
X1220868Y1241064D01*
X1220218D01*
X1219042Y1239888D01*
X1218448D01*
X1216269Y1242067D01*
X1210111D01*
G01X1276551Y1153875D02*
Y1184729D01*
X1236941Y1224339D01*
Y1224989D01*
X1237402Y1225450D01*
X1238052D01*
X1241479Y1222023D01*
X1242129D01*
X1242590Y1222484D01*
Y1223134D01*
X1238052Y1227672D01*
X1237402D01*
X1235830Y1226100D01*
X1235180D01*
X1234065Y1227215D01*
Y1231659D01*
X1216964Y1248760D01*
X1210111D01*
G01X1200075Y1396500D02*
X1200632D01*
X1203272Y1399140D01*
G01D02*
X1205677Y1401545D01*
Y1404415D01*
X1208100Y1406838D01*
Y1410700D01*
X1208739Y1411339D01*
X1209681D01*
G01Y1412913D02*
X1208513D01*
X1206300Y1410700D01*
Y1407094D01*
X1204129Y1404923D01*
X1202439D01*
X1200075Y1402559D01*
Y1401000D01*
G01Y1414500D02*
X1200302D01*
X1203242Y1417440D01*
G01D02*
X1206039D01*
X1206237Y1417638D01*
X1209681D01*
G01X1200075Y1405500D02*
X1200595D01*
X1202548Y1407453D01*
G01D02*
X1203400Y1408305D01*
Y1410000D01*
X1207888Y1414488D01*
X1209681D01*
G01X1200075Y1410000D02*
X1200403D01*
X1202857Y1412454D01*
G01D02*
X1205203Y1414800D01*
X1205799D01*
X1207062Y1416063D01*
X1209681D01*
G01Y1422362D02*
X1206769D01*
X1202411Y1426720D01*
Y1427410D01*
G01D02*
X1201321Y1428500D01*
X1200075D01*
G01Y1424000D02*
X1201569D01*
X1203117Y1422452D01*
G01D02*
X1204296Y1421273D01*
X1205837D01*
X1206323Y1420787D01*
X1209681D01*
G01X1203040Y1437500D02*
X1204701Y1435839D01*
Y1430392D01*
X1205968Y1427332D01*
X1207788Y1425512D01*
X1209681D01*
G01X1200075Y1433000D02*
X1201943D01*
X1202475Y1432468D01*
G01D02*
X1203174Y1431769D01*
Y1430351D01*
X1204819Y1426381D01*
X1207263Y1423937D01*
X1209681D01*
G01X1204492Y1442500D02*
Y1439551D01*
X1206270Y1437773D01*
Y1430642D01*
X1207268Y1428232D01*
X1208413Y1427087D01*
X1209681D01*
G01X1204664Y1447500D02*
X1207500Y1444664D01*
Y1430892D01*
X1208017Y1429644D01*
X1209000Y1428661D01*
X1209681D01*
G01X1200075Y1437500D02*
X1203040D01*
G01X1200075Y1442500D02*
X1204492D01*
G01X1200075Y1447500D02*
X1204664D01*
G01X1210513Y1685399D02*
Y1689268D01*
X1211104Y1689859D01*
G01X1210513Y1677919D02*
X1213072D01*
G01D02*
Y1673059D01*
G01X1208272D02*
X1213072D01*
G01X1207954Y1685399D02*
Y1689859D01*
G01X1211804Y1693859D02*
Y1690559D01*
X1211104Y1689859D01*
G01X1211804Y1697859D02*
Y1693859D01*
G01X1212954Y1703343D02*
X1212246Y1702635D01*
Y1698301D01*
X1211804Y1697859D01*
G01X1207954D02*
Y1693859D01*
G01D02*
Y1689859D01*
G01Y1703343D02*
Y1697859D01*
G01X1214254Y1713861D02*
X1210254D01*
G01X1219738D02*
X1214254D01*
G01X1210254D02*
X1203347D01*
X1201747Y1712261D01*
G01X1210254Y1710011D02*
X1214254D01*
G01X1219738Y1708861D02*
X1218588Y1710011D01*
X1214254D01*
G01X1201747Y1709702D02*
X1202056Y1710011D01*
X1210254D01*
G01X1219738Y1722861D02*
X1218588Y1724011D01*
X1214254D01*
G01D02*
X1210254D01*
G01X1201794Y1723702D02*
X1205245D01*
X1206254Y1724711D01*
G01X1210254Y1724011D02*
X1208378D01*
X1207678Y1724711D01*
X1206254D01*
G01X1219738Y1727861D02*
X1214254D01*
G01D02*
X1210254D01*
G01D02*
X1206254D01*
G01D02*
X1203394D01*
X1201794Y1726261D01*
G01X1215581Y85771D02*
X1216943D01*
X1233404Y69310D01*
Y60384D01*
G01X1223455Y85771D02*
X1228318D01*
X1238769Y75320D01*
G01X1230312Y94210D02*
X1227803D01*
G01X1230693Y150239D02*
X1225193D01*
X1224193Y149239D01*
Y145739D01*
G01X1222094Y269008D02*
Y274108D01*
G01Y277848D02*
Y282948D01*
G01X1225654Y431875D02*
X1232154D01*
G01X1225654Y441875D02*
X1232154D01*
G01X1225654Y436875D02*
X1232154D01*
G01X1241278Y60384D02*
Y72811D01*
X1238769Y75320D01*
G01X1236909Y94210D02*
X1230312D01*
G01X1234268Y145239D02*
Y149164D01*
X1233193Y150239D01*
X1230693D01*
G01X1234268Y145239D02*
X1241618D01*
G01X1249107Y163551D02*
X1246607D01*
X1245441Y164717D01*
X1242226D01*
G01X1249107Y184051D02*
Y184050D01*
X1245129Y180072D01*
X1242226D01*
G01X1249107Y170551D02*
X1246607D01*
X1245891Y169835D01*
X1242226D01*
G01Y167276D02*
X1253107D01*
G01Y174051D02*
X1247107D01*
X1245451Y172395D01*
X1242226D01*
G01X1238094Y274108D02*
Y269008D01*
G01X1230094D02*
Y274108D01*
G01Y277848D02*
Y282948D01*
G01X1240029Y427255D02*
X1242429D01*
G01X1236879D02*
Y431255D01*
G01D02*
X1232774D01*
X1232154Y431875D01*
G01X1240029Y439255D02*
X1242429D01*
G01X1236879Y443255D02*
X1233534D01*
X1232154Y441875D01*
G01X1236879Y439255D02*
Y435255D01*
G01D02*
X1233774D01*
X1232154Y436875D01*
G01X1238338Y460376D02*
X1242993D01*
X1245187Y458182D01*
G01X1238338Y455376D02*
X1242993D01*
X1245187Y453182D01*
G01X1238338Y465376D02*
X1244497D01*
X1246715Y463158D01*
G01X1245425Y1414500D02*
X1241613D01*
G01D02*
X1240500D01*
X1238500Y1416500D01*
X1235616D01*
X1234478Y1417638D01*
X1232319D01*
G01Y1419213D02*
X1235374D01*
X1235679Y1418908D01*
G01X1249152Y60384D02*
Y72895D01*
G01X1259472Y87289D02*
Y85640D01*
X1249152Y75320D01*
Y72895D01*
G01X1253152Y90470D02*
X1255661D01*
G01X1246555D02*
X1253152D01*
G01X1259835Y135053D02*
X1254501D01*
X1251815Y137739D01*
X1249431D01*
G01X1252693Y124739D02*
X1253693D01*
X1256507Y127553D01*
X1259835D01*
G01X1252693Y124739D02*
X1252494Y124540D01*
X1245569D01*
X1244768Y123739D01*
G01X1249693Y145053D02*
X1244954D01*
X1244768Y145239D01*
G01X1259835Y145053D02*
X1249693D01*
G01X1249431Y137739D02*
X1245268D01*
X1244768Y137239D01*
G01X1253107Y167276D02*
X1254807D01*
X1258032Y164051D01*
G01X1269437Y162051D02*
X1265437Y166051D01*
X1260032D01*
X1258032Y164051D01*
G01X1269437Y158051D02*
X1265493Y161995D01*
X1259976D01*
X1258032Y160051D01*
G01D02*
X1254532Y163551D01*
X1249107D01*
G01X1258032Y168051D02*
X1255532Y170551D01*
X1249107D01*
G01X1269437Y166051D02*
Y168051D01*
X1267437Y170051D01*
X1260107D01*
X1258107Y168051D01*
X1258032D01*
G01X1269437Y171551D02*
X1266729D01*
X1264229Y174051D01*
X1260032D01*
X1258032Y172051D01*
G01D02*
X1256032Y174051D01*
X1253107D01*
G01X1269437Y184987D02*
X1266873Y187551D01*
X1259607D01*
X1258032Y185976D01*
Y185051D01*
G01D02*
X1256422D01*
X1255422Y184051D01*
X1249107D01*
G01X1255315Y236594D02*
X1249065D01*
G01X1255315Y251594D02*
X1249065D01*
G01X1255315Y246594D02*
X1249065D01*
G01X1255315Y241594D02*
X1249065D01*
G01X1246094Y274108D02*
Y269008D01*
G01X1254094Y274108D02*
Y269008D01*
G01Y277848D02*
Y282948D01*
G01X1270474Y390884D02*
X1268858Y392500D01*
X1258500D01*
G01X1254872Y464372D02*
X1247929D01*
X1246715Y463158D01*
G01X1253137Y458182D02*
X1255137D01*
X1256137Y459182D01*
G01X1253137Y453182D02*
X1255447D01*
X1256137Y453872D01*
G01X1245187Y458182D02*
X1249987D01*
G01D02*
Y460087D01*
X1251500Y461600D01*
X1258000D01*
X1258872Y460728D01*
Y459182D01*
G01X1245187Y453182D02*
X1249987D01*
G01D02*
Y451277D01*
X1250600Y450664D01*
X1258000D01*
X1258942Y451606D01*
Y454372D01*
G01X1256785Y757865D02*
X1259075Y760155D01*
Y765000D01*
G01X1294086Y877481D02*
Y873147D01*
X1296071Y871162D01*
X1297000D01*
X1319820Y848342D01*
Y829745D01*
X1259075Y769000D01*
G01D02*
Y765000D01*
G01X1271042Y1418748D02*
X1262794Y1410500D01*
X1248575D01*
G01X1245425D02*
Y1414500D01*
G01X1259472Y87289D02*
X1263472D01*
G01X1272536Y150030D02*
X1267611D01*
G01D02*
Y152884D01*
X1268757Y154030D01*
X1272536D01*
G01X1272587Y158051D02*
Y154081D01*
X1272536Y154030D01*
G01X1272587Y162051D02*
X1274442Y163906D01*
X1279038D01*
X1281128Y161816D01*
G01X1272587Y166051D02*
Y167293D01*
X1274003Y168709D01*
X1280593D01*
X1280901Y168401D01*
G01X1272587Y171551D02*
Y172856D01*
X1273407Y173676D01*
X1280684D01*
X1280791Y173783D01*
G01X1272587Y184987D02*
Y186031D01*
X1273607Y187051D01*
X1279032D01*
X1281570Y184513D01*
G01X1262094Y274108D02*
Y269008D01*
G01X1270094D02*
Y274108D01*
G01X1262094Y277848D02*
Y282948D01*
G01X1270094Y277848D02*
Y282948D01*
G01X1280524Y390884D02*
Y387524D01*
X1278000Y385000D01*
X1274000D01*
G01X1265575Y390500D02*
Y389000D01*
X1266075Y388500D01*
X1272454D01*
X1273624Y389670D01*
Y390884D01*
G01X1262425Y390500D02*
X1260703D01*
X1259659Y389456D01*
G01X1274390Y405741D02*
X1272793D01*
X1270580Y403528D01*
Y400447D01*
X1269258Y399125D01*
G01D02*
X1265777D01*
G01X1273624Y390884D02*
Y392076D01*
X1272457Y393243D01*
Y394559D01*
G01D02*
Y402674D01*
X1273555Y403772D01*
X1274390D01*
G01X1262627Y399125D02*
X1260107D01*
G01X1262624Y395125D02*
Y399122D01*
X1262627Y399125D01*
G01X1269229Y407865D02*
X1271875D01*
X1272031Y407709D01*
X1274390D01*
G01X1269229Y407865D02*
X1266517D01*
X1265777Y407125D01*
G01Y415125D02*
Y411125D01*
G01D02*
X1269410D01*
X1269413Y411128D01*
X1269840D01*
G01D02*
X1271401D01*
X1272851Y409678D01*
X1274390D01*
G01X1272825Y416295D02*
X1274259D01*
X1276949Y413605D01*
Y412237D01*
G01X1263706Y757865D02*
X1261263Y760308D01*
Y763338D01*
X1262925Y765000D01*
G01X1303338Y874292D02*
Y870950D01*
X1324060Y850228D01*
Y823921D01*
X1273677Y773538D01*
Y765063D01*
G01X1295937Y874292D02*
X1296869D01*
X1321940Y849221D01*
Y828439D01*
X1264895Y771394D01*
Y769106D01*
G01D02*
X1262925Y767136D01*
Y765000D01*
G01X1270149Y1544505D02*
X1270972Y1545328D01*
X1271450D01*
X1272051Y1545929D01*
X1273168D01*
X1275975Y1543122D01*
X1280796D01*
X1284318Y1539600D01*
X1286223D01*
G01X1273046Y1548083D02*
X1274701Y1547073D01*
G01X1273046Y1550445D02*
X1274645Y1549336D01*
G01X1286223Y1536100D02*
X1285883D01*
X1280324Y1541659D01*
X1277198D01*
X1274156Y1538617D01*
X1270641D01*
X1268968Y1540290D01*
Y1542459D01*
G01X1273046Y1555169D02*
X1277497Y1559620D01*
X1280753D01*
X1282992Y1561859D01*
X1283967Y1562263D01*
X1287267D01*
X1289577Y1559953D01*
G01X1284577D02*
X1283259Y1558635D01*
X1277757D01*
X1274507Y1555385D01*
Y1554268D01*
X1273046Y1552807D01*
G01Y1564618D02*
X1274997D01*
G01X1273046Y1562256D02*
X1273604Y1561698D01*
X1274908D01*
G01X1281223Y1571370D02*
X1280217D01*
X1278463Y1569616D01*
Y1568577D01*
X1275966Y1566080D01*
X1274163D01*
X1273882Y1565799D01*
X1271001D01*
G01Y1563437D02*
X1273854D01*
X1274133Y1563158D01*
X1276014D01*
X1276751Y1563895D01*
Y1565140D01*
X1279881Y1568270D01*
X1281223D01*
G01X1273692Y1573477D02*
X1278846Y1578631D01*
X1280145Y1581767D01*
Y1582626D01*
X1280982Y1584647D01*
Y1586145D01*
X1279777Y1587350D01*
X1279453D01*
G01X1276253Y1591650D02*
X1274113D01*
X1273123Y1590660D01*
Y1578668D01*
X1270149Y1575694D01*
Y1571431D01*
G01X1269153Y1588510D02*
X1270403D01*
X1271703Y1587210D01*
Y1579630D01*
X1268968Y1576895D01*
Y1573477D01*
G01X1273046Y1569343D02*
X1274699D01*
X1274996Y1569640D01*
G01X1273046Y1566980D02*
X1273606Y1567540D01*
X1274996D01*
G01X1276253Y1591650D02*
Y1593204D01*
X1274937Y1594520D01*
X1272490D01*
G01X1262253Y1588300D02*
X1264293Y1590340D01*
X1265783D01*
G01D02*
X1267323D01*
X1269153Y1588510D01*
G01X1267530Y1598620D02*
X1273390D01*
X1279453Y1592557D01*
Y1587350D01*
G01X1284764Y92229D02*
Y88259D01*
X1283465Y86960D01*
G01X1299439Y92812D02*
X1291635Y85008D01*
X1285417D01*
X1283465Y86960D01*
G01X1275964Y95379D02*
Y90706D01*
X1275981Y90689D01*
G01X1284764Y92229D02*
X1280764D01*
G01Y95379D02*
X1275964D01*
G01X1295118Y125739D02*
X1293118Y123739D01*
X1286073D01*
X1284593Y122259D01*
G01D02*
Y125683D01*
X1282723Y127553D01*
X1280741D01*
G01X1287693Y128239D02*
X1285693D01*
X1283879Y130053D01*
X1280741D01*
G01X1295118Y129739D02*
X1293618Y128239D01*
X1287693D01*
G01X1290193Y132739D02*
X1289054Y131600D01*
X1284960D01*
X1284007Y132553D01*
X1280741D01*
G01X1287693Y137239D02*
X1284693D01*
X1284379Y137553D01*
X1280741D01*
G01X1295118Y137739D02*
X1292342D01*
X1291842Y137239D01*
X1287693D01*
G01X1290193Y141739D02*
X1287693D01*
X1286007Y140053D01*
X1280741D01*
G01X1275686Y154030D02*
X1276238Y153478D01*
X1277484D01*
X1278050Y152912D01*
G01X1296032Y162051D02*
X1294177Y163906D01*
X1288387D01*
X1286532Y162051D01*
G01D02*
X1286297Y161816D01*
X1281128D01*
G01X1275737Y162051D02*
X1277190D01*
X1278211Y161030D01*
G01X1275737Y158051D02*
X1276190D01*
X1278211Y156030D01*
G01X1296032Y166051D02*
Y166958D01*
X1294682Y168308D01*
X1287686D01*
X1286532Y167154D01*
Y166051D01*
G01X1280901Y168401D02*
X1282290D01*
X1284496Y166195D01*
X1286388D01*
X1286532Y166051D01*
G01X1275737D02*
X1278137D01*
G01X1286532Y171551D02*
X1284866D01*
X1282634Y173783D01*
X1280791D01*
G01X1286532Y171551D02*
X1286758Y171777D01*
Y172555D01*
X1288058Y173855D01*
X1294594D01*
X1296032Y172417D01*
Y171551D01*
G01X1275737D02*
X1278137D01*
G01X1296032Y184051D02*
X1294143Y185940D01*
X1288321D01*
X1286532Y184151D01*
Y184051D01*
G01D02*
X1282032D01*
X1281570Y184513D01*
G01X1275737Y184987D02*
X1278137D01*
G01X1278094Y269008D02*
Y274108D01*
G01X1286094Y269008D02*
Y274108D01*
G01X1278094Y277848D02*
Y282948D01*
G01X1286094Y277848D02*
Y282948D01*
G01X1277457Y396165D02*
X1278918Y397626D01*
Y401213D01*
G01X1282458Y396184D02*
X1280886Y397756D01*
Y401213D01*
G01X1287340Y397279D02*
X1285991Y398628D01*
X1284869D01*
X1282855Y400642D01*
Y401213D01*
G01X1275585Y393597D02*
Y392673D01*
X1277374Y390884D01*
G01X1276949Y401213D02*
Y399383D01*
X1275082Y397516D01*
Y394100D01*
X1275585Y393597D01*
G01X1280886Y421145D02*
Y412237D01*
G01X1277738Y417241D02*
X1278918Y416061D01*
Y412237D01*
G01X1281677Y756588D02*
Y675123D01*
X1298000Y658800D01*
Y657500D01*
G01X1312590Y877481D02*
Y866242D01*
X1327064Y851768D01*
Y822831D01*
X1285677Y781444D01*
Y672722D01*
X1303250Y655149D01*
G01X1281677Y761913D02*
Y756588D01*
G01Y765063D02*
X1277677D01*
G01Y770388D02*
Y765063D01*
G01X1307039Y874292D02*
Y869475D01*
X1325693Y850821D01*
Y823796D01*
X1281677Y779780D01*
Y774388D01*
X1277677Y770388D01*
G01X1288677Y762063D02*
X1288769Y761971D01*
X1290450D01*
X1290983Y762504D01*
X1292586D01*
X1292677Y762413D01*
G01X1290386Y877481D02*
X1288549Y876434D01*
G01X1311715Y1221042D02*
X1286902D01*
X1278915Y1213055D01*
Y1190611D01*
X1285082Y1184444D01*
Y1163729D01*
X1287866Y1160945D01*
G01X1289716Y1157756D02*
Y1161736D01*
X1288525Y1162927D01*
X1287533D01*
X1286273Y1164187D01*
Y1165659D01*
X1289215Y1168601D01*
X1291499D01*
X1317645Y1194747D01*
Y1218435D01*
X1318776Y1219566D01*
G01X1276500Y1432000D02*
X1278500Y1434000D01*
X1281525D01*
G01Y1430000D02*
X1279525Y1432000D01*
G01X1284675Y1430000D02*
X1286000D01*
X1287700Y1431700D01*
G01X1284675Y1434000D02*
X1289400D01*
X1291700Y1431700D01*
G01X1286223Y1539600D02*
Y1539202D01*
X1287425Y1538000D01*
X1291423D01*
G01X1290873Y1554750D02*
X1290349Y1554745D01*
X1289395Y1555688D01*
Y1557012D01*
X1288835Y1557572D01*
X1286624Y1558488D01*
X1286042D01*
X1284577Y1559953D01*
G01X1281223Y1568270D02*
Y1566725D01*
X1281854Y1566094D01*
X1296333D01*
X1297034Y1566795D01*
X1301036D01*
X1301980Y1565851D01*
G01X1276253Y1586650D02*
X1275095D01*
X1274543Y1586098D01*
Y1580146D01*
X1275170Y1579519D01*
G01X1276253Y1589550D02*
Y1586650D01*
G01X1296200Y61336D02*
Y56536D01*
G01X1301710Y60741D02*
Y58889D01*
X1299357Y56536D01*
X1296200D01*
G01X1301705Y72342D02*
Y66652D01*
X1301710Y66647D01*
G01X1301705Y77748D02*
Y72342D01*
G01Y80307D02*
X1300097D01*
X1299196Y79406D01*
Y76209D01*
G01X1305091Y123680D02*
X1297177D01*
X1295118Y125739D01*
G01X1305091Y127830D02*
X1297027D01*
X1295118Y129739D01*
G01X1305091Y131750D02*
X1297107D01*
X1295118Y133739D01*
G01D02*
X1291193D01*
X1290193Y132739D01*
G01X1313011Y135820D02*
X1311092Y137739D01*
X1298268D01*
G01Y141739D02*
X1298494Y141965D01*
X1310891D01*
X1313011Y139845D01*
G01X1295118Y141739D02*
X1290193D01*
G01X1294094Y269008D02*
Y274108D01*
G01X1302094Y269008D02*
Y274108D01*
G01X1294094Y277848D02*
Y282948D01*
G01X1302094Y277848D02*
Y282948D01*
G01X1300307Y541634D02*
X1295464Y536791D01*
G01X1307217Y537299D02*
Y538263D01*
X1305971Y539509D01*
X1300726D01*
X1295486Y534269D01*
G01X1315411Y549885D02*
X1313826D01*
X1305575Y541634D01*
X1300307D01*
G01X1302500Y664500D02*
X1292677Y674323D01*
Y762413D01*
G01X1305100Y662100D02*
Y665399D01*
X1296677Y673822D01*
Y762413D01*
G01X1300677Y762063D02*
X1297027D01*
X1296677Y762413D01*
G01X1290677Y771388D02*
Y767563D01*
X1292677Y765563D01*
G01X1314441Y874292D02*
Y866741D01*
X1328684Y852498D01*
Y822159D01*
X1292677Y786152D01*
Y778688D01*
X1290677Y776688D01*
Y771388D01*
G01X1296677Y770888D02*
Y765563D01*
G01X1318142Y874292D02*
Y865442D01*
X1330304Y853280D01*
Y821487D01*
X1296677Y787860D01*
Y770888D01*
G01X1299638Y880670D02*
X1297800Y879623D01*
G01X1301488Y877481D02*
X1299650Y876434D01*
G01X1292236Y880670D02*
X1290399Y879623D01*
G01X1305189Y883859D02*
X1303351Y882812D01*
G01X1295937Y887048D02*
X1294099Y886001D01*
G01X1301488Y890237D02*
X1299650Y889190D01*
G01X1297787Y890237D02*
X1295949Y889190D01*
G01X1303338Y893426D02*
X1301500Y892379D01*
G01X1301488Y883859D02*
X1299650Y882812D01*
G01X1297787Y909370D02*
X1295949Y908324D01*
G01X1295937Y899804D02*
X1294099Y898757D01*
G01X1301488Y902993D02*
X1299650Y901946D01*
G01X1297787Y902993D02*
X1295949Y901946D01*
G01X1303338Y906181D02*
X1301500Y905134D01*
G01X1295937Y906181D02*
X1294099Y905134D01*
G01X1301488Y909370D02*
X1299650Y908324D01*
G01X1303338Y912559D02*
X1301500Y911512D01*
G01X1295937Y918937D02*
X1294099Y917890D01*
G01X1301488Y922126D02*
X1299650Y921079D01*
G01X1297787Y922126D02*
X1295949Y921079D01*
G01X1303338Y925315D02*
X1301500Y924268D01*
G01X1295937Y925315D02*
X1294099Y924268D01*
G01X1301488Y928504D02*
X1299650Y927457D01*
G01X1297787Y928504D02*
X1295949Y927457D01*
G01X1303338Y931693D02*
X1301500Y930646D01*
G01X1295937Y938071D02*
X1294099Y937024D01*
G01X1301488Y941260D02*
X1299650Y940213D01*
G01X1297787Y941260D02*
X1295949Y940213D01*
G01X1303338Y944449D02*
X1301500Y943402D01*
G01X1295937Y944449D02*
X1294099Y943402D01*
G01X1301488Y947638D02*
X1299650Y946591D01*
G01X1297787Y947638D02*
X1295949Y946591D01*
G01X1303338Y950827D02*
X1301500Y949780D01*
G01X1295937Y963583D02*
X1294099Y962536D01*
G01X1301488Y966772D02*
X1299650Y965725D01*
G01X1297787Y966772D02*
X1295949Y965725D01*
G01X1303338Y969961D02*
X1301500Y968914D01*
G01X1295937Y957205D02*
X1294099Y956158D01*
G01X1301488Y960394D02*
X1299650Y959347D01*
G01X1297787Y960394D02*
X1295949Y959347D01*
G01X1303338Y963583D02*
X1301500Y962536D01*
G01X1301488Y985906D02*
X1299650Y984859D01*
G01X1295937Y976339D02*
X1294099Y975292D01*
G01X1301488Y979528D02*
X1299650Y978481D01*
G01X1297787Y979528D02*
X1295949Y978481D01*
G01X1303338Y982717D02*
X1301500Y981670D01*
G01X1303338Y989095D02*
X1301500Y988048D01*
G01X1295937Y995473D02*
X1294099Y994426D01*
G01X1297787Y998662D02*
X1295949Y997615D01*
G01X1301488Y998662D02*
X1299650Y997615D01*
G01X1297787Y992284D02*
X1295949Y991237D01*
G01X1303338Y995473D02*
X1301500Y994426D01*
G01X1301488Y992284D02*
X1299650Y991237D01*
G01X1295937Y989095D02*
X1294099Y988048D01*
G01X1303338Y1001851D02*
X1301500Y1000804D01*
G01X1295937Y1001851D02*
X1294099Y1000804D01*
G01X1297787Y1005040D02*
X1295949Y1003993D01*
G01X1301488Y1005040D02*
X1299650Y1003993D01*
G01X1303338Y1008229D02*
X1301500Y1007182D01*
G01X1291567Y1027008D02*
X1289729Y1028055D01*
G01X1302669Y1027008D02*
X1300831Y1028055D01*
G01X1304520Y1030197D02*
X1302681Y1031244D01*
G01X1302669Y1033386D02*
X1300831Y1034433D01*
G01X1298968Y1033386D02*
X1297130Y1034433D01*
G01X1297118Y1036575D02*
X1295280Y1037622D01*
G01X1304520Y1036575D02*
X1302681Y1037622D01*
G01X1302669Y1039764D02*
X1300831Y1040811D01*
G01X1298968Y1039764D02*
X1297130Y1040811D01*
G01X1297118Y1042953D02*
X1295280Y1044000D01*
G01X1304520Y1049331D02*
X1302681Y1050378D01*
G01X1298968Y1058898D02*
X1297130Y1059945D01*
G01X1302669Y1046142D02*
X1300831Y1047189D01*
G01X1297118Y1049331D02*
X1295280Y1050378D01*
G01X1298968Y1052520D02*
X1297130Y1053567D01*
G01X1298968Y1071654D02*
X1297130Y1072701D01*
G01X1297118Y1074843D02*
X1295280Y1075890D01*
G01X1304520Y1062087D02*
X1302681Y1063134D01*
G01X1297118Y1062087D02*
X1295280Y1063134D01*
G01X1302669Y1065276D02*
X1300831Y1066323D01*
G01X1304520Y1074843D02*
X1302681Y1075890D01*
G01X1302669Y1078032D02*
X1300831Y1079079D01*
G01X1298968Y1078032D02*
X1297130Y1079079D01*
G01X1304520Y1081221D02*
X1302681Y1082268D01*
G01X1297118Y1081221D02*
X1295280Y1082268D01*
G01X1302669Y1084410D02*
X1300831Y1085457D01*
G01X1297118Y1100355D02*
X1295280Y1101402D01*
G01X1302669Y1103544D02*
X1300831Y1104591D01*
G01X1298968Y1090788D02*
X1297130Y1091835D01*
G01X1304520Y1093977D02*
X1302681Y1095024D01*
G01X1297118Y1093977D02*
X1295280Y1095024D01*
G01X1302669Y1097166D02*
X1300831Y1098213D01*
G01X1298968Y1097166D02*
X1297130Y1098213D01*
G01X1304520Y1100355D02*
X1302681Y1101402D01*
G01X1298968Y1109922D02*
X1297130Y1110969D01*
G01X1304520Y1113111D02*
X1302681Y1114158D01*
G01X1297118Y1113111D02*
X1295280Y1114158D01*
G01X1302669Y1116300D02*
X1300831Y1117347D01*
G01X1298968Y1116300D02*
X1297130Y1117347D01*
G01X1297118Y1119489D02*
X1295280Y1120536D01*
G01X1304520Y1119489D02*
X1302681Y1120536D01*
G01X1302669Y1122678D02*
X1300831Y1123725D01*
G01X1298968Y1129056D02*
X1297130Y1130102D01*
G01X1304520Y1132245D02*
X1302681Y1133292D01*
G01X1297118Y1132245D02*
X1295280Y1133292D01*
G01X1302669Y1135433D02*
X1300831Y1136480D01*
G01X1298968Y1135433D02*
X1297130Y1136480D01*
G01X1304520Y1138622D02*
X1302681Y1139669D01*
G01X1297118Y1138622D02*
X1295280Y1139669D01*
G01X1302669Y1141811D02*
X1300831Y1142858D01*
G01X1298968Y1148189D02*
X1297130Y1149236D01*
G01X1293417Y1157756D02*
X1291579Y1158803D01*
G01X1304520Y1151378D02*
X1302681Y1152425D01*
G01X1297118Y1151378D02*
X1295280Y1152425D01*
G01X1302669Y1154567D02*
X1300831Y1155614D01*
G01X1297118Y1164134D02*
X1298690D01*
X1325137Y1190581D01*
Y1210653D01*
G01X1295268Y1160945D02*
Y1164471D01*
X1296477Y1165680D01*
X1298148D01*
X1323169Y1190701D01*
Y1208995D01*
G01X1293417Y1164134D02*
X1321386Y1192103D01*
Y1208218D01*
X1321359Y1208245D01*
Y1209745D01*
X1321386Y1209772D01*
Y1212904D01*
X1324901Y1216419D01*
G01X1291567Y1160945D02*
Y1165068D01*
X1319611Y1193112D01*
Y1207489D01*
X1319589Y1207511D01*
Y1210479D01*
X1319611Y1210501D01*
Y1214835D01*
X1322141Y1217365D01*
G01X1308900Y1525510D02*
X1308391Y1525001D01*
X1303934D01*
G01X1302390Y1530430D02*
X1303934Y1528886D01*
Y1528147D01*
G01X1301834Y1525001D02*
X1299399D01*
X1297490Y1526910D01*
G01X1297620Y1529534D02*
X1299007Y1528147D01*
X1301834D01*
G01X1302323Y1550640D02*
X1303412D01*
X1303812Y1551040D01*
X1305223D01*
G01X1302323Y1550640D02*
Y1551788D01*
X1301823Y1552288D01*
X1298245D01*
X1297333Y1553200D01*
G01X1305223Y1547420D02*
X1302203D01*
X1302097Y1547314D01*
G01X1291423Y1538000D02*
Y1538659D01*
X1294745Y1541981D01*
G01X1301323Y1543800D02*
X1305223D01*
G01X1301323D02*
Y1544135D01*
X1298144Y1547314D01*
X1297097D01*
G01X1294073Y1554750D02*
Y1551850D01*
G01X1289577Y1559953D02*
X1291375Y1561751D01*
X1293320D01*
X1295576Y1559495D01*
Y1555917D01*
X1294409Y1554750D01*
X1294073D01*
G01X1290873Y1551850D02*
Y1554750D01*
G01X1308110Y61336D02*
Y56536D01*
G01X1313620Y60741D02*
Y58889D01*
X1311267Y56536D01*
X1308110D01*
G01X1313615Y72342D02*
Y66652D01*
X1313620Y66647D01*
G01X1309185Y82866D02*
X1311664D01*
X1313615Y80915D01*
Y72342D01*
G01X1309185Y80307D02*
X1308244D01*
X1305685Y77748D01*
Y74748D01*
G01X1310094Y269008D02*
Y274108D01*
G01X1318094Y269008D02*
Y274108D01*
G01X1310094Y277848D02*
Y282948D01*
G01X1318094Y277848D02*
Y282948D01*
G01X1315411Y547916D02*
X1314565D01*
X1310546Y543897D01*
Y540212D01*
X1307633Y537299D01*
X1307217D01*
G01X1319992Y877481D02*
X1318154Y876434D01*
G01X1307039Y880670D02*
X1305201Y879623D01*
G01X1314441Y880670D02*
X1312603Y879623D01*
G01X1318142Y880670D02*
X1316304Y879623D01*
G01X1308890Y877481D02*
X1307052Y876434D01*
G01X1310740Y887048D02*
X1308902Y886001D01*
G01X1316291Y890237D02*
X1314453Y889190D01*
G01X1308890Y890237D02*
X1307052Y889190D01*
G01X1314441Y893426D02*
X1312603Y892379D01*
G01X1308890Y909370D02*
X1307052Y908324D01*
G01X1310740Y899804D02*
X1308902Y898757D01*
G01X1316291Y902993D02*
X1314453Y901946D01*
G01X1308890Y902993D02*
X1307052Y901946D01*
G01X1314441Y906181D02*
X1312603Y905134D01*
G01X1310740Y906181D02*
X1308902Y905134D01*
G01X1316291Y909370D02*
X1314453Y908324D01*
G01X1314441Y912559D02*
X1312603Y911512D01*
G01X1310740Y918937D02*
X1308902Y917890D01*
G01X1316291Y922126D02*
X1314453Y921079D01*
G01X1308890Y922126D02*
X1307052Y921079D01*
G01X1314441Y925315D02*
X1312603Y924268D01*
G01X1310740Y925315D02*
X1308902Y924268D01*
G01X1316291Y928504D02*
X1314453Y927457D01*
G01X1308890Y928504D02*
X1307052Y927457D01*
G01X1314441Y931693D02*
X1312603Y930646D01*
G01X1310740Y938071D02*
X1308902Y937024D01*
G01X1316291Y941260D02*
X1314453Y940213D01*
G01X1308890Y941260D02*
X1307052Y940213D01*
G01X1314441Y944449D02*
X1312603Y943402D01*
G01X1310740Y944449D02*
X1308902Y943402D01*
G01X1316291Y947638D02*
X1314453Y946591D01*
G01X1308890Y947638D02*
X1307052Y946591D01*
G01X1314441Y950827D02*
X1312603Y949780D01*
G01X1310740Y963583D02*
X1308902Y962536D01*
G01X1316291Y966772D02*
X1314453Y965725D01*
G01X1308890Y966772D02*
X1307052Y965725D01*
G01X1314441Y969961D02*
X1312603Y968914D01*
G01X1310740Y957205D02*
X1308902Y956158D01*
G01X1316291Y960394D02*
X1314453Y959347D01*
G01X1308890Y960394D02*
X1307052Y959347D01*
G01X1314441Y963583D02*
X1312603Y962536D01*
G01X1316291Y985906D02*
X1314453Y984859D01*
G01X1310740Y976339D02*
X1308902Y975292D01*
G01X1316291Y979528D02*
X1314453Y978481D01*
G01X1308890Y979528D02*
X1307052Y978481D01*
G01X1314441Y982717D02*
X1312603Y981670D01*
G01X1314441Y989095D02*
X1312603Y988048D01*
G01X1310740Y995473D02*
X1308902Y994426D01*
G01X1308890Y998662D02*
X1307052Y997615D01*
G01X1316291Y998662D02*
X1314453Y997615D01*
G01X1308890Y992284D02*
X1307052Y991237D01*
G01X1314441Y995473D02*
X1312603Y994426D01*
G01X1316291Y992284D02*
X1314453Y991237D01*
G01X1310740Y989095D02*
X1308902Y988048D01*
G01X1314441Y1001851D02*
X1312603Y1000804D01*
G01X1310740Y1001851D02*
X1308902Y1000804D01*
G01X1308890Y1005040D02*
X1307052Y1003993D01*
G01X1316291Y1005040D02*
X1314453Y1003993D01*
G01X1314441Y1008229D02*
X1312603Y1007182D01*
G01X1317472Y1027008D02*
X1315634Y1028055D01*
G01X1315622Y1030197D02*
X1313784Y1031244D01*
G01X1317472Y1033386D02*
X1315634Y1034433D01*
G01X1310071Y1033386D02*
X1308233Y1034433D01*
G01X1311921Y1036575D02*
X1310083Y1037622D01*
G01X1315622Y1036575D02*
X1313784Y1037622D01*
G01X1317472Y1039764D02*
X1315634Y1040811D01*
G01X1310071Y1039764D02*
X1308233Y1040811D01*
G01X1311921Y1042953D02*
X1310083Y1044000D01*
G01X1315622Y1049331D02*
X1313784Y1050378D01*
G01X1310071Y1058898D02*
X1308233Y1059945D01*
G01X1317472Y1046142D02*
X1315634Y1047189D01*
G01X1311921Y1049331D02*
X1310083Y1050378D01*
G01X1310071Y1052520D02*
X1308233Y1053567D01*
G01X1310071Y1071654D02*
X1308233Y1072701D01*
G01X1315622Y1074843D02*
X1313784Y1075890D01*
G01X1311921Y1074843D02*
X1310083Y1075890D01*
G01X1315622Y1062087D02*
X1313784Y1063134D01*
G01X1311921Y1062087D02*
X1310083Y1063134D01*
G01X1317472Y1065276D02*
X1315634Y1066323D01*
G01X1317472Y1078032D02*
X1315634Y1079079D01*
G01X1310071Y1078032D02*
X1308233Y1079079D01*
G01X1315622Y1081221D02*
X1313784Y1082268D01*
G01X1311921Y1081221D02*
X1310083Y1082268D01*
G01X1317472Y1084410D02*
X1315634Y1085457D01*
G01X1311921Y1100355D02*
X1310083Y1101402D01*
G01X1317472Y1103544D02*
X1315634Y1104591D01*
G01X1310071Y1090788D02*
X1308233Y1091835D01*
G01X1315622Y1093977D02*
X1313784Y1095024D01*
G01X1311921Y1093977D02*
X1310083Y1095024D01*
G01X1317472Y1097166D02*
X1315634Y1098213D01*
G01X1310071Y1097166D02*
X1308233Y1098213D01*
G01X1315622Y1100355D02*
X1313784Y1101402D01*
G01X1310071Y1109922D02*
X1308233Y1110969D01*
G01X1315622Y1113111D02*
X1313784Y1114158D01*
G01X1311921Y1113111D02*
X1310083Y1114158D01*
G01X1317472Y1116300D02*
X1315634Y1117347D01*
G01X1310071Y1116300D02*
X1308233Y1117347D01*
G01X1315622Y1119489D02*
X1313784Y1120536D01*
G01X1311921Y1119489D02*
X1310083Y1120536D01*
G01X1317472Y1122678D02*
X1315634Y1123725D01*
G01X1310071Y1129056D02*
X1308233Y1130102D01*
G01X1315622Y1132245D02*
X1313784Y1133292D01*
G01X1311921Y1132245D02*
X1310083Y1133292D01*
G01X1317472Y1135433D02*
X1315634Y1136480D01*
G01X1310071Y1135433D02*
X1308233Y1136480D01*
G01X1315622Y1138622D02*
X1313784Y1139669D01*
G01X1311921Y1138622D02*
X1310083Y1139669D01*
G01X1317472Y1141811D02*
X1315634Y1142858D01*
G01X1310071Y1148189D02*
X1308233Y1149236D01*
G01X1315622Y1151378D02*
X1313784Y1152425D01*
G01X1311921Y1151378D02*
X1310083Y1152425D01*
G01X1310071Y1154567D02*
X1308233Y1155614D01*
G01X1305223Y1551040D02*
Y1549839D01*
X1305832Y1549230D01*
X1310583D01*
X1311358Y1550005D01*
Y1552121D01*
X1312044Y1552807D01*
X1315392D01*
G01Y1550445D02*
X1314638D01*
X1311996Y1547803D01*
Y1547248D01*
X1310358Y1545610D01*
X1305843D01*
X1305223Y1546230D01*
Y1547420D01*
G01X1314680Y1546218D02*
X1316754D01*
X1317438Y1546902D01*
G01X1313021Y1551121D02*
X1314016D01*
X1314521Y1551626D01*
X1317438D01*
G01X1305223Y1543800D02*
Y1542522D01*
X1306054Y1541691D01*
X1309889D01*
X1313007Y1544809D01*
Y1547568D01*
X1314703Y1549264D01*
X1317438D01*
G01Y1565799D02*
X1313976D01*
X1311721Y1568054D01*
Y1573381D01*
X1322380Y1584040D01*
Y1588570D01*
X1322644Y1588834D01*
G01X1315392Y1564618D02*
X1313073D01*
X1310200Y1567491D01*
Y1573881D01*
X1316659Y1580340D01*
Y1584952D01*
X1315723Y1585888D01*
X1315072D01*
G01X1317438Y1563437D02*
X1311874D01*
X1308624Y1566687D01*
Y1583552D01*
X1308072Y1584104D01*
Y1586688D01*
G01X1313422Y1554612D02*
X1314046Y1553988D01*
X1317438D01*
G01Y1568162D02*
X1314004D01*
X1313468Y1568698D01*
G01X1315392Y1569343D02*
X1313837Y1570898D01*
X1313468D01*
G01X1310914Y1577299D02*
X1310106Y1578107D01*
Y1585096D01*
X1310898Y1585888D01*
X1311872D01*
G01X1315072Y1588788D02*
Y1585888D01*
G01Y1588788D02*
X1316121D01*
X1317003Y1589670D01*
Y1593171D01*
X1316095Y1594079D01*
G01X1308072Y1586688D02*
X1306971D01*
X1306390Y1587269D01*
Y1590769D01*
X1315943Y1600322D01*
G01X1308072Y1588788D02*
X1311872D01*
G01Y1585888D02*
Y1588788D01*
G01X1320020Y61404D02*
Y56604D01*
G01X1325530Y60824D02*
Y57692D01*
X1324442Y56604D01*
X1320020D01*
G01X1331930Y61370D02*
Y56570D01*
G01X1337440Y60824D02*
Y57658D01*
X1336352Y56570D01*
X1331930D01*
G01X1329435Y70452D02*
Y68469D01*
X1325530Y64564D01*
G01X1323604Y74869D02*
Y72095D01*
X1325247Y70452D01*
X1329435D01*
G01X1333399Y92509D02*
Y87709D01*
G01X1327541Y83687D02*
X1331627D01*
X1333399Y85459D01*
Y87709D01*
G01X1327541Y101327D02*
Y105227D01*
G01X1323604Y92509D02*
X1333399D01*
G01X1326094Y269008D02*
Y274108D01*
G01Y277848D02*
Y282948D01*
G01X1325543Y880670D02*
X1323705Y879623D01*
G01X1329244Y880670D02*
X1327406Y879623D01*
G01X1325543Y874292D02*
Y871161D01*
G01X1329244Y874292D02*
Y871161D01*
G01X1323693Y877481D02*
X1321855Y876434D01*
G01X1334795Y877481D02*
X1332957Y876434D01*
G01X1331094Y877481D02*
X1329256Y876434D01*
G01X1321842Y887048D02*
X1320004Y886001D01*
G01X1327394Y890237D02*
X1325556Y889190D01*
G01X1323693Y890237D02*
X1321855Y889190D01*
G01X1329244Y893426D02*
X1327406Y892379D01*
G01X1334795Y890237D02*
X1332957Y889190D01*
G01X1323693Y909370D02*
X1321855Y908324D01*
G01X1321842Y899804D02*
X1320004Y898757D01*
G01X1327394Y902993D02*
X1325556Y901946D01*
G01X1323693Y902993D02*
X1321855Y901946D01*
G01X1329244Y906181D02*
X1327406Y905134D01*
G01X1321842Y906181D02*
X1320004Y905134D01*
G01X1327394Y909370D02*
X1325556Y908324D01*
G01X1334795Y909370D02*
X1332957Y908324D01*
G01X1334795Y902993D02*
X1332957Y901946D01*
G01X1329244Y912559D02*
X1327406Y911512D01*
G01X1321842Y918937D02*
X1320004Y917890D01*
G01X1327394Y922126D02*
X1325556Y921079D01*
G01X1323693Y922126D02*
X1321855Y921079D01*
G01X1329244Y925315D02*
X1327406Y924268D01*
G01X1321842Y925315D02*
X1320004Y924268D01*
G01X1334795Y922126D02*
X1332957Y921079D01*
G01X1327394Y928504D02*
X1325556Y927457D01*
G01X1323693Y928504D02*
X1321855Y927457D01*
G01X1329244Y931693D02*
X1327406Y930646D01*
G01X1321842Y938071D02*
X1320004Y937024D01*
G01X1327394Y941260D02*
X1325556Y940213D01*
G01X1323693Y941260D02*
X1321855Y940213D01*
G01X1334795Y928504D02*
X1332957Y927457D01*
G01X1334795Y941260D02*
X1332957Y940213D01*
G01X1329244Y944449D02*
X1327406Y943402D01*
G01X1321842Y944449D02*
X1320004Y943402D01*
G01X1327394Y947638D02*
X1325556Y946591D01*
G01X1323693Y947638D02*
X1321855Y946591D01*
G01X1329244Y950827D02*
X1327406Y949780D01*
G01X1334795Y947638D02*
X1332957Y946591D01*
G01X1321842Y963583D02*
X1320004Y962536D01*
G01X1327394Y966772D02*
X1325556Y965725D01*
G01X1323693Y966772D02*
X1321855Y965725D01*
G01X1329244Y969961D02*
X1327406Y968914D01*
G01X1321842Y957205D02*
X1320004Y956158D01*
G01X1327394Y960394D02*
X1325556Y959347D01*
G01X1323693Y960394D02*
X1321855Y959347D01*
G01X1329244Y963583D02*
X1327406Y962536D01*
G01X1334795Y966772D02*
X1332957Y965725D01*
G01X1334795Y960394D02*
X1332957Y959347D01*
G01X1327394Y985906D02*
X1325556Y984859D01*
G01X1321842Y976339D02*
X1320004Y975292D01*
G01X1327394Y979528D02*
X1325556Y978481D01*
G01X1323693Y979528D02*
X1321855Y978481D01*
G01X1329244Y982717D02*
X1327406Y981670D01*
G01X1334795Y979528D02*
X1332957Y978481D01*
G01X1329244Y989095D02*
X1327406Y988048D01*
G01X1321842Y995473D02*
X1320004Y994426D01*
G01X1323693Y998662D02*
X1321855Y997615D01*
G01X1327394Y998662D02*
X1325556Y997615D01*
G01X1323693Y992284D02*
X1321855Y991237D01*
G01X1329244Y995473D02*
X1327406Y994426D01*
G01X1334795Y998662D02*
X1332957Y997615D01*
G01X1334795Y992284D02*
X1332957Y991237D01*
G01X1327394Y992284D02*
X1325556Y991237D01*
G01X1321842Y989095D02*
X1320004Y988048D01*
G01X1329244Y1001851D02*
X1327406Y1000804D01*
G01X1321842Y1001851D02*
X1320004Y1000804D01*
G01X1323693Y1005040D02*
X1321855Y1003993D01*
G01X1327394Y1005040D02*
X1325556Y1003993D01*
G01X1329244Y1008229D02*
X1327406Y1007182D01*
G01X1334795Y1005040D02*
X1332957Y1003993D01*
G01X1328575Y1027008D02*
X1326737Y1028055D01*
G01X1330425Y1030197D02*
X1328587Y1031244D01*
G01X1328575Y1033386D02*
X1326737Y1034433D01*
G01X1324874Y1033386D02*
X1323036Y1034433D01*
G01X1323023Y1036575D02*
X1321185Y1037622D01*
G01X1330425Y1036575D02*
X1328587Y1037622D01*
G01X1328575Y1039764D02*
X1326737Y1040811D01*
G01X1324874Y1039764D02*
X1323036Y1040811D01*
G01X1323023Y1042953D02*
X1321185Y1044000D01*
G01X1330425Y1049331D02*
X1328587Y1050378D01*
G01X1324874Y1058898D02*
X1323036Y1059945D01*
G01X1328575Y1046142D02*
X1326737Y1047189D01*
G01X1323023Y1049331D02*
X1321185Y1050378D01*
G01X1324874Y1052520D02*
X1323036Y1053567D01*
G01X1324874Y1071654D02*
X1323036Y1072701D01*
G01X1330425Y1074843D02*
X1328587Y1075890D01*
G01X1323023Y1074843D02*
X1321185Y1075890D01*
G01X1330425Y1062087D02*
X1328587Y1063134D01*
G01X1323023Y1062087D02*
X1321185Y1063134D01*
G01X1328575Y1065276D02*
X1326737Y1066323D01*
G01X1328575Y1078032D02*
X1326737Y1079079D01*
G01X1324874Y1078032D02*
X1323036Y1079079D01*
G01X1330425Y1081221D02*
X1328587Y1082268D01*
G01X1323023Y1081221D02*
X1321185Y1082268D01*
G01X1328575Y1084410D02*
X1326737Y1085457D01*
G01X1323023Y1100355D02*
X1321185Y1101402D01*
G01X1328575Y1103544D02*
X1326737Y1104591D01*
G01X1324874Y1090788D02*
X1323036Y1091835D01*
G01X1330425Y1093977D02*
X1328587Y1095024D01*
G01X1323023Y1093977D02*
X1321185Y1095024D01*
G01X1328575Y1097166D02*
X1326737Y1098213D01*
G01X1324874Y1097166D02*
X1323036Y1098213D01*
G01X1330425Y1100355D02*
X1328587Y1101402D01*
G01X1324874Y1109922D02*
X1323036Y1110969D01*
G01X1330425Y1113111D02*
X1328587Y1114158D01*
G01X1323023Y1113111D02*
X1321185Y1114158D01*
G01X1328575Y1116300D02*
X1326737Y1117347D01*
G01X1324874Y1116300D02*
X1323036Y1117347D01*
G01X1330425Y1119489D02*
X1328587Y1120536D01*
G01X1323023Y1119489D02*
X1321185Y1120536D01*
G01X1328575Y1122678D02*
X1326737Y1123725D01*
G01X1324874Y1129056D02*
X1323036Y1130102D01*
G01X1330425Y1132245D02*
X1328587Y1133292D01*
G01X1323023Y1132245D02*
X1321185Y1133292D01*
G01X1328575Y1135433D02*
X1326737Y1136480D01*
G01X1324874Y1135433D02*
X1323036Y1136480D01*
G01X1330425Y1138622D02*
X1328587Y1139669D01*
G01X1323023Y1138622D02*
X1321185Y1139669D01*
G01X1328575Y1141811D02*
X1326737Y1142858D01*
G01X1324874Y1148189D02*
X1323036Y1149236D01*
G01X1330425Y1151378D02*
X1328587Y1152425D01*
G01X1323023Y1151378D02*
X1321185Y1152425D01*
G01X1328575Y1154567D02*
X1326737Y1155614D01*
G01X1356331Y1164134D02*
X1352316Y1168149D01*
X1336752D01*
X1328992Y1175909D01*
Y1209788D01*
G01X1352630Y1164134D02*
X1349495Y1167269D01*
X1336047D01*
X1327029Y1176287D01*
Y1206788D01*
G01X1319349Y1592939D02*
Y1590039D01*
G01D02*
X1321439D01*
X1322644Y1588834D01*
G01X1343840Y61336D02*
Y56536D01*
G01X1349350Y60741D02*
Y58889D01*
X1346997Y56536D01*
X1343840D01*
G01X1344958Y75369D02*
Y77032D01*
X1348199Y80273D01*
Y87709D01*
G01X1342399Y75369D02*
Y73664D01*
X1342928Y73135D01*
X1344429D01*
X1344958Y73664D01*
Y75369D01*
G01X1337440Y64564D02*
X1337435Y64569D01*
Y70452D01*
G01D02*
Y78723D01*
X1339840Y81128D01*
Y82849D01*
G01X1351750Y82815D02*
Y81094D01*
X1348531Y77875D01*
Y75106D01*
X1343877Y70452D01*
G01X1349350Y66647D02*
X1347682D01*
X1343877Y70452D01*
G01X1342399Y82849D02*
Y86709D01*
X1341399Y87709D01*
G01D02*
Y92509D01*
G01X1348199Y87709D02*
Y92509D01*
G01X1337399D02*
X1341399D01*
G01X1337399Y95659D02*
Y98084D01*
G01X1342094Y269008D02*
Y274108D01*
G01X1334094Y269008D02*
Y274108D01*
G01X1342094Y277848D02*
Y282948D01*
G01X1334094Y277848D02*
Y282948D01*
G01X1342197Y877481D02*
X1340359Y876434D01*
G01X1336646Y880670D02*
X1334807Y879623D01*
G01X1347748Y887048D02*
X1345910Y886001D01*
G01X1349598Y890237D02*
X1347760Y889190D01*
G01X1336646Y887048D02*
X1334807Y886001D01*
G01X1342197Y890237D02*
X1340359Y889190D01*
G01X1340346Y893426D02*
X1338508Y892379D01*
G01X1349598Y909370D02*
X1347760Y908324D01*
G01X1347748Y899804D02*
X1345910Y898757D01*
G01X1349598Y902993D02*
X1347760Y901946D01*
G01X1347748Y906181D02*
X1345910Y905134D01*
G01X1336646Y899804D02*
X1334807Y898757D01*
G01X1342197Y902993D02*
X1340359Y901946D01*
G01X1340346Y906181D02*
X1338508Y905134D01*
G01X1336646Y906181D02*
X1334807Y905134D01*
G01X1342197Y909370D02*
X1340359Y908324D01*
G01X1347748Y918937D02*
X1345910Y917890D01*
G01X1349598Y922126D02*
X1347760Y921079D01*
G01X1347748Y925315D02*
X1345910Y924268D01*
G01X1340346Y912559D02*
X1338508Y911512D01*
G01X1336646Y918937D02*
X1334807Y917890D01*
G01X1342197Y922126D02*
X1340359Y921079D01*
G01X1340346Y925315D02*
X1338508Y924268D01*
G01X1336646Y925315D02*
X1334807Y924268D01*
G01X1349598Y928504D02*
X1347760Y927457D01*
G01X1347748Y938071D02*
X1345910Y937024D01*
G01X1349598Y941260D02*
X1347760Y940213D01*
G01X1342197Y928504D02*
X1340359Y927457D01*
G01X1340346Y931693D02*
X1338508Y930646D01*
G01X1336646Y938071D02*
X1334807Y937024D01*
G01X1342197Y941260D02*
X1340359Y940213D01*
G01X1347748Y944449D02*
X1345910Y943402D01*
G01X1349598Y947638D02*
X1347760Y946591D01*
G01X1340346Y944449D02*
X1338508Y943402D01*
G01X1336646Y944449D02*
X1334807Y943402D01*
G01X1342197Y947638D02*
X1340359Y946591D01*
G01X1340346Y950827D02*
X1338508Y949780D01*
G01X1347748Y963583D02*
X1345910Y962536D01*
G01X1349598Y966772D02*
X1347760Y965725D01*
G01X1347748Y957205D02*
X1345910Y956158D01*
G01X1349598Y960394D02*
X1347760Y959347D01*
G01X1336646Y963583D02*
X1334807Y962536D01*
G01X1342197Y966772D02*
X1340359Y965725D01*
G01X1340346Y969961D02*
X1338508Y968914D01*
G01X1336646Y957205D02*
X1334807Y956158D01*
G01X1342197Y960394D02*
X1340359Y959347D01*
G01X1340346Y963583D02*
X1338508Y962536D01*
G01X1347748Y976339D02*
X1345910Y975292D01*
G01X1349598Y979528D02*
X1347760Y978481D01*
G01X1342197Y985906D02*
X1340359Y984859D01*
G01X1336646Y976339D02*
X1334807Y975292D01*
G01X1342197Y979528D02*
X1340359Y978481D01*
G01X1340346Y982717D02*
X1338508Y981670D01*
G01X1347748Y995473D02*
X1345910Y994426D01*
G01X1349598Y998662D02*
X1347760Y997615D01*
G01X1349598Y992284D02*
X1347760Y991237D01*
G01X1340346Y989095D02*
X1338508Y988048D01*
G01X1336646Y995473D02*
X1334807Y994426D01*
G01X1342197Y998662D02*
X1340359Y997615D01*
G01X1340346Y995473D02*
X1338508Y994426D01*
G01X1342197Y992284D02*
X1340359Y991237D01*
G01X1336646Y989095D02*
X1334808Y988048D01*
G01X1347748Y989095D02*
X1345910Y988048D01*
G01X1347748Y1001851D02*
X1345910Y1000804D01*
G01X1349598Y1005040D02*
X1347760Y1003993D01*
G01X1340346Y1001851D02*
X1338508Y1000804D01*
G01X1336646Y1001851D02*
X1334807Y1000804D01*
G01X1342197Y1005040D02*
X1340359Y1003993D01*
G01X1340346Y1008229D02*
X1338508Y1007182D01*
G01X1343378Y1027008D02*
X1341540Y1028055D01*
G01X1335976Y1027008D02*
X1334138Y1028055D01*
G01X1348929Y1036575D02*
X1347091Y1037622D01*
G01X1348929Y1042953D02*
X1347091Y1044000D01*
G01X1341527Y1030197D02*
X1339689Y1031244D01*
G01X1343378Y1033386D02*
X1341540Y1034433D01*
G01X1335976Y1033386D02*
X1334138Y1034433D01*
G01X1337827Y1036575D02*
X1335989Y1037622D01*
G01X1341527Y1036575D02*
X1339689Y1037622D01*
G01X1343378Y1039764D02*
X1341540Y1040811D01*
G01X1335976Y1039764D02*
X1334138Y1040811D01*
G01X1337827Y1042953D02*
X1335989Y1044000D01*
G01X1337827Y1030197D02*
X1335989Y1031244D01*
G01X1348929Y1030197D02*
X1347091Y1031244D01*
G01X1348929Y1049331D02*
X1347091Y1050378D01*
G01X1341527Y1049331D02*
X1339689Y1050378D01*
G01X1335976Y1058898D02*
X1334138Y1059945D01*
G01X1343378Y1046142D02*
X1341540Y1047189D01*
G01X1337827Y1049331D02*
X1335989Y1050378D01*
G01X1335976Y1052520D02*
X1334138Y1053567D01*
G01X1348929Y1062087D02*
X1347091Y1063134D01*
G01X1335976Y1071654D02*
X1334138Y1072701D01*
G01X1341527Y1074843D02*
X1339689Y1075890D01*
G01X1337827Y1074843D02*
X1335989Y1075890D01*
G01X1341527Y1062087D02*
X1339689Y1063134D01*
G01X1337827Y1062087D02*
X1335989Y1063134D01*
G01X1343378Y1065276D02*
X1341540Y1066323D01*
G01X1348929Y1074843D02*
X1347091Y1075890D01*
G01X1348929Y1081221D02*
X1347091Y1082268D01*
G01X1343378Y1078032D02*
X1341540Y1079079D01*
G01X1335976Y1078032D02*
X1334138Y1079079D01*
G01X1341527Y1081221D02*
X1339689Y1082268D01*
G01X1337827Y1081221D02*
X1335989Y1082268D01*
G01X1343378Y1084410D02*
X1341540Y1085457D01*
G01X1348929Y1100355D02*
X1347091Y1101402D01*
G01X1348929Y1093977D02*
X1347091Y1095024D01*
G01X1337827Y1100355D02*
X1335989Y1101402D01*
G01X1343378Y1103544D02*
X1341540Y1104591D01*
G01X1335976Y1090788D02*
X1334138Y1091835D01*
G01X1341527Y1093977D02*
X1339689Y1095024D01*
G01X1337827Y1093977D02*
X1335989Y1095024D01*
G01X1343378Y1097166D02*
X1341540Y1098213D01*
G01X1335976Y1097166D02*
X1334138Y1098213D01*
G01X1341527Y1100355D02*
X1339689Y1101402D01*
G01X1348929Y1113111D02*
X1347091Y1114158D01*
G01X1335976Y1109922D02*
X1334138Y1110969D01*
G01X1341527Y1113111D02*
X1339689Y1114158D01*
G01X1337827Y1113111D02*
X1335989Y1114158D01*
G01X1343378Y1116300D02*
X1341540Y1117347D01*
G01X1335976Y1116300D02*
X1334138Y1117347D01*
G01X1341527Y1119489D02*
X1339689Y1120536D01*
G01X1337827Y1119489D02*
X1335989Y1120536D01*
G01X1348929Y1119489D02*
X1347091Y1120536D01*
G01X1348929Y1132245D02*
X1347091Y1133292D01*
G01X1343378Y1122678D02*
X1341540Y1123725D01*
G01X1335976Y1129056D02*
X1334138Y1130102D01*
G01X1341527Y1132245D02*
X1339689Y1133292D01*
G01X1337827Y1132245D02*
X1335989Y1133292D01*
G01X1348929Y1138622D02*
X1347091Y1139669D01*
G01X1343378Y1135433D02*
X1341540Y1136480D01*
G01X1335976Y1135433D02*
X1334138Y1136480D01*
G01X1341527Y1138622D02*
X1339689Y1139669D01*
G01X1337827Y1138622D02*
X1335989Y1139669D01*
G01X1343378Y1141811D02*
X1341540Y1142858D01*
G01X1335976Y1148189D02*
X1334138Y1149236D01*
G01X1348929Y1151378D02*
X1347091Y1152425D01*
G01X1341527Y1151378D02*
X1339689Y1152425D01*
G01X1337827Y1151378D02*
X1335989Y1152425D01*
G01X1335976Y1154567D02*
X1334138Y1155614D01*
G01X1355750Y61336D02*
Y56536D01*
G01X1361550Y60824D02*
Y57658D01*
X1360428Y56536D01*
X1355750D01*
G01X1356868Y75335D02*
Y76998D01*
X1360109Y80239D01*
Y87675D01*
G01X1354309Y75335D02*
Y73630D01*
X1354838Y73101D01*
X1356339D01*
X1356868Y73630D01*
Y75335D01*
G01X1353309Y87675D02*
X1354309Y86675D01*
Y82815D01*
G01X1352199Y92475D02*
Y88785D01*
X1353309Y87675D01*
G01X1360109D02*
Y92475D01*
G01X1360629Y106559D02*
Y104855D01*
X1356199Y100425D01*
G01D02*
Y95625D01*
G01Y92475D02*
X1352199D01*
G01X1357677Y236594D02*
X1372655D01*
G01X1357677Y241594D02*
X1372655D01*
G01X1357677Y246594D02*
X1372655D01*
G01Y251594D02*
X1357677D01*
G01X1358094Y269008D02*
Y274108D01*
G01X1350094Y269008D02*
Y274108D01*
G01X1358094Y277848D02*
Y282948D01*
G01X1350094Y277848D02*
Y282948D01*
G01X1353299Y890237D02*
X1351461Y889190D01*
G01X1355149Y893426D02*
X1353311Y892379D01*
G01X1353299Y902993D02*
X1351461Y901946D01*
G01X1355149Y906181D02*
X1353311Y905134D01*
G01X1353299Y909370D02*
X1351461Y908324D01*
G01X1355149Y912559D02*
X1353311Y911512D01*
G01X1353299Y922126D02*
X1351461Y921079D01*
G01X1355149Y925315D02*
X1353311Y924268D01*
G01X1353299Y928504D02*
X1351461Y927457D01*
G01X1355149Y931693D02*
X1353311Y930646D01*
G01X1353299Y941260D02*
X1351461Y940213D01*
G01X1362551Y938071D02*
X1360713Y937024D01*
G01X1355149Y944449D02*
X1353311Y943402D01*
G01X1353299Y947638D02*
X1351461Y946591D01*
G01X1355149Y950827D02*
X1353311Y949780D01*
G01X1353299Y966772D02*
X1351461Y965725D01*
G01X1355149Y969961D02*
X1353311Y968914D01*
G01X1353299Y960394D02*
X1351461Y959347D01*
G01X1355149Y963583D02*
X1353311Y962536D01*
G01X1353299Y985906D02*
X1351461Y984859D01*
G01X1353299Y979528D02*
X1351461Y978481D01*
G01X1355149Y982717D02*
X1353311Y981670D01*
G01X1355149Y989095D02*
X1353311Y988048D01*
G01X1353299Y998662D02*
X1351461Y997615D01*
G01X1355149Y995473D02*
X1353311Y994426D01*
G01X1353299Y992284D02*
X1351461Y991237D01*
G01X1355149Y1001851D02*
X1353311Y1000804D01*
G01X1353299Y1005040D02*
X1351461Y1003993D01*
G01X1355149Y1008229D02*
X1353311Y1007182D01*
G01X1354480Y1027008D02*
X1352642Y1028055D01*
G01X1350779Y1027008D02*
X1348941Y1028055D01*
G01X1356331Y1030197D02*
X1354493Y1031244D01*
G01X1354480Y1033386D02*
X1352642Y1034433D01*
G01X1350779Y1033386D02*
X1348941Y1034433D01*
G01X1356331Y1036575D02*
X1354493Y1037622D01*
G01X1354480Y1039764D02*
X1352642Y1040811D01*
G01X1350779Y1039764D02*
X1348941Y1040811D01*
G01X1356331Y1049331D02*
X1354493Y1050378D01*
G01X1350779Y1058898D02*
X1348941Y1059945D01*
G01X1354480Y1046142D02*
X1352642Y1047189D01*
G01X1350779Y1052520D02*
X1348941Y1053567D01*
G01X1361882Y1052520D02*
X1360044Y1053567D01*
G01X1350779Y1071654D02*
X1348941Y1072701D01*
G01X1356331Y1074843D02*
X1354493Y1075890D01*
G01X1356331Y1062087D02*
X1354493Y1063134D01*
G01X1354480Y1065276D02*
X1352642Y1066323D01*
G01X1354480Y1078032D02*
X1352642Y1079079D01*
G01X1350779Y1078032D02*
X1348941Y1079079D01*
G01X1356331Y1081221D02*
X1354493Y1082268D01*
G01X1354480Y1084410D02*
X1352642Y1085457D01*
G01X1354480Y1103544D02*
X1352642Y1104591D01*
G01X1350779Y1090788D02*
X1348941Y1091835D01*
G01X1356331Y1093977D02*
X1354493Y1095024D01*
G01X1354480Y1097166D02*
X1352642Y1098213D01*
G01X1350779Y1097166D02*
X1348941Y1098213D01*
G01X1356331Y1100355D02*
X1354493Y1101402D01*
G01X1363732Y1100355D02*
X1361894Y1101402D01*
G01X1350779Y1109922D02*
X1348941Y1110969D01*
G01X1356331Y1113111D02*
X1354493Y1114158D01*
G01X1354480Y1116300D02*
X1352642Y1117347D01*
G01X1350779Y1116300D02*
X1348941Y1117347D01*
G01X1356331Y1119489D02*
X1354493Y1120536D01*
G01X1354480Y1122678D02*
X1352642Y1123725D01*
G01X1350779Y1129056D02*
X1348941Y1130102D01*
G01X1356331Y1132245D02*
X1354493Y1133292D01*
G01X1354480Y1135433D02*
X1352642Y1136480D01*
G01X1350779Y1135433D02*
X1348941Y1136480D01*
G01X1356331Y1138622D02*
X1354493Y1139669D01*
G01X1354480Y1141811D02*
X1352642Y1142858D01*
G01X1350779Y1148189D02*
X1348941Y1149236D01*
G01X1356331Y1151378D02*
X1354493Y1152425D01*
G01X1354480Y1154567D02*
X1352642Y1155614D01*
G01X1449956Y1267923D02*
Y1260333D01*
X1402627Y1213004D01*
X1361942D01*
X1357393Y1208455D01*
Y1205221D01*
X1364479Y1198135D01*
X1388317D01*
X1417687Y1168765D01*
X1430547D01*
X1434047Y1165265D01*
Y1164134D01*
G01X1355222Y1200561D02*
X1357304D01*
X1362950Y1194915D01*
X1387661D01*
X1418442Y1164134D01*
X1426646D01*
G01X1362810Y1211071D02*
X1361876D01*
X1358713Y1207908D01*
Y1205769D01*
X1364977Y1199505D01*
X1389793D01*
X1419163Y1170135D01*
X1431869D01*
X1435897Y1166107D01*
Y1160945D01*
G01X1361285Y1206718D02*
X1367128Y1200875D01*
X1390361D01*
X1419731Y1171505D01*
X1432437D01*
X1437748Y1166194D01*
Y1164134D01*
G01X1430346D02*
Y1165720D01*
X1428801Y1167265D01*
X1417249D01*
X1387749Y1196765D01*
X1363911D01*
X1355667Y1205009D01*
X1349050D01*
X1349012Y1204971D01*
G01X1367950Y61336D02*
Y56536D01*
G01X1373750Y60824D02*
Y57658D01*
X1372628Y56536D01*
X1367950D01*
G01X1378945Y68142D02*
X1373745Y73342D01*
Y74869D01*
G01X1373750Y64564D02*
X1377196D01*
X1378945Y66313D01*
Y68142D01*
G01X1377682Y83687D02*
Y87587D01*
G01X1364369Y116205D02*
Y120380D01*
G01X1378140Y236594D02*
X1372655D01*
G01X1378140Y241594D02*
X1372655D01*
G01X1378140Y246594D02*
X1372655D01*
G01X1378140Y251594D02*
X1372655D01*
G01X1366094Y269008D02*
Y274108D01*
G01Y277848D02*
Y282948D01*
G01X1373653Y938071D02*
X1371815Y937024D01*
G01X1366252Y938071D02*
X1364414Y937024D01*
G01X1369953Y938071D02*
X1368115Y937024D01*
G01X1377354Y938071D02*
X1375516Y937024D01*
G01X1374835Y1100355D02*
X1372997Y1101402D01*
G01X1378535Y1100355D02*
X1376697Y1101402D01*
G01X1371134Y1100355D02*
X1369296Y1101402D01*
G01X1367433Y1100355D02*
X1365595Y1101402D01*
G01X1381290Y236594D02*
X1383715D01*
G01X1381290Y241594D02*
X1383715D01*
G01X1381290Y246594D02*
X1385832Y251136D01*
X1395302D01*
G01X1381290Y251594D02*
X1385832Y256136D01*
X1395302D01*
G01X1381055Y938071D02*
X1379217Y937024D01*
G01X1382905Y934882D02*
X1381067Y933835D01*
G01X1388457Y938071D02*
X1386619Y937024D01*
G01X1386606Y934882D02*
X1384768Y933835D01*
G01X1384756Y938071D02*
X1382918Y937024D01*
G01X1387787Y1103544D02*
X1385949Y1104591D01*
G01X1385937Y1100355D02*
X1384099Y1101402D01*
G01X1382236Y1100355D02*
X1380398Y1101402D01*
G01X1384086Y1103544D02*
X1382249Y1104591D01*
G01X1389638Y1100355D02*
X1387800Y1101402D01*
G01X1398018Y1605304D02*
X1396472Y1606850D01*
X1393400D01*
G01X1383800D02*
X1388641Y1611691D01*
X1399579D01*
X1416709Y1594561D01*
Y1592819D01*
G01X1413836Y1586944D02*
X1412610Y1588170D01*
Y1594006D01*
X1397813Y1608803D01*
X1392153D01*
X1390200Y1606850D01*
G01X1416862Y1582871D02*
Y1586867D01*
X1414560Y1589169D01*
Y1594599D01*
X1398769Y1610390D01*
X1390540D01*
X1387000Y1606850D01*
G01X1385068Y1670391D02*
Y1674391D01*
G01Y1670391D02*
Y1664907D01*
G01X1390738Y1664938D02*
X1388918Y1666758D01*
Y1670391D01*
G01D02*
Y1674391D01*
G01X1386359Y1682898D02*
Y1678982D01*
X1385068Y1677691D01*
Y1674391D01*
G01X1388918D02*
Y1682898D01*
G01X1384470Y1700038D02*
X1382045D01*
G01X1387620D02*
Y1704038D01*
G01X1386359Y1690378D02*
X1383800D01*
G01X1388600Y1695238D02*
X1383800D01*
G01Y1690378D02*
Y1695238D01*
G01X1387620Y1704038D02*
Y1708038D01*
G01X1390179Y1716438D02*
X1392420Y1714197D01*
Y1708038D01*
G01D02*
X1387620D01*
G01X1385061Y1716438D02*
X1379261D01*
G01X1390179Y1733118D02*
Y1728318D01*
G01D02*
Y1723918D01*
G01X1385379Y1733118D02*
X1390179D01*
G01X1408817Y116911D02*
X1404917D01*
G01X1409992Y1154567D02*
X1408154Y1155614D01*
G01X1414285Y1539600D02*
X1412380D01*
X1408978Y1543002D01*
X1404157D01*
X1401230Y1545929D01*
X1400113D01*
X1399512Y1545328D01*
X1399034D01*
X1398211Y1544505D01*
G01X1401108Y1548083D02*
X1402763Y1547073D01*
G01X1401108Y1550445D02*
X1402707Y1549336D01*
G01X1414285Y1536100D02*
Y1536512D01*
X1412656Y1538141D01*
X1412244D01*
X1408726Y1541659D01*
X1405260D01*
X1402218Y1538617D01*
X1398703D01*
X1397030Y1540290D01*
Y1542459D01*
G01X1401108Y1555169D02*
X1405681Y1559742D01*
X1409149D01*
X1411366Y1561959D01*
X1412100Y1562263D01*
X1415329D01*
X1417639Y1559953D01*
G01X1412639D02*
X1411273Y1558587D01*
X1405771D01*
X1402569Y1555385D01*
Y1554268D01*
X1401108Y1552807D01*
G01Y1564618D02*
X1403059D01*
G01X1401108Y1562256D02*
X1401666Y1561698D01*
X1402970D01*
G01X1412648Y1573976D02*
X1411924D01*
X1404028Y1566080D01*
X1402225D01*
X1401944Y1565799D01*
X1399063D01*
G01Y1563437D02*
X1401916D01*
X1402195Y1563158D01*
X1404076D01*
X1404813Y1563895D01*
Y1565140D01*
X1408649Y1568976D01*
X1412648D01*
G01X1401754Y1573477D02*
X1406908Y1578631D01*
X1409044Y1583788D01*
Y1585457D01*
X1407851Y1586650D01*
X1407515D01*
G01X1404315Y1591650D02*
X1402175D01*
X1401185Y1590660D01*
Y1578668D01*
X1398211Y1575694D01*
Y1571431D01*
G01X1404315Y1586650D02*
X1403157D01*
X1402605Y1586098D01*
Y1580146D01*
X1403232Y1579519D01*
G01X1397030Y1573477D02*
Y1576895D01*
X1399765Y1579630D01*
Y1585684D01*
X1398799Y1586650D01*
X1397955D01*
G01X1416950Y1580400D02*
X1413999Y1577449D01*
X1411094D01*
X1402988Y1569343D01*
X1401108D01*
G01Y1566980D02*
X1401668Y1567540D01*
X1403058D01*
G01X1407515Y1586650D02*
Y1592557D01*
X1401189Y1598883D01*
X1399009D01*
G01X1404315Y1591650D02*
Y1593204D01*
X1403157Y1594362D01*
X1401552D01*
G01X1404315Y1589550D02*
Y1586650D01*
G01X1397955D02*
Y1589550D01*
G01D02*
X1394695D01*
G01X1416950Y1580400D02*
X1416188Y1581162D01*
X1414962D01*
X1410280Y1585844D01*
Y1593042D01*
X1398018Y1605304D01*
G01X1401208Y1622167D02*
Y1626167D01*
G01D02*
Y1629467D01*
X1401908Y1630167D01*
G01X1400029Y1615796D02*
X1401208Y1616975D01*
Y1622167D01*
G01X1405058D02*
Y1626167D01*
G01D02*
Y1630167D01*
G01X1406447Y1619572D02*
X1405058Y1620961D01*
Y1622167D01*
G01X1402499Y1634627D02*
Y1630758D01*
X1401908Y1630167D01*
G01X1399940Y1642107D02*
Y1639853D01*
X1400238Y1639555D01*
X1402013D01*
X1402499Y1640041D01*
Y1642107D01*
G01X1405058Y1634627D02*
Y1630167D01*
G01X1399940Y1642107D02*
Y1646967D01*
G01X1404740D02*
X1399940D01*
G01X1424271Y112849D02*
X1417760D01*
X1417635Y112974D01*
G01X1421989Y244450D02*
X1427119D01*
G01X1448194D02*
Y245960D01*
X1446270Y247884D01*
X1414051D01*
X1410750Y244583D01*
G01X1422945Y1151378D02*
X1424783Y1152425D01*
G01X1422945Y1157756D02*
X1424783Y1158803D01*
G01X1411842Y1151378D02*
X1410004Y1152425D01*
G01X1411842Y1157756D02*
X1410004Y1158803D01*
G01X1455314Y1267286D02*
Y1263089D01*
X1418869Y1226644D01*
Y1175257D01*
X1418982Y1175144D01*
G01X1414285Y1536100D02*
X1420979D01*
X1422289Y1534790D01*
X1424769D01*
X1427807Y1537828D01*
Y1541981D01*
G01X1419485Y1538000D02*
Y1538659D01*
X1422807Y1541981D01*
G01X1414285Y1539600D02*
Y1539202D01*
X1415487Y1538000D01*
X1419485D01*
G01X1422135Y1551850D02*
Y1554750D01*
G01X1417639Y1559953D02*
X1419437Y1561751D01*
X1421382D01*
X1422482Y1560651D01*
X1423638Y1557859D01*
Y1555917D01*
X1422471Y1554750D01*
X1422135D01*
G01X1418935D02*
X1418411Y1554745D01*
X1417457Y1555688D01*
Y1557012D01*
X1416897Y1557572D01*
X1414686Y1558488D01*
X1414104D01*
X1412639Y1559953D01*
G01X1418935Y1551850D02*
Y1554750D01*
G01X1412648Y1568976D02*
X1415184Y1566440D01*
X1419273D01*
G01X1419123Y1571000D02*
X1420199Y1569924D01*
Y1567698D01*
X1419273Y1566772D01*
Y1566440D01*
G01X1417023Y1577200D02*
X1413799Y1573976D01*
X1412648D01*
G01X1410622Y1610192D02*
X1409286Y1608856D01*
Y1605796D01*
G01X1415622Y1610192D02*
X1419622D01*
G01D02*
Y1609122D01*
X1418000Y1607500D01*
G01X1415623Y1599084D02*
X1419811D01*
G01D02*
X1425549D01*
X1425569Y1599104D01*
G01X1413622Y1625627D02*
Y1620622D01*
X1410622Y1617622D01*
Y1617000D01*
G01D02*
Y1613342D01*
G01X1416181Y1625627D02*
Y1617681D01*
X1416000Y1617500D01*
Y1617000D01*
G01D02*
X1415622Y1616622D01*
Y1613342D01*
G01X1421890Y1642967D02*
Y1635500D01*
G01X1418740Y1642967D02*
Y1638167D01*
G01D02*
Y1633107D01*
G01Y1646967D02*
Y1642967D01*
G01X1438262Y58467D02*
X1434262D01*
G01D02*
X1434187D01*
X1431262Y61392D01*
G01D02*
Y87345D01*
X1431175Y87432D01*
G01X1431816Y104219D02*
Y94665D01*
X1439049Y87432D01*
G01X1434513Y112975D02*
X1432853D01*
X1431816Y111938D01*
Y104219D01*
G01X1439049Y113018D02*
X1434556D01*
X1434513Y112975D01*
G01X1435257Y117664D02*
Y123110D01*
X1433549Y124818D01*
G01X1424271Y112849D02*
X1428694D01*
X1428733Y112888D01*
X1429169D01*
G01D02*
Y116337D01*
X1430496Y117664D01*
X1432107D01*
G01X1438312Y134818D02*
Y129581D01*
X1433549Y124818D01*
G01X1443430Y156866D02*
Y159802D01*
X1441672Y161560D01*
X1437289D01*
X1435645Y163204D01*
Y166180D01*
G01D02*
Y167304D01*
X1436983Y168642D01*
X1439769D01*
G01X1427119Y244450D02*
X1432044D01*
G01X1435194D02*
X1440119D01*
G01X1436567Y880670D02*
X1438405Y879623D01*
G01X1429165Y874292D02*
X1431003Y873245D01*
G01X1432866Y880670D02*
X1434704Y879623D01*
G01X1432866Y874292D02*
X1434704Y873245D01*
G01X1436567Y874292D02*
X1438405Y873245D01*
G01X1434716Y883859D02*
X1436554Y882812D01*
G01X1436567Y887048D02*
X1438405Y886001D01*
G01X1424795Y1160945D02*
X1426633Y1161992D01*
G01X1437748Y1157756D02*
X1439586Y1158803D01*
G01X1424795Y1154567D02*
X1426633Y1155614D01*
G01X1430346Y1157756D02*
X1432184Y1158803D01*
G01X1432197Y1154567D02*
X1434035Y1155614D01*
G01X1426646Y1157756D02*
X1428484Y1158803D01*
G01X1437735Y1155614D02*
X1435897Y1154567D01*
G01X1439586Y1152425D02*
X1437748Y1151378D01*
G01X1441335Y1547420D02*
X1438315D01*
X1438209Y1547314D01*
G01X1437435Y1543800D02*
X1441335D01*
G01X1437435D02*
Y1544135D01*
X1434256Y1547314D01*
X1433209D01*
G01X1438435Y1550640D02*
Y1551960D01*
X1437935Y1552460D01*
X1434185D01*
X1429800Y1556845D01*
Y1557762D01*
G01X1425569Y1599104D02*
Y1596545D01*
G01X1435884Y1609966D02*
Y1602163D01*
X1435384Y1601663D01*
X1433049D01*
G01X1435884Y1613904D02*
Y1609966D01*
G01X1426872Y1613966D02*
Y1609904D01*
G01D02*
Y1606649D01*
X1429621Y1603900D01*
Y1600206D01*
X1430723Y1599104D01*
X1433049D01*
G01X1438565Y1612583D02*
X1437244Y1613904D01*
X1435884D01*
G01X1426872Y1613966D02*
X1427067D01*
X1430238Y1617137D01*
G01X1436072Y1619566D02*
Y1623504D01*
G01Y1619566D02*
Y1618367D01*
X1437594Y1616845D01*
G01X1436072Y1623504D02*
Y1625238D01*
X1433184Y1628126D01*
G01X1429072Y1632989D02*
Y1629663D01*
X1426872Y1627463D01*
Y1623366D01*
G01Y1619504D02*
Y1617017D01*
X1426899Y1616990D01*
G01X1426872Y1623366D02*
Y1619504D01*
G01X1426513Y1640469D02*
Y1638534D01*
X1426977Y1638070D01*
X1428572D01*
X1429072Y1638570D01*
Y1640469D01*
G01Y1643655D02*
Y1640469D01*
G01X1433184Y1628126D02*
X1431631Y1629679D01*
Y1632989D01*
G01X1439087Y1682665D02*
X1436958D01*
X1433473Y1679180D01*
Y1664193D01*
X1436443Y1661223D01*
Y1655078D01*
X1433342Y1651977D01*
X1433157D01*
G01X1428811Y1647087D02*
Y1643916D01*
X1429072Y1643655D01*
G01X1439087Y1686165D02*
X1438443D01*
X1432133Y1679855D01*
Y1660816D01*
X1433618Y1659331D01*
G01X1445372Y56673D02*
X1446888D01*
X1449162Y58947D01*
Y61071D01*
X1466681Y78590D01*
G01X1445372Y60413D02*
X1441712D01*
X1439951Y62174D01*
G01X1450723Y103655D02*
Y102168D01*
X1446923Y98368D01*
Y87432D01*
G01X1446869Y111436D02*
X1449057D01*
X1450723Y109770D01*
Y103655D01*
G01X1439049Y116868D02*
Y113018D01*
G01Y120018D02*
X1438549Y120518D01*
Y124818D01*
G01X1443049Y120018D02*
X1443549Y120518D01*
Y124818D01*
G01X1443049Y116868D02*
Y113018D01*
G01D02*
X1445287D01*
X1446869Y111436D01*
G01X1448549Y120218D02*
Y134818D01*
G01Y120218D02*
X1446040D01*
G01X1450915Y125038D02*
X1451108Y124845D01*
Y121102D01*
X1452192Y120018D01*
X1454549D01*
G01Y113018D02*
X1452040D01*
G01X1443430Y134818D02*
Y129699D01*
X1438549Y124818D01*
G01X1445989Y134818D02*
Y127258D01*
X1443549Y124818D01*
G01X1451108Y134818D02*
Y125231D01*
X1450915Y125038D01*
G01X1449769Y168642D02*
Y163842D01*
G01X1448549Y156866D02*
Y162622D01*
X1449769Y163842D01*
G01X1451108Y156866D02*
Y161581D01*
X1453369Y163842D01*
X1454769D01*
G01X1445989Y156866D02*
Y162622D01*
X1444769Y163842D01*
G01D02*
Y168642D01*
G01X1449769Y176642D02*
Y174217D01*
G01D02*
Y171792D01*
G01X1439769Y176642D02*
Y174217D01*
G01Y171792D02*
Y174217D01*
G01X1445044Y244450D02*
X1440119D01*
G01X1438417Y883859D02*
X1440255Y882812D01*
G01X1440268Y931693D02*
X1442106Y930646D01*
G01X1451370Y938071D02*
X1453208Y937024D01*
G01X1443968Y938071D02*
X1445806Y937024D01*
G01X1449520Y934882D02*
X1451357Y933835D01*
G01X1445819Y934882D02*
X1447657Y933835D01*
G01X1447669Y938071D02*
X1449507Y937024D01*
G01X1452551Y1100355D02*
X1454389Y1101402D01*
G01X1447000Y1103544D02*
X1448838Y1104591D01*
G01X1450701Y1103544D02*
X1452539Y1104591D01*
G01X1445149Y1100355D02*
X1446987Y1101402D01*
G01X1448850Y1100355D02*
X1450688Y1101402D01*
G01X1445149Y1151378D02*
X1446987Y1152425D01*
G01X1447000Y1160945D02*
Y1162195D01*
X1444800Y1164395D01*
Y1223007D01*
X1518081Y1296288D01*
G01X1452551Y1157756D02*
X1454389Y1158803D01*
G01X1443287Y1165181D02*
X1441449Y1164134D01*
G01X1448850D02*
Y1177821D01*
X1478524Y1207495D01*
Y1233845D01*
X1505477Y1260798D01*
Y1265844D01*
G01X1447000Y1154567D02*
X1448838Y1155614D01*
G01X1452551Y1164134D02*
Y1172742D01*
X1463070Y1183261D01*
Y1183725D01*
X1460778Y1186017D01*
Y1186481D01*
X1461106Y1186809D01*
X1461570D01*
X1463862Y1184517D01*
X1464326D01*
X1464654Y1184845D01*
Y1185309D01*
X1462362Y1187601D01*
Y1188065D01*
X1462690Y1188393D01*
X1463154D01*
X1465446Y1186101D01*
X1465910D01*
X1466238Y1186429D01*
Y1186893D01*
X1463946Y1189185D01*
Y1189649D01*
X1464274Y1189977D01*
X1464738D01*
X1467030Y1187685D01*
X1467494D01*
X1467822Y1188013D01*
Y1188477D01*
X1465530Y1190769D01*
Y1191233D01*
X1465858Y1191561D01*
X1466322D01*
X1468614Y1189269D01*
X1469078D01*
X1469406Y1189597D01*
Y1190061D01*
X1467114Y1192353D01*
Y1192817D01*
X1467442Y1193145D01*
X1467906D01*
X1470198Y1190853D01*
X1470662D01*
X1480936Y1201127D01*
Y1231447D01*
X1513349Y1263860D01*
Y1268403D01*
X1521346Y1276400D01*
Y1281136D01*
G01X1513046Y1286424D02*
X1446867Y1220245D01*
Y1163559D01*
X1448850Y1161576D01*
Y1157756D01*
G01X1443299Y1154567D02*
X1445137Y1155614D01*
G01X1441449Y1157756D02*
X1443287Y1158803D01*
G01X1449956Y1267923D02*
Y1271295D01*
X1449334Y1271917D01*
G01Y1275067D02*
X1512707Y1338440D01*
X1564268D01*
G01X1441335Y1551040D02*
Y1549839D01*
X1441944Y1549230D01*
X1446695D01*
X1447470Y1550005D01*
Y1552121D01*
X1448156Y1552807D01*
X1451504D01*
G01X1438435Y1550640D02*
X1439552D01*
X1439952Y1551040D01*
X1441335D01*
G01X1451504Y1550445D02*
X1450750D01*
X1448108Y1547803D01*
Y1547248D01*
X1446470Y1545610D01*
X1441955D01*
X1441335Y1546230D01*
Y1547420D01*
G01X1450792Y1546218D02*
X1452866D01*
X1453550Y1546902D01*
G01X1449133Y1551121D02*
X1450128D01*
X1450633Y1551626D01*
X1453550D01*
G01Y1549264D02*
X1450815D01*
X1449119Y1547568D01*
Y1544809D01*
X1446270Y1541960D01*
X1442461D01*
X1441335Y1543086D01*
Y1543800D01*
G01X1453550Y1565799D02*
X1450088D01*
X1447833Y1568054D01*
Y1573363D01*
X1458492Y1584022D01*
Y1588570D01*
X1458756Y1588834D01*
G01X1451504Y1564618D02*
X1449321D01*
X1446350Y1567589D01*
Y1573791D01*
X1452771Y1580212D01*
Y1584952D01*
X1451835Y1585888D01*
X1451184D01*
G01X1453550Y1563437D02*
X1448386D01*
X1444736Y1567087D01*
Y1583552D01*
X1444184Y1584104D01*
Y1586688D01*
G01X1453550Y1553988D02*
X1450158D01*
X1449534Y1554612D01*
G01X1453550Y1568162D02*
X1450116D01*
X1449580Y1568698D01*
G01X1451504Y1569343D02*
X1449949Y1570898D01*
X1449580D01*
G01X1447984Y1585888D02*
X1447010D01*
X1446218Y1585096D01*
Y1578107D01*
X1447026Y1577299D01*
G01X1451184Y1588788D02*
Y1585888D01*
G01Y1588788D02*
X1452233D01*
X1453115Y1589670D01*
Y1593171D01*
X1452207Y1594079D01*
G01X1454274Y1600121D02*
X1445163Y1596346D01*
X1442502Y1593685D01*
Y1587269D01*
X1443083Y1586688D01*
X1444184D01*
G01Y1588788D02*
X1447984D01*
G01D02*
Y1585888D01*
G01X1445500Y1620575D02*
X1446425D01*
X1448000Y1619000D01*
Y1610000D01*
X1451000Y1607000D01*
Y1601000D01*
G01X1446000Y1600500D02*
Y1608500D01*
X1443000Y1611500D01*
Y1618075D01*
X1440500Y1620575D01*
G01X1450500Y1624000D02*
Y1626925D01*
G01Y1620575D02*
Y1624000D01*
G01X1445500Y1620575D02*
Y1626925D01*
G01X1440500D02*
Y1620575D01*
G01X1445500Y1617425D02*
Y1614500D01*
G01X1440500Y1617425D02*
Y1615000D01*
X1441000Y1614500D01*
G01X1450500Y1630075D02*
Y1632500D01*
X1451500Y1633500D01*
G01X1450579Y1640337D02*
Y1634421D01*
X1451500Y1633500D01*
G01X1445500Y1630075D02*
Y1633500D01*
G01X1445579Y1640337D02*
Y1633579D01*
X1445500Y1633500D01*
G01X1440500Y1630075D02*
Y1632500D01*
X1439500Y1633500D01*
G01X1440579Y1640337D02*
Y1634579D01*
X1439500Y1633500D01*
G01X1447579Y1667728D02*
Y1666131D01*
X1445579Y1664131D01*
Y1661203D01*
G01X1445079Y1677089D02*
Y1668728D01*
X1446079Y1667728D01*
X1447579D01*
G01X1450579Y1661203D02*
Y1664068D01*
X1452579Y1666068D01*
Y1667728D01*
G01X1451000Y1677000D02*
X1450639Y1676639D01*
Y1668228D01*
X1451139Y1667728D01*
X1452579D01*
G01X1445079Y1681103D02*
Y1677089D01*
G01X1450079Y1680138D02*
X1451000Y1679217D01*
Y1677000D01*
G01X1450079Y1680138D02*
X1449070Y1681147D01*
G01X1441187Y1682665D02*
X1442802Y1684280D01*
Y1686991D01*
X1443296Y1688184D01*
X1445102Y1689990D01*
X1445754D01*
G01X1441150Y1679544D02*
Y1682628D01*
X1441187Y1682665D01*
G01X1441167Y1689273D02*
Y1686185D01*
X1441187Y1686165D01*
G01X1474146Y1687854D02*
X1469466Y1692534D01*
X1443576D01*
X1441167Y1690125D01*
Y1689273D01*
G01X1445754Y1689990D02*
X1468676D01*
X1473943Y1684723D01*
Y1681921D01*
G01X1454820Y52933D02*
X1460820D01*
G01X1467980Y61563D02*
Y57777D01*
X1463136Y52933D01*
X1460820D01*
G01X1471830Y61563D02*
X1467980D01*
G01X1454549Y116868D02*
Y113018D01*
G01X1454769Y163842D02*
Y168642D01*
G01X1456982Y437362D02*
X1453872Y440472D01*
Y556710D01*
X1461832Y564670D01*
Y564977D01*
G01X1466682Y552977D02*
Y551373D01*
X1466347Y551038D01*
X1461377D01*
X1456682Y546343D01*
Y457182D01*
X1456500Y457000D01*
G01X1462682Y537827D02*
Y450372D01*
G01X1465832Y530656D02*
Y488019D01*
X1465395Y487582D01*
G01X1462682Y537827D02*
X1461143Y539366D01*
Y547204D01*
X1462916Y548977D01*
X1466682D01*
G01X1461832Y564977D02*
Y566197D01*
X1462563Y566928D01*
X1465957D01*
X1466682Y566203D01*
Y564977D01*
G01Y572977D02*
X1464257D01*
G01X1466682Y568977D02*
X1464257D01*
G01X1466682Y580977D02*
X1464257D01*
G01Y576977D02*
X1461832D01*
G01X1466682D02*
X1464257D01*
G01X1455071Y938071D02*
X1456909Y937024D01*
G01X1462472Y938071D02*
X1464310Y937024D01*
G01X1458771Y938071D02*
X1460609Y937024D01*
G01X1466173Y938071D02*
X1468011Y937024D01*
G01X1467354Y1100355D02*
X1469192Y1101402D01*
G01X1459953Y1100355D02*
X1461791Y1101402D01*
G01X1456252Y1100355D02*
X1458090Y1101402D01*
G01X1463653Y1100355D02*
X1465491Y1101402D01*
G01X1467354Y1151378D02*
X1469192Y1152425D01*
G01X1465504Y1154567D02*
X1467342Y1155614D01*
G01X1463653Y1157756D02*
X1465491Y1158803D01*
G01X1458102Y1154567D02*
X1459940Y1155614D01*
G01X1459953Y1164134D02*
X1461791Y1165181D01*
G01X1456252Y1151378D02*
X1458090Y1152425D01*
G01X1456252Y1164134D02*
Y1172003D01*
X1483496Y1199247D01*
Y1205480D01*
X1483824Y1205808D01*
X1486039D01*
X1486367Y1206136D01*
Y1206600D01*
X1486039Y1206928D01*
X1483824D01*
X1483496Y1207256D01*
Y1207720D01*
X1483824Y1208048D01*
X1486039D01*
X1486367Y1208376D01*
Y1208840D01*
X1486039Y1209168D01*
X1483824D01*
X1483496Y1209496D01*
Y1209960D01*
X1483824Y1210288D01*
X1486039D01*
X1486367Y1210616D01*
Y1211080D01*
X1486039Y1211408D01*
X1483824D01*
X1483496Y1211736D01*
Y1212200D01*
X1483824Y1212528D01*
X1486039D01*
X1486367Y1212856D01*
Y1213320D01*
X1486039Y1213648D01*
X1483824D01*
X1483496Y1213976D01*
Y1214440D01*
X1483824Y1214768D01*
X1486039D01*
X1486367Y1215096D01*
Y1215560D01*
X1486039Y1215888D01*
X1483824D01*
X1483496Y1216216D01*
Y1216680D01*
X1483824Y1217008D01*
X1486039D01*
X1486367Y1217336D01*
Y1217800D01*
X1486039Y1218128D01*
X1483824D01*
X1483496Y1218456D01*
Y1218920D01*
X1483824Y1219248D01*
X1486039D01*
X1486367Y1219576D01*
Y1220040D01*
X1486039Y1220368D01*
X1483824D01*
X1483496Y1220696D01*
Y1221160D01*
X1483824Y1221488D01*
X1486039D01*
X1486367Y1221816D01*
Y1222280D01*
X1486039Y1222608D01*
X1483824D01*
X1483496Y1222936D01*
Y1223400D01*
X1483824Y1223728D01*
X1486039D01*
X1486367Y1224056D01*
Y1224520D01*
X1486039Y1224848D01*
X1483824D01*
X1483496Y1225176D01*
Y1225640D01*
X1483824Y1225968D01*
X1486039D01*
X1486367Y1226296D01*
Y1226760D01*
X1486039Y1227088D01*
X1483824D01*
X1483496Y1227416D01*
Y1230583D01*
X1516857Y1263944D01*
Y1268115D01*
X1521842Y1273100D01*
X1522017D01*
X1529045Y1280128D01*
G01X1459953Y1157756D02*
X1461791Y1158803D01*
G01X1454401Y1154567D02*
X1456239Y1155614D01*
G01X1463653Y1164134D02*
Y1170874D01*
X1474399Y1181619D01*
Y1182081D01*
X1472480Y1184000D01*
Y1184464D01*
X1472808Y1184792D01*
X1473272D01*
X1475190Y1182874D01*
X1475654D01*
X1475982Y1183202D01*
Y1183666D01*
X1474064Y1185584D01*
Y1186048D01*
X1474392Y1186376D01*
X1474856D01*
X1476774Y1184458D01*
X1477238D01*
X1477566Y1184786D01*
Y1185250D01*
X1475648Y1187168D01*
Y1187632D01*
X1475976Y1187960D01*
X1476440D01*
X1478358Y1186042D01*
X1478822D01*
X1479150Y1186370D01*
Y1186834D01*
X1477232Y1188752D01*
Y1189216D01*
X1477560Y1189544D01*
X1478024D01*
X1479942Y1187626D01*
X1480406D01*
X1480734Y1187954D01*
Y1188418D01*
X1478816Y1190336D01*
Y1190800D01*
X1479144Y1191128D01*
X1479608D01*
X1481526Y1189210D01*
X1481990D01*
X1482318Y1189538D01*
Y1190002D01*
X1480400Y1191920D01*
Y1192384D01*
X1480728Y1192712D01*
X1481192D01*
X1483110Y1190794D01*
X1483574D01*
X1483902Y1191122D01*
Y1191586D01*
X1481984Y1193504D01*
Y1193968D01*
X1482312Y1194296D01*
X1482776D01*
X1484694Y1192378D01*
X1485158D01*
X1485486Y1192706D01*
Y1193170D01*
X1483568Y1195088D01*
Y1195552D01*
X1483896Y1195880D01*
X1484360D01*
X1486279Y1193961D01*
X1486741D01*
X1488787Y1196008D01*
Y1232450D01*
X1522875Y1266538D01*
Y1268496D01*
G01X1455314Y1267286D02*
Y1269937D01*
X1453334Y1271917D01*
G01X1597621Y1365384D02*
X1578792D01*
X1569240Y1355832D01*
Y1339102D01*
X1565750Y1335612D01*
X1513879D01*
X1453334Y1275067D01*
G01X1455461Y1592939D02*
Y1590039D01*
G01D02*
X1457551D01*
X1458756Y1588834D01*
G01X1457579Y1667728D02*
X1461617D01*
X1461702Y1667813D01*
G01X1455579Y1661203D02*
Y1665701D01*
G01D02*
Y1665976D01*
X1457331Y1667728D01*
X1457579D01*
G01X1465500Y1670550D02*
Y1672789D01*
X1463231Y1675058D01*
Y1676766D01*
G01D02*
X1463572Y1677107D01*
X1467968D01*
X1468608Y1677747D01*
X1469506D01*
X1470006Y1677247D01*
Y1676881D01*
G01Y1681921D02*
Y1683107D01*
X1468015Y1685098D01*
X1466111D01*
G01X1474980Y61563D02*
Y58934D01*
X1472129Y56083D01*
G01X1475257Y530656D02*
X1471395Y526794D01*
Y487582D01*
G01X1469832Y552977D02*
X1471213D01*
X1473444Y555208D01*
G01X1469832Y548977D02*
X1469993D01*
X1472257Y551241D01*
G01X1469832Y544977D02*
Y548977D01*
G01Y556977D02*
X1471235Y558380D01*
X1473362D01*
G01X1469832Y564977D02*
X1472257D01*
G01X1469832Y560977D02*
Y562153D01*
X1472257Y564578D01*
Y564977D01*
G01X1469874Y874292D02*
X1471712Y873245D01*
G01X1475413D02*
X1473575Y874292D01*
G01X1480964Y876434D02*
X1479126Y877481D01*
G01Y890237D02*
X1480964Y889190D01*
G01X1482827Y890237D02*
X1484665Y889190D01*
G01X1477275Y893426D02*
X1479113Y892379D01*
G01X1482827Y909370D02*
X1484665Y908324D01*
G01X1479126Y902993D02*
X1480964Y901946D01*
G01X1482827Y902993D02*
X1484665Y901946D01*
G01X1477275Y906181D02*
X1479113Y905134D01*
G01X1479126Y909370D02*
X1480964Y908324D01*
G01X1477275Y912559D02*
X1479113Y911512D01*
G01X1479126Y922126D02*
X1480964Y921079D01*
G01X1482827Y922126D02*
X1484665Y921079D01*
G01X1477275Y925315D02*
X1479113Y924268D01*
G01X1479126Y928504D02*
X1480964Y927457D01*
G01X1482827Y928504D02*
X1484665Y927457D01*
G01X1477275Y931693D02*
X1479113Y930646D01*
G01X1479126Y941260D02*
X1480964Y940213D01*
G01X1469874Y938071D02*
X1471712Y937024D01*
G01X1482827Y941260D02*
X1484665Y940213D01*
G01X1477275Y944449D02*
X1479113Y943402D01*
G01X1479126Y947638D02*
X1480964Y946591D01*
G01X1482827Y947638D02*
X1484665Y946591D01*
G01X1477275Y950827D02*
X1479113Y949780D01*
G01X1479126Y966772D02*
X1480964Y965725D01*
G01X1482827Y966772D02*
X1484665Y965725D01*
G01X1477275Y969961D02*
X1479113Y968914D01*
G01X1479126Y960394D02*
X1480964Y959347D01*
G01X1482827Y960394D02*
X1484665Y959347D01*
G01X1477275Y963583D02*
X1479113Y962536D01*
G01X1479126Y985906D02*
X1480964Y984859D01*
G01X1479126Y979528D02*
X1480964Y978481D01*
G01X1482827Y979528D02*
X1484665Y978481D01*
G01X1477275Y982717D02*
X1479113Y981670D01*
G01X1477275Y989095D02*
X1479113Y988048D01*
G01X1482827Y998662D02*
X1484665Y997615D01*
G01X1479126Y998662D02*
X1480964Y997615D01*
G01X1479126Y992284D02*
X1480964Y991237D01*
G01X1477275Y995473D02*
X1479113Y994426D01*
G01X1482827Y992284D02*
X1484665Y991237D01*
G01X1477275Y1001851D02*
X1479113Y1000804D01*
G01X1482827Y1005040D02*
X1484665Y1003993D01*
G01X1479126Y1005040D02*
X1480964Y1003993D01*
G01X1477275Y1008229D02*
X1479113Y1007182D01*
G01X1479126Y1011418D02*
X1480964Y1010371D01*
G01X1480307Y1027008D02*
X1482145Y1028055D01*
G01X1478457Y1030197D02*
X1480295Y1031244D01*
G01X1480307Y1033386D02*
X1482145Y1034433D01*
G01X1478457Y1036575D02*
X1480295Y1037622D01*
G01X1480307Y1039764D02*
X1482145Y1040811D01*
G01X1478457Y1042953D02*
X1480295Y1044000D01*
G01X1478457Y1049331D02*
X1480295Y1050378D01*
G01X1480307Y1046142D02*
X1482145Y1047189D01*
G01X1480307Y1052520D02*
X1482145Y1053567D01*
G01X1478457Y1074843D02*
X1480295Y1075890D01*
G01X1478457Y1062087D02*
X1480295Y1063134D01*
G01X1480307Y1065276D02*
X1482145Y1066323D01*
G01X1480307Y1078032D02*
X1482145Y1079079D01*
G01X1478457Y1081221D02*
X1480295Y1082268D01*
G01X1480307Y1084410D02*
X1482145Y1085457D01*
G01X1480307Y1103544D02*
X1482145Y1104591D01*
G01X1478457Y1093977D02*
X1480295Y1095024D01*
G01X1480307Y1097166D02*
X1482145Y1098213D01*
G01X1478457Y1100355D02*
X1480295Y1101402D01*
G01X1478457Y1113111D02*
X1480295Y1114158D01*
G01X1480307Y1116300D02*
X1482145Y1117347D01*
G01X1478457Y1119489D02*
X1480295Y1120536D01*
G01X1480307Y1122678D02*
X1482145Y1123725D01*
G01X1478457Y1132245D02*
X1480295Y1133292D01*
G01X1480307Y1135433D02*
X1482145Y1136480D01*
G01X1478457Y1138622D02*
X1480295Y1139669D01*
G01X1480307Y1141811D02*
X1482145Y1142858D01*
G01X1471055Y1157756D02*
X1472893Y1158803D01*
G01X1474756Y1164134D02*
X1476778Y1165778D01*
G01X1469205Y1154567D02*
X1471043Y1155614D01*
G01X1471055Y1164134D02*
Y1169832D01*
X1490925Y1189702D01*
Y1230974D01*
X1492188Y1232237D01*
X1492782D01*
X1495792Y1229227D01*
X1496386D01*
X1497150Y1229991D01*
Y1230585D01*
X1494140Y1233595D01*
Y1234189D01*
X1494904Y1234953D01*
X1495498D01*
X1498508Y1231943D01*
X1499102D01*
X1499866Y1232707D01*
Y1233301D01*
X1496856Y1236311D01*
Y1236905D01*
X1497620Y1237669D01*
X1498214D01*
X1501354Y1234529D01*
X1501948D01*
X1502712Y1235293D01*
Y1235887D01*
X1499572Y1239027D01*
Y1239621D01*
X1500336Y1240385D01*
X1500930D01*
X1504034Y1237281D01*
X1504628D01*
X1505392Y1238045D01*
Y1238639D01*
X1502288Y1241743D01*
Y1242337D01*
X1503052Y1243101D01*
X1503646D01*
X1506774Y1239973D01*
X1507368D01*
X1508132Y1240737D01*
Y1241331D01*
X1505004Y1244459D01*
Y1245053D01*
X1505768Y1245817D01*
X1506362D01*
X1508530Y1243649D01*
X1509124D01*
X1509888Y1244413D01*
Y1245007D01*
X1507720Y1247175D01*
Y1247769D01*
X1527402Y1267451D01*
Y1269664D01*
X1548647Y1290909D01*
X1553773D01*
X1556349Y1288333D01*
Y1284255D01*
X1560454Y1280150D01*
Y1279004D01*
G01X1469205Y1160945D02*
X1471043Y1161992D01*
G01X1478457Y1151378D02*
X1480295Y1152425D01*
G01X1480307Y1154567D02*
X1482145Y1155614D01*
G01X1478457Y1164134D02*
Y1170583D01*
X1492801Y1184927D01*
Y1219480D01*
X1528857Y1255536D01*
Y1266243D01*
X1537295Y1274681D01*
G01X1482157Y1164134D02*
Y1172387D01*
X1494421Y1184651D01*
Y1218682D01*
X1494652D01*
X1532229Y1256259D01*
Y1265615D01*
X1532335Y1265721D01*
G01X1474756Y1157756D02*
X1476594Y1158803D01*
G01X1473943Y1676881D02*
Y1675115D01*
X1469645Y1670817D01*
X1468102D01*
G01X1482680Y1668917D02*
X1487652D01*
X1488875Y1670140D01*
Y1677385D01*
G01X1471975Y1676881D02*
Y1675729D01*
X1469588Y1673342D01*
G01X1482450Y1678500D02*
Y1675950D01*
X1481612Y1675112D01*
G01D02*
X1481000Y1674500D01*
X1477000D01*
X1475912Y1675588D01*
Y1676881D01*
G01Y1681921D02*
Y1686088D01*
X1474146Y1687854D01*
G01X1471975Y1681921D02*
Y1684025D01*
X1470500Y1685500D01*
G01X1502443Y127082D02*
X1500802D01*
X1494891Y121171D01*
G01X1492797Y134562D02*
X1488647D01*
G01X1489177Y812988D02*
X1491377D01*
X1492477Y814088D01*
Y819388D01*
X1494277Y821188D01*
X1502177D01*
X1504296Y823307D01*
Y848046D01*
X1511594Y855344D01*
Y868712D01*
X1507560Y872746D01*
X1506160D01*
X1505336Y873570D01*
Y874324D01*
X1503822Y875838D01*
X1500228D01*
X1499301Y876765D01*
Y878265D01*
X1496896Y880670D01*
X1495779D01*
G01X1493929Y877481D02*
Y871432D01*
X1497176Y868185D01*
X1501961D01*
X1504592Y865554D01*
Y858090D01*
X1492728Y846226D01*
Y832092D01*
X1490239Y829603D01*
Y826291D01*
X1490973Y825557D01*
G01X1495779Y874292D02*
Y871874D01*
X1497848Y869805D01*
X1502691D01*
X1506475Y866021D01*
Y857585D01*
X1495277Y846387D01*
Y826466D01*
X1495670Y826073D01*
G01X1492079Y874292D02*
Y870987D01*
X1496501Y866565D01*
X1501153D01*
X1502708Y865010D01*
Y858585D01*
X1490577Y846454D01*
Y832763D01*
X1486761Y828947D01*
Y826279D01*
G01X1486515Y879623D02*
X1484677Y880670D01*
G01X1488378D02*
X1490216Y879623D01*
G01X1492079Y880670D02*
X1493396D01*
X1495801Y878265D01*
Y876764D01*
X1497431Y875134D01*
Y873334D01*
X1499640Y871125D01*
X1503759D01*
X1508189Y866695D01*
Y857003D01*
X1498177Y846991D01*
Y829359D01*
G01X1484677Y887048D02*
X1486515Y886001D01*
G01X1495779Y887048D02*
X1497617Y886001D01*
G01X1490228Y890237D02*
X1492066Y889190D01*
G01X1497630Y890237D02*
X1499468Y889190D01*
G01X1492079Y893426D02*
X1493917Y892379D01*
G01X1490228Y883859D02*
X1492066Y882812D01*
G01X1484677Y899804D02*
X1486515Y898757D01*
G01X1484677Y906181D02*
X1486515Y905134D01*
G01X1497630Y909370D02*
X1499468Y908324D01*
G01X1495779Y899804D02*
X1497617Y898757D01*
G01X1490228Y902993D02*
X1492066Y901946D01*
G01X1497630Y902993D02*
X1499468Y901946D01*
G01X1492079Y906181D02*
X1493917Y905134D01*
G01X1495779Y906181D02*
X1497617Y905134D01*
G01X1490228Y909370D02*
X1492066Y908324D01*
G01X1484677Y918937D02*
X1486515Y917890D01*
G01X1484677Y925315D02*
X1486515Y924268D01*
G01X1492079Y912559D02*
X1493917Y911512D01*
G01X1495779Y918937D02*
X1497617Y917890D01*
G01X1490228Y922126D02*
X1492066Y921079D01*
G01X1497630Y922126D02*
X1499468Y921079D01*
G01X1492079Y925315D02*
X1493917Y924268D01*
G01X1495779Y925315D02*
X1497617Y924268D01*
G01X1484677Y938071D02*
X1486515Y937024D01*
G01X1490228Y928504D02*
X1492066Y927457D01*
G01X1497630Y928504D02*
X1499468Y927457D01*
G01X1492079Y931693D02*
X1493917Y930646D01*
G01X1495779Y938071D02*
X1497617Y937024D01*
G01X1490228Y941260D02*
X1492066Y940213D01*
G01X1484677Y944449D02*
X1486515Y943402D01*
G01X1497630Y941260D02*
X1499468Y940213D01*
G01X1492079Y944449D02*
X1493917Y943402D01*
G01X1495779Y944449D02*
X1497617Y943402D01*
G01X1490228Y947638D02*
X1492066Y946591D01*
G01X1497630Y947638D02*
X1499468Y946591D01*
G01X1492079Y950827D02*
X1493917Y949780D01*
G01X1484677Y963583D02*
X1486515Y962536D01*
G01X1484677Y957205D02*
X1486515Y956158D01*
G01X1495779Y963583D02*
X1497617Y962536D01*
G01X1490228Y966772D02*
X1492066Y965725D01*
G01X1497630Y966772D02*
X1499468Y965725D01*
G01X1492079Y969961D02*
X1493917Y968914D01*
G01X1495779Y957205D02*
X1497617Y956158D01*
G01X1490228Y960394D02*
X1492066Y959347D01*
G01X1497630Y960394D02*
X1499468Y959347D01*
G01X1492079Y963583D02*
X1493917Y962536D01*
G01X1484677Y976339D02*
X1486515Y975292D01*
G01X1490228Y985906D02*
X1492066Y984859D01*
G01X1495779Y976339D02*
X1497617Y975292D01*
G01X1490228Y979528D02*
X1492066Y978481D01*
G01X1497630Y979528D02*
X1499468Y978481D01*
G01X1492079Y982717D02*
X1493917Y981670D01*
G01X1484677Y995473D02*
X1486515Y994426D01*
G01X1484677Y989095D02*
X1486515Y988048D01*
G01X1492079Y989095D02*
X1493917Y988048D01*
G01X1495779Y995473D02*
X1497617Y994426D01*
G01X1497630Y998662D02*
X1499468Y997615D01*
G01X1490228Y998662D02*
X1492066Y997615D01*
G01X1495779Y989095D02*
X1497617Y988048D01*
G01X1490228Y992284D02*
X1492066Y991237D01*
G01X1492079Y995473D02*
X1493917Y994426D01*
G01X1497630Y992284D02*
X1499468Y991237D01*
G01X1484677Y1001851D02*
X1486515Y1000804D01*
G01X1492079Y1001851D02*
X1493917Y1000804D01*
G01X1495779Y1001851D02*
X1497617Y1000804D01*
G01X1497630Y1005040D02*
X1499468Y1003993D01*
G01X1490228Y1005040D02*
X1492066Y1003993D01*
G01X1492079Y1008229D02*
X1493917Y1007182D01*
G01X1490228Y1011418D02*
X1492066Y1010371D01*
G01X1491409Y1027008D02*
X1493247Y1028055D01*
G01X1484008Y1027008D02*
X1485846Y1028055D01*
G01X1484008Y1033386D02*
X1485846Y1034433D01*
G01X1485858Y1036575D02*
X1487696Y1037622D01*
G01X1484008Y1039764D02*
X1485846Y1040811D01*
G01X1493260Y1030197D02*
X1495098Y1031244D01*
G01X1491409Y1033386D02*
X1493247Y1034433D01*
G01X1496960Y1036575D02*
X1498799Y1037622D01*
G01X1493260Y1036575D02*
X1495098Y1037622D01*
G01X1491409Y1039764D02*
X1493247Y1040811D01*
G01X1493260Y1042953D02*
X1495098Y1044000D01*
G01X1496960Y1042953D02*
X1498798Y1044000D01*
G01X1496960Y1030197D02*
X1498798Y1031244D01*
G01X1485858Y1042953D02*
X1487696Y1044000D01*
G01X1485858Y1030197D02*
X1487696Y1031244D01*
G01X1484008Y1058898D02*
X1485846Y1059945D01*
G01X1485858Y1049331D02*
X1487696Y1050378D01*
G01X1484008Y1052520D02*
X1485846Y1053567D01*
G01X1493260Y1049331D02*
X1495098Y1050378D01*
G01X1491409Y1046142D02*
X1493247Y1047189D01*
G01X1496960Y1049331D02*
X1498799Y1050378D01*
G01X1496960Y1055709D02*
X1498798Y1056756D01*
G01X1491409Y1052520D02*
X1493247Y1053567D01*
G01X1485858Y1055709D02*
X1487696Y1056756D01*
G01X1484008Y1046142D02*
X1485846Y1047189D01*
G01X1484008Y1071654D02*
X1485846Y1072701D01*
G01X1485858Y1074843D02*
X1487696Y1075890D01*
G01X1485858Y1062087D02*
X1487696Y1063134D01*
G01X1493260Y1074843D02*
X1495098Y1075890D01*
G01X1496960Y1074843D02*
X1498799Y1075890D01*
G01X1493260Y1062087D02*
X1495098Y1063134D01*
G01X1496960Y1062087D02*
X1498799Y1063134D01*
G01X1491409Y1065276D02*
X1493247Y1066323D01*
G01X1484008Y1078032D02*
X1485846Y1079079D01*
G01X1485858Y1081221D02*
X1487696Y1082268D01*
G01X1491409Y1078032D02*
X1493247Y1079079D01*
G01X1493260Y1081221D02*
X1495098Y1082268D01*
G01X1496960Y1081221D02*
X1498799Y1082268D01*
G01X1491409Y1084410D02*
X1493247Y1085457D01*
G01X1485858Y1100355D02*
X1487696Y1101402D01*
G01X1484008Y1090788D02*
X1485846Y1091835D01*
G01X1485858Y1093977D02*
X1487696Y1095024D01*
G01X1484008Y1097166D02*
X1485846Y1098213D01*
G01X1496960Y1100355D02*
X1498799Y1101402D01*
G01X1491409Y1103544D02*
X1493247Y1104591D01*
G01X1493260Y1093977D02*
X1495098Y1095024D01*
G01X1496960Y1093977D02*
X1498799Y1095024D01*
G01X1491409Y1097166D02*
X1493247Y1098213D01*
G01X1493260Y1100355D02*
X1495098Y1101402D01*
G01X1484008Y1109922D02*
X1485846Y1110969D01*
G01X1485858Y1113111D02*
X1487696Y1114158D01*
G01X1484008Y1116300D02*
X1485846Y1117347D01*
G01X1485858Y1119489D02*
X1487696Y1120536D01*
G01X1493260Y1113111D02*
X1495098Y1114158D01*
G01X1496960Y1113111D02*
X1498799Y1114158D01*
G01X1491409Y1116300D02*
X1493247Y1117347D01*
G01X1493260Y1119489D02*
X1495098Y1120536D01*
G01X1496960Y1119489D02*
X1498799Y1120536D01*
G01X1484008Y1129056D02*
X1485846Y1130102D01*
G01X1485858Y1132245D02*
X1487696Y1133292D01*
G01X1491409Y1122678D02*
X1493247Y1123725D01*
G01X1493260Y1132245D02*
X1495098Y1133292D01*
G01X1496960Y1132245D02*
X1498799Y1133292D01*
G01X1484008Y1135433D02*
X1485846Y1136480D01*
G01X1485858Y1138622D02*
X1487696Y1139669D01*
G01X1484008Y1148189D02*
X1485846Y1149236D01*
G01X1491409Y1135433D02*
X1493247Y1136480D01*
G01X1493260Y1138622D02*
X1495098Y1139669D01*
G01X1496960Y1138622D02*
X1498799Y1139669D01*
G01X1491409Y1141811D02*
X1493247Y1142858D01*
G01X1485858Y1151378D02*
X1487696Y1152425D01*
G01X1493260Y1151378D02*
X1495098Y1152425D01*
G01X1496960Y1151378D02*
X1498799Y1152425D01*
G01X1493260Y1164134D02*
Y1167390D01*
G01X1496960Y1164134D02*
Y1167390D01*
G01X1515464Y1164134D02*
X1496497Y1183101D01*
Y1216946D01*
X1532580Y1253029D01*
X1542174D01*
X1542747Y1253602D01*
G01X1484550Y1678500D02*
X1487000Y1680950D01*
Y1685000D01*
X1486000Y1686000D01*
G01X1502443Y130822D02*
X1509479D01*
G01D02*
X1514358D01*
X1514367Y130813D01*
G01X1510682Y563977D02*
X1510302Y564357D01*
X1507468D01*
G01X1503932Y561677D02*
X1506337D01*
G01X1529086Y880670D02*
X1530065D01*
X1532702Y878033D01*
Y871105D01*
X1508036Y846439D01*
Y815495D01*
X1501604Y809063D01*
X1500500D01*
G01X1510261Y814611D02*
Y845664D01*
X1536488Y871891D01*
Y874292D01*
G01X1540189D02*
Y872592D01*
X1512539Y844942D01*
Y812920D01*
G01X1505016Y817107D02*
X1505916Y818007D01*
Y847319D01*
X1513224Y854627D01*
Y869585D01*
X1508517Y874292D01*
X1506882D01*
G01X1503181D02*
Y873468D01*
X1505073Y871576D01*
X1506135D01*
X1509925Y867786D01*
Y856352D01*
X1500730Y847157D01*
Y829602D01*
X1501536Y828796D01*
X1501636D01*
G01X1505031Y877481D02*
X1506869Y876434D01*
G01X1503181Y880670D02*
X1505019Y879623D01*
G01X1510583Y887048D02*
X1512421Y886001D01*
G01X1505031Y890237D02*
X1506869Y889190D01*
G01X1508732Y890237D02*
X1510570Y889190D01*
G01X1503181Y893426D02*
X1505019Y892379D01*
G01X1505031Y883859D02*
X1506869Y882812D01*
G01X1508732Y909370D02*
X1510570Y908324D01*
G01X1510583Y899804D02*
X1512421Y898757D01*
G01X1505031Y902993D02*
X1506869Y901946D01*
G01X1508732Y902993D02*
X1510570Y901946D01*
G01X1503181Y906181D02*
X1505019Y905134D01*
G01X1510583Y906181D02*
X1512421Y905134D01*
G01X1505031Y909370D02*
X1506869Y908324D01*
G01X1503181Y912559D02*
X1505019Y911512D01*
G01X1510583Y918937D02*
X1512421Y917890D01*
G01X1505031Y922126D02*
X1506869Y921079D01*
G01X1508732Y922126D02*
X1510570Y921079D01*
G01X1503181Y925315D02*
X1505019Y924268D01*
G01X1510583Y925315D02*
X1512421Y924268D01*
G01X1505031Y928504D02*
X1506869Y927457D01*
G01X1508732Y928504D02*
X1510570Y927457D01*
G01X1503181Y931693D02*
X1505019Y930646D01*
G01X1510583Y938071D02*
X1512421Y937024D01*
G01X1505031Y941260D02*
X1506869Y940213D01*
G01X1508732Y941260D02*
X1510570Y940213D01*
G01X1503181Y944449D02*
X1505019Y943402D01*
G01X1510583Y944449D02*
X1512421Y943402D01*
G01X1505031Y947638D02*
X1506869Y946591D01*
G01X1508732Y947638D02*
X1510570Y946591D01*
G01X1503181Y950827D02*
X1505019Y949780D01*
G01X1510583Y963583D02*
X1512421Y962536D01*
G01X1505031Y966772D02*
X1506869Y965725D01*
G01X1508732Y966772D02*
X1510570Y965725D01*
G01X1503181Y969961D02*
X1505019Y968914D01*
G01X1510583Y957205D02*
X1512421Y956158D01*
G01X1505031Y960394D02*
X1506869Y959347D01*
G01X1508732Y960394D02*
X1510570Y959347D01*
G01X1503181Y963583D02*
X1505019Y962536D01*
G01X1505031Y985906D02*
X1506869Y984859D01*
G01X1510583Y976339D02*
X1512421Y975292D01*
G01X1505031Y979528D02*
X1506869Y978481D01*
G01X1508732Y979528D02*
X1510570Y978481D01*
G01X1503181Y982717D02*
X1505019Y981670D01*
G01X1503181Y989095D02*
X1505019Y988048D01*
G01X1510583Y995473D02*
X1512421Y994426D01*
G01X1508732Y998662D02*
X1510570Y997615D01*
G01X1505031Y998662D02*
X1506869Y997615D01*
G01X1510583Y989095D02*
X1512421Y988048D01*
G01X1505031Y992284D02*
X1506869Y991237D01*
G01X1503181Y995473D02*
X1505019Y994426D01*
G01X1508732Y992284D02*
X1510570Y991237D01*
G01X1503181Y1001851D02*
X1505019Y1000804D01*
G01X1510583Y1001851D02*
X1512421Y1000804D01*
G01X1508732Y1005040D02*
X1510570Y1003993D01*
G01X1505031Y1005040D02*
X1506869Y1003993D01*
G01X1503181Y1008229D02*
X1505019Y1007182D01*
G01X1505031Y1011418D02*
X1506869Y1010371D01*
G01X1506212Y1027008D02*
X1508050Y1028055D01*
G01X1498811Y1027008D02*
X1500649Y1028055D01*
G01X1509913Y1027008D02*
X1511751Y1028055D01*
G01X1504362Y1030197D02*
X1506200Y1031244D01*
G01X1506212Y1033386D02*
X1508050Y1034433D01*
G01X1509913Y1033386D02*
X1511751Y1034433D01*
G01X1511764Y1036575D02*
X1513602Y1037622D01*
G01X1504362Y1036575D02*
X1506200Y1037622D01*
G01X1506212Y1039764D02*
X1508050Y1040811D01*
G01X1509913Y1039764D02*
X1511751Y1040811D01*
G01X1504362Y1042953D02*
X1506200Y1044000D01*
G01X1498811Y1033386D02*
X1500649Y1034433D01*
G01X1498811Y1039764D02*
X1500649Y1040811D01*
G01X1511764Y1042953D02*
X1513602Y1044000D01*
G01X1511764Y1030197D02*
X1513602Y1031244D01*
G01X1504362Y1049331D02*
X1506200Y1050378D01*
G01X1509913Y1058898D02*
X1511751Y1059945D01*
G01X1506212Y1046142D02*
X1508050Y1047189D01*
G01X1511764Y1049331D02*
X1513602Y1050378D01*
G01X1509913Y1052520D02*
X1511751Y1053567D01*
G01X1498811Y1058898D02*
X1500649Y1059945D01*
G01X1498811Y1052520D02*
X1500649Y1053567D01*
G01X1498811Y1046142D02*
X1500649Y1047189D01*
G01X1511764Y1055709D02*
X1513602Y1056756D01*
G01X1509913Y1046142D02*
X1511751Y1047189D01*
G01X1506212Y1052520D02*
X1508050Y1053567D01*
G01X1509913Y1071654D02*
X1511751Y1072701D01*
G01X1504362Y1074843D02*
X1506200Y1075890D01*
G01X1511764Y1074843D02*
X1513602Y1075890D01*
G01X1504362Y1062087D02*
X1506200Y1063134D01*
G01X1511764Y1062087D02*
X1513602Y1063134D01*
G01X1506212Y1065276D02*
X1508050Y1066323D01*
G01X1498811Y1071654D02*
X1500649Y1072701D01*
G01X1506212Y1078032D02*
X1508050Y1079079D01*
G01X1509913Y1078032D02*
X1511751Y1079079D01*
G01X1504362Y1081221D02*
X1506200Y1082268D01*
G01X1511764Y1081221D02*
X1513602Y1082268D01*
G01X1506212Y1084410D02*
X1508050Y1085457D01*
G01X1498811Y1078032D02*
X1500649Y1079079D01*
G01X1511764Y1100355D02*
X1513602Y1101402D01*
G01X1506212Y1103544D02*
X1508050Y1104591D01*
G01X1509913Y1090788D02*
X1511751Y1091835D01*
G01X1504362Y1093977D02*
X1506200Y1095024D01*
G01X1511764Y1093977D02*
X1513602Y1095024D01*
G01X1506212Y1097166D02*
X1508050Y1098213D01*
G01X1509913Y1097166D02*
X1511751Y1098213D01*
G01X1504362Y1100355D02*
X1506200Y1101402D01*
G01X1498811Y1090788D02*
X1500649Y1091835D01*
G01X1498811Y1097166D02*
X1500649Y1098213D01*
G01X1509913Y1109922D02*
X1511751Y1110969D01*
G01X1504362Y1113111D02*
X1506200Y1114158D01*
G01X1511764Y1113111D02*
X1513602Y1114158D01*
G01X1506212Y1116300D02*
X1508050Y1117347D01*
G01X1509913Y1116300D02*
X1511751Y1117347D01*
G01X1504362Y1119489D02*
X1506200Y1120536D01*
G01X1511764Y1119489D02*
X1513602Y1120536D01*
G01X1498811Y1109922D02*
X1500649Y1110969D01*
G01X1498811Y1116300D02*
X1500649Y1117347D01*
G01X1506212Y1122678D02*
X1508050Y1123725D01*
G01X1509913Y1129056D02*
X1511751Y1130102D01*
G01X1504362Y1132245D02*
X1506200Y1133292D01*
G01X1511764Y1132245D02*
X1513602Y1133292D01*
G01X1498811Y1129056D02*
X1500649Y1130102D01*
G01X1506212Y1135433D02*
X1508050Y1136480D01*
G01X1509913Y1135433D02*
X1511751Y1136480D01*
G01X1504362Y1138622D02*
X1506200Y1139669D01*
G01X1511764Y1138622D02*
X1513602Y1139669D01*
G01X1506212Y1141811D02*
X1508050Y1142858D01*
G01X1509913Y1148189D02*
X1511751Y1149236D01*
G01X1498811Y1135433D02*
X1500649Y1136480D01*
G01X1498811Y1148189D02*
X1500649Y1149236D01*
G01X1504362Y1151378D02*
X1506200Y1152425D01*
G01X1511764Y1151378D02*
X1513602Y1152425D01*
G01X1506212Y1154567D02*
X1508050Y1155614D01*
G01X1498811Y1154567D02*
X1500649Y1155614D01*
G01X1511764Y1157756D02*
X1513602Y1158803D01*
G01X1504362Y1164134D02*
Y1167390D01*
G01X1508063Y1164134D02*
Y1167390D01*
G01X1498811Y1160945D02*
X1500649Y1161992D01*
G01X1502512Y1160945D02*
X1504350Y1161992D01*
G01X1543980Y1258312D02*
X1544538D01*
X1547589Y1255261D01*
Y1252132D01*
X1545604Y1250147D01*
X1534658D01*
X1502921Y1218410D01*
Y1185297D01*
X1508454Y1179764D01*
Y1178129D01*
X1521016Y1165567D01*
Y1160945D01*
G01X1519165Y1164134D02*
Y1165409D01*
X1507034Y1177540D01*
Y1179175D01*
X1498287Y1187922D01*
Y1216316D01*
X1533543Y1251572D01*
X1544787D01*
X1545627Y1252412D01*
Y1254068D01*
G01X1521003Y1169488D02*
X1517551Y1172940D01*
X1515652D01*
X1509874Y1178718D01*
Y1180353D01*
X1504341Y1185886D01*
Y1217586D01*
X1534960Y1248205D01*
X1543519D01*
G01X1532896Y1234836D02*
X1530150Y1232090D01*
X1523726D01*
X1508007Y1216371D01*
Y1190336D01*
X1524896Y1173447D01*
Y1165537D01*
X1524716Y1165357D01*
Y1160945D01*
G01X1522866Y1164134D02*
Y1172038D01*
X1505961Y1188943D01*
Y1217196D01*
X1533830Y1245065D01*
X1538587D01*
G01X1505477Y1265844D02*
Y1270813D01*
G01X1568456Y1311533D02*
X1568283Y1311706D01*
X1543220D01*
X1505477Y1273963D01*
G01X1517517Y130813D02*
Y121473D01*
X1515854Y119810D01*
G01X1545620Y209250D02*
X1526894D01*
G01X1522094D02*
X1526894D01*
G01X1523744Y201250D02*
Y202800D01*
X1518944Y207600D01*
Y209250D01*
G01X1545620Y219250D02*
X1539478D01*
X1537478Y221250D01*
X1526894D01*
G01X1522094D02*
X1526894D01*
G01X1545620Y214250D02*
X1526894D01*
G01D02*
X1525894Y213250D01*
X1522094D01*
G01X1518944Y225250D02*
Y221250D01*
G01Y213250D02*
X1513644D01*
G01X1522094Y244250D02*
Y242679D01*
X1518944Y239529D01*
Y238017D01*
G01Y225250D02*
X1513644D01*
G01X1545620Y224250D02*
X1540639D01*
X1539860Y225029D01*
Y227292D01*
X1537899Y229253D01*
X1536034D01*
X1535146Y228365D01*
X1520343D01*
X1518944Y229764D01*
Y231250D01*
G01Y253250D02*
Y258080D01*
X1517411Y259613D01*
X1513348D01*
G01X1545620Y249250D02*
X1526894D01*
G01X1522094D02*
X1526894D01*
G01X1522094Y253250D02*
Y249250D01*
G01X1513644Y246350D02*
X1516844D01*
X1518944Y244250D01*
G01X1545620D02*
X1526894D01*
G01X1522094D02*
X1526894D01*
G01X1519317Y561977D02*
X1523549D01*
X1525031Y560495D01*
Y484718D01*
X1519528Y479215D01*
X1519120D01*
G01X1542039Y877481D02*
Y872545D01*
X1515677Y846183D01*
Y817000D01*
X1517431Y815246D01*
Y811466D01*
G01X1521685Y887048D02*
X1523523Y886001D01*
G01X1516134Y890237D02*
X1517972Y889190D01*
G01X1523535Y890237D02*
X1525373Y889190D01*
G01X1517984Y893426D02*
X1519822Y892379D01*
G01X1523535Y909370D02*
X1525373Y908324D01*
G01X1521685Y899804D02*
X1523523Y898757D01*
G01X1516134Y902993D02*
X1517972Y901946D01*
G01X1523535Y902993D02*
X1525373Y901946D01*
G01X1517984Y906181D02*
X1519822Y905134D01*
G01X1521685Y906181D02*
X1523523Y905134D01*
G01X1516134Y909370D02*
X1517972Y908324D01*
G01X1517984Y912559D02*
X1519822Y911512D01*
G01X1521685Y918937D02*
X1523523Y917890D01*
G01X1516134Y922126D02*
X1517972Y921079D01*
G01X1523535Y922126D02*
X1525373Y921079D01*
G01X1517984Y925315D02*
X1519822Y924268D01*
G01X1521685Y925315D02*
X1523523Y924268D01*
G01X1516134Y928504D02*
X1517972Y927457D01*
G01X1523535Y928504D02*
X1525373Y927457D01*
G01X1517984Y931693D02*
X1519822Y930646D01*
G01X1521685Y938071D02*
X1523523Y937024D01*
G01X1516134Y941260D02*
X1517972Y940213D01*
G01X1523535Y941260D02*
X1525373Y940213D01*
G01X1517984Y944449D02*
X1519822Y943402D01*
G01X1521685Y944449D02*
X1523523Y943402D01*
G01X1516134Y947638D02*
X1517972Y946591D01*
G01X1523535Y947638D02*
X1525373Y946591D01*
G01X1517984Y950827D02*
X1519822Y949780D01*
G01X1521685Y963583D02*
X1523523Y962536D01*
G01X1516134Y966772D02*
X1517972Y965725D01*
G01X1523535Y966772D02*
X1525373Y965725D01*
G01X1517984Y969961D02*
X1519822Y968914D01*
G01X1521685Y957205D02*
X1523523Y956158D01*
G01X1516134Y960394D02*
X1517972Y959347D01*
G01X1523535Y960394D02*
X1525373Y959347D01*
G01X1517984Y963583D02*
X1519822Y962536D01*
G01X1516134Y985906D02*
X1517972Y984859D01*
G01X1521685Y976339D02*
X1523523Y975292D01*
G01X1516134Y979528D02*
X1517972Y978481D01*
G01X1523535Y979528D02*
X1525373Y978481D01*
G01X1517984Y982717D02*
X1519822Y981670D01*
G01X1517984Y989095D02*
X1519822Y988048D01*
G01X1521685Y995473D02*
X1523523Y994426D01*
G01X1523535Y998662D02*
X1525373Y997615D01*
G01X1516134Y998662D02*
X1517972Y997615D01*
G01X1521685Y989095D02*
X1523523Y988048D01*
G01X1516134Y992284D02*
X1517972Y991237D01*
G01X1517984Y995473D02*
X1519822Y994426D01*
G01X1523535Y992284D02*
X1525373Y991237D01*
G01X1517984Y1001851D02*
X1519822Y1000804D01*
G01X1521685Y1001851D02*
X1523523Y1000804D01*
G01X1523535Y1005040D02*
X1525373Y1003993D01*
G01X1516134Y1005040D02*
X1517972Y1003993D01*
G01X1517984Y1008229D02*
X1519822Y1007182D01*
G01X1516134Y1011418D02*
X1517972Y1010371D01*
G01X1517315Y1027008D02*
X1519153Y1028055D01*
G01X1524716Y1027008D02*
X1526554Y1028055D01*
G01X1519165Y1030197D02*
X1521003Y1031244D01*
G01X1517315Y1033386D02*
X1519153Y1034433D01*
G01X1524716Y1033386D02*
X1526554Y1034433D01*
G01X1522866Y1036575D02*
X1524704Y1037622D01*
G01X1519165Y1036575D02*
X1521003Y1037622D01*
G01X1517315Y1039764D02*
X1519153Y1040811D01*
G01X1524716Y1039764D02*
X1526554Y1040811D01*
G01X1519165Y1042953D02*
X1521003Y1044000D01*
G01X1522866Y1042953D02*
X1524704Y1044000D01*
G01X1522866Y1030197D02*
X1524704Y1031244D01*
G01X1519165Y1049331D02*
X1521003Y1050378D01*
G01X1524716Y1058898D02*
X1526554Y1059945D01*
G01X1517315Y1046142D02*
X1519153Y1047189D01*
G01X1522866Y1049331D02*
X1524704Y1050378D01*
G01X1524716Y1052520D02*
X1526554Y1053567D01*
G01X1522866Y1055709D02*
X1524704Y1056756D01*
G01X1524716Y1046142D02*
X1526554Y1047189D01*
G01X1517315Y1052520D02*
X1519153Y1053567D01*
G01X1524716Y1071654D02*
X1526554Y1072701D01*
G01X1519165Y1074843D02*
X1521003Y1075890D01*
G01X1522866Y1074843D02*
X1524704Y1075890D01*
G01X1519165Y1062087D02*
X1521003Y1063134D01*
G01X1522866Y1062087D02*
X1524704Y1063134D01*
G01X1517315Y1065276D02*
X1519153Y1066323D01*
G01X1517315Y1078032D02*
X1519153Y1079079D01*
G01X1524716Y1078032D02*
X1526554Y1079079D01*
G01X1519165Y1081221D02*
X1521003Y1082268D01*
G01X1522866Y1081221D02*
X1524704Y1082268D01*
G01X1517315Y1084410D02*
X1519153Y1085457D01*
G01X1522866Y1100355D02*
X1524704Y1101402D01*
G01X1517315Y1103544D02*
X1519153Y1104591D01*
G01X1524716Y1090788D02*
X1526554Y1091835D01*
G01X1519165Y1093977D02*
X1521003Y1095024D01*
G01X1522866Y1093977D02*
X1524704Y1095024D01*
G01X1517315Y1097166D02*
X1519153Y1098213D01*
G01X1524716Y1097166D02*
X1526554Y1098213D01*
G01X1519165Y1100355D02*
X1521003Y1101402D01*
G01X1524716Y1109922D02*
X1526554Y1110969D01*
G01X1519165Y1113111D02*
X1521003Y1114158D01*
G01X1522866Y1113111D02*
X1524704Y1114158D01*
G01X1517315Y1116300D02*
X1519153Y1117347D01*
G01X1524716Y1116300D02*
X1526554Y1117347D01*
G01X1519165Y1119489D02*
X1521003Y1120536D01*
G01X1522866Y1119489D02*
X1524704Y1120536D01*
G01X1517315Y1122678D02*
X1519153Y1123725D01*
G01X1524716Y1129056D02*
X1526554Y1130102D01*
G01X1519165Y1132245D02*
X1521003Y1133292D01*
G01X1522866Y1132245D02*
X1524704Y1133292D01*
G01X1517315Y1135433D02*
X1519153Y1136480D01*
G01X1524716Y1135433D02*
X1526554Y1136480D01*
G01X1519165Y1138622D02*
X1521003Y1139669D01*
G01X1522866Y1138622D02*
X1524704Y1139669D01*
G01X1517315Y1141811D02*
X1519153Y1142858D01*
G01X1524716Y1148189D02*
X1526554Y1149236D01*
G01X1551113Y1238088D02*
X1548922D01*
X1542600Y1231766D01*
X1538128D01*
X1531689Y1225327D01*
X1520494D01*
X1513208Y1218041D01*
Y1217483D01*
X1513198Y1217473D01*
Y1188866D01*
X1513208Y1188856D01*
Y1188546D01*
X1528957Y1172797D01*
Y1166524D01*
X1526567Y1164134D01*
G01X1519165Y1151378D02*
X1521003Y1152425D01*
G01X1522866Y1151378D02*
X1524704Y1152425D01*
G01X1524716Y1154567D02*
X1526554Y1155614D01*
G01X1519165Y1157756D02*
X1521003Y1158803D01*
G01X1513614Y1160945D02*
X1515452Y1161992D01*
G01X1537669Y1164134D02*
Y1165977D01*
X1528036Y1175610D01*
Y1175612D01*
X1514318Y1189330D01*
Y1217009D01*
X1521137Y1223828D01*
X1541749D01*
X1548216Y1230295D01*
Y1234606D01*
X1548360Y1234750D01*
G01X1543220Y1160945D02*
Y1166446D01*
X1524425Y1185241D01*
G01X1522875Y1268496D02*
X1533071Y1278692D01*
Y1283102D01*
X1545056Y1295087D01*
X1558236D01*
X1559393Y1293930D01*
X1562472Y1286497D01*
Y1282458D01*
X1569476Y1275454D01*
X1575130D01*
G01X1521346Y1281136D02*
X1546186Y1305976D01*
X1561090D01*
X1574832Y1292234D01*
Y1288958D01*
G01X1518081Y1296288D02*
X1538225Y1316432D01*
X1572476D01*
X1581697Y1307211D01*
Y1302278D01*
G01X1582102Y1292988D02*
X1579049D01*
X1577286Y1294751D01*
Y1297746D01*
X1579032Y1299492D01*
Y1307016D01*
X1571658Y1314390D01*
X1541012D01*
X1513046Y1286424D01*
G01X1540342Y32756D02*
Y30406D01*
X1538342Y28406D01*
G01X1540342Y44370D02*
Y48720D01*
G01X1530884Y62569D02*
X1531375Y62078D01*
Y53584D01*
X1536745Y48214D01*
Y40714D01*
X1539314Y38145D01*
X1542565D01*
X1545066Y40646D01*
Y44370D01*
G01X1533815Y57185D02*
Y53595D01*
X1538265Y49145D01*
Y41479D01*
X1539237Y40507D01*
X1541586D01*
X1542704Y41625D01*
Y44370D01*
G01X1542092Y300816D02*
Y296816D01*
G01X1545556Y292816D02*
X1542092D01*
G01X1538942Y296816D02*
X1536541D01*
X1536538Y296819D01*
G01X1538942Y292816D02*
X1536422D01*
G01X1538939Y288816D02*
Y292813D01*
X1538942Y292816D01*
G01X1545747Y301400D02*
X1545163Y300816D01*
X1542092D01*
G01Y308816D02*
Y304816D01*
G01X1545187Y306854D02*
X1543149Y304816D01*
X1542092D01*
G01X1545234Y547341D02*
Y550390D01*
X1544615Y551009D01*
X1540735D01*
X1540116Y550390D01*
Y547341D01*
G01X1539693Y541188D02*
Y543613D01*
G01D02*
X1540116Y544036D01*
Y547341D01*
G01Y555215D02*
Y558520D01*
X1539693Y558943D01*
G01X1527853Y565839D02*
Y578829D01*
X1530377Y581353D01*
G01X1527853Y565839D02*
X1530743Y562949D01*
X1532730D01*
G01X1537853Y565839D02*
Y578829D01*
X1540377Y581353D01*
G01X1537853Y565839D02*
X1536959Y564945D01*
X1534565D01*
G01X1527853Y562689D02*
Y560264D01*
G01X1537853Y562689D02*
Y561010D01*
X1532824Y555981D01*
G01X1556017Y885367D02*
X1559988Y881396D01*
Y845589D01*
X1581689Y823888D01*
X1584514Y817069D01*
X1616307Y785276D01*
X1619361D01*
G01X1536488Y887048D02*
X1538326Y886001D01*
G01X1530937Y890237D02*
X1532775Y889190D01*
G01X1534638Y890237D02*
X1536476Y889190D01*
G01X1529086Y893426D02*
X1530925Y892379D01*
G01X1530937Y883859D02*
X1532775Y882812D01*
G01X1558567Y899955D02*
X1572031Y886491D01*
Y849747D01*
X1581952Y839826D01*
X1582821D01*
X1584284Y841289D01*
X1584935D01*
X1617523Y808701D01*
X1619361D01*
G01X1557248Y909585D02*
X1578111Y888722D01*
Y860894D01*
X1588227Y850778D01*
Y846402D01*
X1612542Y822087D01*
X1619361D01*
G01X1534638Y909370D02*
X1536476Y908324D01*
G01X1536488Y899804D02*
X1538326Y898757D01*
G01X1530937Y902993D02*
X1532775Y901946D01*
G01X1534638Y902993D02*
X1536476Y901946D01*
G01X1529086Y906181D02*
X1530925Y905134D01*
G01X1536488Y906181D02*
X1538326Y905134D01*
G01X1530937Y909370D02*
X1532775Y908324D01*
G01X1557867Y923878D02*
X1559373D01*
X1589787Y893464D01*
Y870042D01*
X1590710Y869119D01*
Y868469D01*
X1590213Y867972D01*
Y867322D01*
X1590674Y866861D01*
X1591324D01*
X1591821Y867358D01*
X1592471D01*
X1592932Y866897D01*
Y866247D01*
X1592435Y865750D01*
Y865100D01*
X1592896Y864639D01*
X1593546D01*
X1594043Y865136D01*
X1594693D01*
X1595154Y864675D01*
Y864025D01*
X1594657Y863528D01*
Y862878D01*
X1595162Y862373D01*
X1598542D01*
X1615403Y845512D01*
X1619361D01*
G01X1529086Y912559D02*
X1530925Y911512D01*
G01X1536488Y918937D02*
X1538326Y917890D01*
G01X1530937Y922126D02*
X1532775Y921079D01*
G01X1534638Y922126D02*
X1536476Y921079D01*
G01X1529086Y925315D02*
X1530925Y924268D01*
G01X1536488Y925315D02*
X1538326Y924268D01*
G01X1557934Y930005D02*
X1561500D01*
X1595777Y895728D01*
Y876731D01*
X1613610Y858898D01*
X1619361D01*
G01X1530937Y928504D02*
X1532775Y927457D01*
G01X1534638Y928504D02*
X1536476Y927457D01*
G01X1529086Y931693D02*
X1530925Y930646D01*
G01X1536488Y938071D02*
X1538326Y937024D01*
G01X1530937Y941260D02*
X1532775Y940213D01*
G01X1534638Y941260D02*
X1536476Y940213D01*
G01X1557067Y943575D02*
X1568642D01*
X1577213Y935004D01*
Y934354D01*
X1576752Y933893D01*
X1576102D01*
X1574547Y935448D01*
X1573897D01*
X1573436Y934987D01*
Y934337D01*
X1607458Y900315D01*
Y897266D01*
X1618496Y886228D01*
Y883829D01*
X1619361Y882964D01*
G01X1558087Y949448D02*
X1571567D01*
X1599582Y921433D01*
Y916425D01*
X1613278Y902729D01*
Y899978D01*
X1615621Y897635D01*
X1618802Y896317D01*
X1619361Y896086D01*
G01X1529086Y944449D02*
X1530925Y943402D01*
G01X1536488Y944449D02*
X1538326Y943402D01*
G01X1530937Y947638D02*
X1532775Y946591D01*
G01X1534638Y947638D02*
X1536476Y946591D01*
G01X1529086Y950827D02*
X1530925Y949780D01*
G01X1557880Y967668D02*
X1587241D01*
X1590003Y964906D01*
Y962364D01*
X1596046Y956321D01*
Y953849D01*
X1615230Y934665D01*
X1617541Y933707D01*
X1618975Y933113D01*
X1619361Y932953D01*
G01X1557857Y961758D02*
X1575455D01*
X1576125Y961088D01*
X1576775D01*
X1577386Y961699D01*
X1578036D01*
X1578497Y961238D01*
Y960588D01*
X1577886Y959977D01*
Y959327D01*
X1585262Y951951D01*
X1589708D01*
X1618377Y923282D01*
Y920964D01*
X1619547Y919794D01*
G01X1536488Y963583D02*
X1538326Y962536D01*
G01X1530937Y966772D02*
X1532775Y965725D01*
G01X1534638Y966772D02*
X1536476Y965725D01*
G01X1529086Y969961D02*
X1530925Y968914D01*
G01X1536488Y957205D02*
X1538326Y956158D01*
G01X1530937Y960394D02*
X1532775Y959347D01*
G01X1534638Y960394D02*
X1536476Y959347D01*
G01X1529086Y963583D02*
X1530925Y962536D01*
G01X1556811Y981562D02*
X1564411D01*
X1566230Y979743D01*
X1593268D01*
X1593739Y979272D01*
X1594389D01*
X1594741Y979624D01*
X1595391D01*
X1595852Y979163D01*
Y978513D01*
X1595500Y978161D01*
Y977511D01*
X1608115Y964896D01*
X1610625D01*
X1619157Y956364D01*
G01X1530937Y985906D02*
X1532775Y984859D01*
G01X1536488Y976339D02*
X1538326Y975292D01*
G01X1530937Y979528D02*
X1532775Y978481D01*
G01X1534638Y979528D02*
X1536476Y978481D01*
G01X1529086Y982717D02*
X1530925Y981670D01*
G01X1557567Y999475D02*
X1566942D01*
X1572574Y993843D01*
X1605726D01*
X1619538Y980031D01*
G01X1554734Y992805D02*
X1555194Y993265D01*
X1565568D01*
X1569970Y988863D01*
X1601512D01*
X1619371Y971004D01*
X1623496D01*
G01X1529086Y989095D02*
X1530925Y988048D01*
G01X1536488Y995473D02*
X1538326Y994426D01*
G01X1534638Y998662D02*
X1536476Y997615D01*
G01X1530937Y998662D02*
X1532775Y997615D01*
G01X1536488Y989095D02*
X1538326Y988048D01*
G01X1530937Y992284D02*
X1532775Y991237D01*
G01X1529086Y995473D02*
X1530924Y994426D01*
G01X1534638Y992284D02*
X1536476Y991237D01*
G01X1557457Y1006053D02*
X1567948D01*
X1574733Y999268D01*
X1594557D01*
X1597734Y1002445D01*
X1609450D01*
X1618479Y993416D01*
G01X1529086Y1001851D02*
X1530925Y1000804D01*
G01X1536488Y1001851D02*
X1538326Y1000804D01*
G01X1534638Y1005040D02*
X1536476Y1003993D01*
G01X1530937Y1005040D02*
X1532775Y1003993D01*
G01X1529086Y1008229D02*
X1530925Y1007182D01*
G01X1530937Y1011418D02*
X1532775Y1010371D01*
G01X1542039Y1011418D02*
X1543877Y1010371D01*
G01X1532118Y1027008D02*
X1533956Y1028055D01*
G01X1535819Y1027008D02*
X1537657Y1028055D01*
G01X1530268Y1030197D02*
X1532106Y1031244D01*
G01X1532118Y1033386D02*
X1533956Y1034433D01*
G01X1535819Y1033386D02*
X1537657Y1034433D01*
G01X1537669Y1036575D02*
X1539507Y1037622D01*
G01X1530268Y1036575D02*
X1532106Y1037622D01*
G01X1532118Y1039764D02*
X1533956Y1040811D01*
G01X1535819Y1039764D02*
X1537657Y1040811D01*
G01X1530268Y1042953D02*
X1532106Y1044000D01*
G01X1537669Y1042953D02*
X1539507Y1044000D01*
G01X1537669Y1030197D02*
X1539507Y1031244D01*
G01X1530268Y1049331D02*
X1532106Y1050378D01*
G01X1535819Y1058898D02*
X1537657Y1059945D01*
G01X1532118Y1046142D02*
X1533956Y1047189D01*
G01X1537669Y1049331D02*
X1539507Y1050378D01*
G01X1535819Y1052520D02*
X1537657Y1053567D01*
G01X1537669Y1055709D02*
X1539507Y1056756D01*
G01X1535819Y1046142D02*
X1537657Y1047189D01*
G01X1532118Y1052520D02*
X1533956Y1053567D01*
G01X1535819Y1071654D02*
X1537657Y1072701D01*
G01X1530268Y1074843D02*
X1532106Y1075890D01*
G01X1537669Y1074843D02*
X1539507Y1075890D01*
G01X1530268Y1062087D02*
X1532106Y1063134D01*
G01X1537669Y1062087D02*
X1539507Y1063134D01*
G01X1532118Y1065276D02*
X1533956Y1066323D01*
G01X1532118Y1078032D02*
X1533956Y1079079D01*
G01X1535819Y1078032D02*
X1537657Y1079079D01*
G01X1530268Y1081221D02*
X1532106Y1082268D01*
G01X1537669Y1081221D02*
X1539507Y1082268D01*
G01X1532118Y1084410D02*
X1533956Y1085457D01*
G01X1537669Y1100355D02*
X1539507Y1101402D01*
G01X1532118Y1103544D02*
X1533956Y1104591D01*
G01X1535819Y1090788D02*
X1537657Y1091835D01*
G01X1530268Y1093977D02*
X1532106Y1095024D01*
G01X1537669Y1093977D02*
X1539507Y1095024D01*
G01X1532118Y1097166D02*
X1533956Y1098213D01*
G01X1535819Y1097166D02*
X1537657Y1098213D01*
G01X1530268Y1100355D02*
X1532106Y1101402D01*
G01X1535819Y1109922D02*
X1537657Y1110969D01*
G01X1530268Y1113111D02*
X1532106Y1114158D01*
G01X1537669Y1113111D02*
X1539507Y1114158D01*
G01X1532118Y1116300D02*
X1533956Y1117347D01*
G01X1535819Y1116300D02*
X1537657Y1117347D01*
G01X1530268Y1119489D02*
X1532106Y1120536D01*
G01X1537669Y1119489D02*
X1539507Y1120536D01*
G01X1532118Y1122678D02*
X1533956Y1123725D01*
G01X1535819Y1129056D02*
X1537657Y1130102D01*
G01X1530268Y1132245D02*
X1532106Y1133292D01*
G01X1537669Y1132245D02*
X1539507Y1133292D01*
G01X1532118Y1135433D02*
X1533956Y1136480D01*
G01X1535819Y1135433D02*
X1537657Y1136480D01*
G01X1530268Y1138622D02*
X1532106Y1139669D01*
G01X1537669Y1138622D02*
X1539507Y1139669D01*
G01X1532118Y1141811D02*
X1533956Y1142858D01*
G01X1535819Y1148189D02*
X1537657Y1149236D01*
G01X1532118Y1160945D02*
X1533956Y1161992D01*
G01X1541370Y1157756D02*
X1543208Y1158803D01*
G01X1530268Y1151378D02*
X1532106Y1152425D01*
G01X1537669Y1151378D02*
X1539507Y1152425D01*
G01X1532118Y1154567D02*
X1533956Y1155614D01*
G01X1535819Y1160945D02*
X1537657Y1161992D01*
G01X1528417Y1160945D02*
X1530255Y1161992D01*
G01X1538587Y1245065D02*
X1541017D01*
X1543038Y1243044D01*
X1546060D01*
X1549546Y1246530D01*
Y1249126D01*
X1560157Y1259737D01*
Y1262788D01*
G01X1542747Y1253602D02*
X1538832Y1257517D01*
Y1269918D01*
X1547102Y1278188D01*
G01X1545627Y1254068D02*
X1544102Y1255593D01*
X1543523D01*
X1540401Y1258715D01*
Y1267487D01*
X1547102Y1274188D01*
G01X1532335Y1265721D02*
X1543618Y1277004D01*
Y1278704D01*
X1547102Y1282188D01*
G01X1537295Y1274681D02*
X1541394Y1278780D01*
Y1280480D01*
X1547102Y1286188D01*
G01X1529045Y1280128D02*
Y1282646D01*
X1544435Y1298036D01*
X1559278D01*
X1561988Y1295326D01*
X1564863Y1288387D01*
X1566463Y1286787D01*
X1569428D01*
X1570941Y1285274D01*
Y1281568D01*
X1573521Y1278988D01*
X1582102D01*
G01X1534323Y1544505D02*
Y1544506D01*
X1535145Y1545328D01*
X1535623D01*
X1536224Y1545929D01*
X1537341D01*
X1540192Y1543078D01*
X1545013D01*
X1547259Y1540832D01*
X1549164D01*
X1550396Y1539600D01*
G01X1537220Y1548083D02*
X1538875Y1547073D01*
G01X1537220Y1550445D02*
X1538819Y1549336D01*
G01X1550396Y1536100D02*
X1550057D01*
X1544498Y1541659D01*
X1541372D01*
X1538330Y1538617D01*
X1534815D01*
X1533142Y1540290D01*
Y1542459D01*
G01X1537220Y1555169D02*
X1542945Y1560894D01*
X1546360D01*
X1547340Y1561874D01*
X1548279Y1562263D01*
X1551441D01*
X1553751Y1559953D01*
G01X1537220Y1552807D02*
X1538680Y1554267D01*
Y1555267D01*
X1543366Y1559953D01*
X1548751D01*
G01X1537220Y1564618D02*
X1539171D01*
G01X1537220Y1562256D02*
X1537778Y1561698D01*
X1539082D01*
G01X1545396Y1571370D02*
X1544391D01*
X1542637Y1569616D01*
Y1568577D01*
X1540140Y1566080D01*
X1538337D01*
X1538056Y1565799D01*
X1535175D01*
G01Y1563437D02*
X1538028D01*
X1538307Y1563158D01*
X1540188D01*
X1540925Y1563895D01*
Y1565140D01*
X1544055Y1568270D01*
X1545397D01*
G01X1537866Y1573477D02*
X1543020Y1578631D01*
X1544344Y1581828D01*
Y1583582D01*
X1545156Y1584394D01*
Y1586101D01*
X1543907Y1587350D01*
X1543627D01*
G01X1540427Y1591650D02*
X1538287D01*
X1537297Y1590660D01*
Y1578668D01*
X1534323Y1575694D01*
Y1571431D01*
G01X1540427Y1586650D02*
X1539269D01*
X1538717Y1586098D01*
Y1580146D01*
X1539344Y1579519D01*
G01X1533142Y1573477D02*
Y1576895D01*
X1535877Y1579630D01*
Y1585684D01*
X1534911Y1586650D01*
X1534067D01*
G01X1537220Y1569343D02*
X1538873D01*
X1539170Y1569640D01*
G01X1537220Y1566980D02*
X1537780Y1567540D01*
X1539170D01*
G01X1531750Y1598190D02*
X1537994D01*
X1543627Y1592557D01*
Y1587350D01*
G01X1540427Y1591650D02*
Y1593204D01*
X1539111Y1594520D01*
X1536664D01*
G01X1540427Y1589550D02*
Y1586650D01*
G01X1534067D02*
Y1589550D01*
G01D02*
X1530807D01*
G01X1556960Y287478D02*
Y284696D01*
X1556839Y284575D01*
G01X1553689D02*
X1551900Y286364D01*
Y287288D01*
G01X1546789Y284575D02*
Y287116D01*
G01X1549939Y284575D02*
Y285767D01*
X1548772Y286934D01*
Y291916D01*
G01X1553772Y289856D02*
X1555233Y291317D01*
Y294904D01*
G01X1558773Y289875D02*
X1557201Y291447D01*
Y294904D01*
G01X1550705Y299432D02*
X1549108D01*
X1547220Y297544D01*
Y294480D01*
X1545556Y292816D01*
G01X1551900Y287288D02*
X1551397Y287791D01*
Y291207D01*
X1553264Y293074D01*
Y294904D01*
G01X1548772Y291916D02*
Y296365D01*
X1549870Y297463D01*
X1550705D01*
G01Y301400D02*
X1545747D01*
G01X1550705Y303369D02*
X1548672D01*
X1545187Y306854D01*
G01X1559054Y310900D02*
X1557201Y309047D01*
Y305928D01*
G01X1553653Y310980D02*
X1555233Y309400D01*
Y305928D01*
G01X1548197Y311209D02*
X1549990Y309416D01*
X1551768D01*
X1553264Y307920D01*
Y305928D01*
G01X1553154Y479063D02*
Y489988D01*
X1556731Y493565D01*
Y532394D01*
X1565029Y540692D01*
X1575206D01*
X1578690Y544176D01*
X1607250D01*
X1608693Y542733D01*
X1610544D01*
G01X1551779Y530698D02*
Y546194D01*
X1545234Y552739D01*
Y555215D01*
G01X1553241Y883488D02*
X1557308Y879421D01*
Y845052D01*
X1561401Y835169D01*
X1614232Y782338D01*
Y781688D01*
X1613420Y780877D01*
Y780227D01*
X1613881Y779766D01*
X1614531D01*
X1615343Y780577D01*
X1615993D01*
X1617987Y778583D01*
X1619361D01*
G01X1555033Y884367D02*
X1558648Y880752D01*
Y845319D01*
X1561675Y838011D01*
X1567696Y831990D01*
X1568346D01*
X1569554Y833199D01*
X1570204D01*
X1570665Y832738D01*
Y832088D01*
X1569457Y830879D01*
Y830229D01*
X1569918Y829768D01*
X1570568D01*
X1571776Y830977D01*
X1572426D01*
X1572887Y830516D01*
Y829866D01*
X1571679Y828657D01*
Y828007D01*
X1572140Y827546D01*
X1572790D01*
X1573998Y828755D01*
X1574648D01*
X1575109Y828294D01*
Y827644D01*
X1573901Y826435D01*
Y825785D01*
X1574362Y825324D01*
X1575012D01*
X1576220Y826533D01*
X1576870D01*
X1577331Y826072D01*
Y825422D01*
X1576123Y824213D01*
Y823563D01*
X1576584Y823102D01*
X1577234D01*
X1578442Y824311D01*
X1579092D01*
X1579553Y823850D01*
Y823200D01*
X1578345Y821991D01*
Y821341D01*
X1619430Y780256D01*
X1623496D01*
G01X1557267Y886409D02*
X1561328Y882348D01*
Y846146D01*
X1587162Y820312D01*
Y819662D01*
X1585854Y818353D01*
Y817703D01*
X1586315Y817242D01*
X1586965D01*
X1588273Y818551D01*
X1588923D01*
X1589384Y818090D01*
Y817440D01*
X1588076Y816131D01*
Y815481D01*
X1588537Y815020D01*
X1589187D01*
X1590495Y816329D01*
X1591145D01*
X1591606Y815868D01*
Y815218D01*
X1590298Y813909D01*
Y813259D01*
X1590759Y812798D01*
X1591409D01*
X1592717Y814107D01*
X1593367D01*
X1593882Y813592D01*
Y809598D01*
X1616531Y786949D01*
X1623496D01*
G01X1556782Y908155D02*
X1576771Y888166D01*
Y855962D01*
X1577168Y855565D01*
X1577818D01*
X1579074Y856821D01*
X1579724D01*
X1580185Y856360D01*
Y855710D01*
X1578929Y854454D01*
Y853804D01*
X1579390Y853343D01*
X1580040D01*
X1581296Y854599D01*
X1581946D01*
X1582407Y854138D01*
Y853488D01*
X1581151Y852232D01*
Y851582D01*
X1581612Y851121D01*
X1582262D01*
X1583518Y852377D01*
X1584168D01*
X1584629Y851916D01*
Y851266D01*
X1583373Y850010D01*
Y849360D01*
X1583834Y848899D01*
X1584484D01*
X1585740Y850155D01*
X1586390D01*
X1586851Y849694D01*
Y849044D01*
X1585595Y847788D01*
Y847138D01*
X1615666Y817067D01*
X1623496D01*
G01X1558134Y896594D02*
X1568871Y885857D01*
Y849115D01*
X1590574Y827412D01*
X1593964D01*
X1619361Y802015D01*
G01X1558327Y898299D02*
X1570451Y886175D01*
Y849431D01*
X1582244Y837638D01*
X1582894D01*
X1584466Y839210D01*
X1585116D01*
X1592893Y831433D01*
Y830783D01*
X1592432Y830322D01*
X1591782D01*
X1585116Y836988D01*
X1584466D01*
X1584005Y836527D01*
Y835877D01*
X1591130Y828752D01*
X1595576D01*
X1620647Y803681D01*
X1623496D01*
G01X1558527Y901947D02*
X1573611Y886863D01*
Y854509D01*
X1575689Y852431D01*
Y851781D01*
X1574115Y850209D01*
Y849559D01*
X1582061Y841613D01*
X1582711D01*
X1583173Y842075D01*
Y842724D01*
X1576338Y849559D01*
Y850209D01*
X1576800Y850670D01*
X1577450D01*
X1617746Y810374D01*
X1623496D01*
G01X1556306Y906735D02*
X1575431Y887610D01*
Y855406D01*
X1615443Y815394D01*
X1619361D01*
G01X1556819Y911090D02*
X1557639D01*
X1579451Y889278D01*
Y861450D01*
X1591080Y849821D01*
Y849171D01*
X1589567Y847658D01*
Y847008D01*
X1590028Y846547D01*
X1590678D01*
X1592191Y848060D01*
X1592841D01*
X1593302Y847599D01*
Y846949D01*
X1591789Y845436D01*
Y844786D01*
X1592250Y844325D01*
X1592900D01*
X1594413Y845838D01*
X1595063D01*
X1595524Y845377D01*
Y844727D01*
X1594011Y843214D01*
Y842564D01*
X1594472Y842103D01*
X1595122D01*
X1596635Y843616D01*
X1597285D01*
X1597746Y843155D01*
Y842505D01*
X1596233Y840992D01*
Y840292D01*
X1612765Y823760D01*
X1623496D01*
G01X1554347Y920435D02*
X1555474D01*
X1555934Y919975D01*
Y919218D01*
X1556394Y918758D01*
X1557045D01*
X1557505Y919218D01*
Y919975D01*
X1557965Y920435D01*
X1559024D01*
X1587071Y892388D01*
Y866671D01*
X1614923Y838819D01*
X1619211D01*
G01X1557824Y922065D02*
X1559290D01*
X1588411Y892944D01*
Y867227D01*
X1595643Y859995D01*
X1596293D01*
X1597247Y860949D01*
X1597897D01*
X1598358Y860488D01*
Y859838D01*
X1597404Y858884D01*
Y858234D01*
X1597865Y857773D01*
X1598515D01*
X1599469Y858727D01*
X1600119D01*
X1600580Y858266D01*
Y857616D01*
X1599626Y856662D01*
Y856012D01*
X1600087Y855551D01*
X1600737D01*
X1601691Y856505D01*
X1602341D01*
X1602802Y856044D01*
Y855394D01*
X1601848Y854440D01*
Y853790D01*
X1602309Y853329D01*
X1602959D01*
X1603913Y854283D01*
X1604563D01*
X1605024Y853822D01*
Y853172D01*
X1604070Y852218D01*
Y851568D01*
X1604531Y851107D01*
X1605181D01*
X1606135Y852061D01*
X1606785D01*
X1607246Y851600D01*
Y850950D01*
X1606292Y849996D01*
Y849346D01*
X1606753Y848885D01*
X1607403D01*
X1608357Y849839D01*
X1609007D01*
X1609468Y849378D01*
Y848728D01*
X1608514Y847774D01*
Y847124D01*
X1608975Y846663D01*
X1609625D01*
X1610579Y847617D01*
X1611229D01*
X1611690Y847156D01*
Y846506D01*
X1610736Y845552D01*
Y844902D01*
X1611197Y844441D01*
X1611847D01*
X1612801Y845395D01*
X1613451D01*
X1613912Y844934D01*
Y844284D01*
X1612958Y843330D01*
Y842680D01*
X1615146Y840492D01*
X1623496D01*
G01X1557884Y925525D02*
X1559622D01*
X1591297Y893850D01*
Y874872D01*
X1593416Y872753D01*
Y872103D01*
X1591844Y870531D01*
Y869881D01*
X1598012Y863713D01*
X1598662D01*
X1599123Y864174D01*
Y864824D01*
X1594066Y869881D01*
Y870531D01*
X1594527Y870992D01*
X1595177D01*
X1600765Y865404D01*
Y862046D01*
X1614883Y847928D01*
X1615477D01*
X1615897Y848348D01*
Y849137D01*
X1616357Y849597D01*
X1617008D01*
X1617541Y849064D01*
Y847572D01*
X1617928Y847185D01*
X1623496D01*
G01X1557984Y927325D02*
X1560388D01*
X1593097Y894616D01*
Y875619D01*
X1602565Y866151D01*
Y862805D01*
X1613165Y852205D01*
X1619361D01*
G01X1558024Y928665D02*
X1560944D01*
X1594437Y895172D01*
Y876175D01*
X1604928Y865684D01*
Y865034D01*
X1603905Y864012D01*
Y863362D01*
X1604366Y862901D01*
X1605016D01*
X1606039Y863923D01*
X1606689D01*
X1607150Y863462D01*
Y862812D01*
X1606127Y861790D01*
Y861140D01*
X1606588Y860679D01*
X1607238D01*
X1608261Y861701D01*
X1608911D01*
X1609372Y861240D01*
Y860590D01*
X1608349Y859568D01*
Y858918D01*
X1608810Y858457D01*
X1609460D01*
X1610483Y859479D01*
X1611133D01*
X1611594Y859018D01*
Y858368D01*
X1610571Y857346D01*
Y856696D01*
X1611032Y856235D01*
X1611682D01*
X1612705Y857257D01*
X1613355D01*
X1613816Y856796D01*
Y856146D01*
X1612793Y855124D01*
Y854474D01*
X1613254Y854013D01*
X1613904D01*
X1614927Y855035D01*
X1615577D01*
X1616734Y853878D01*
X1623496D01*
G01X1557804Y931345D02*
X1562056D01*
X1597117Y896284D01*
Y879553D01*
X1597916Y878754D01*
Y878104D01*
X1597433Y877621D01*
Y876971D01*
X1597894Y876510D01*
X1598544D01*
X1599027Y876993D01*
X1599677D01*
X1600138Y876532D01*
Y875882D01*
X1599655Y875399D01*
Y874749D01*
X1600116Y874288D01*
X1600766D01*
X1601249Y874771D01*
X1601899D01*
X1602360Y874310D01*
Y873660D01*
X1601877Y873177D01*
Y872527D01*
X1602338Y872066D01*
X1602988D01*
X1603471Y872549D01*
X1604121D01*
X1604582Y872088D01*
Y871438D01*
X1604099Y870955D01*
Y870305D01*
X1604560Y869844D01*
X1605210D01*
X1605693Y870327D01*
X1606343D01*
X1606804Y869866D01*
Y869216D01*
X1606321Y868733D01*
Y868083D01*
X1606782Y867622D01*
X1607432D01*
X1607915Y868105D01*
X1608565D01*
X1609026Y867644D01*
Y866994D01*
X1608543Y866511D01*
Y865861D01*
X1609004Y865400D01*
X1609654D01*
X1610137Y865883D01*
X1610787D01*
X1611248Y865422D01*
Y864772D01*
X1610765Y864289D01*
Y863639D01*
X1611226Y863178D01*
X1611876D01*
X1612359Y863661D01*
X1613009D01*
X1613470Y863200D01*
Y862550D01*
X1612987Y862067D01*
Y861417D01*
X1613448Y860956D01*
X1614098D01*
X1614581Y861439D01*
X1615231D01*
X1616099Y860571D01*
X1623496D01*
G01X1557397Y939265D02*
X1564716D01*
X1604778Y899203D01*
Y892698D01*
X1606333Y891143D01*
Y890493D01*
X1604547Y888709D01*
Y888058D01*
X1605008Y887597D01*
X1605657D01*
X1609158Y891095D01*
X1609808D01*
X1610269Y890634D01*
Y889984D01*
X1609205Y888921D01*
Y888271D01*
X1615816Y881660D01*
Y879172D01*
X1619358Y875630D01*
X1619361D01*
G01X1556224Y942235D02*
X1556792D01*
X1557252Y941775D01*
Y941178D01*
X1557712Y940718D01*
X1558363D01*
X1558823Y941178D01*
Y941775D01*
X1559283Y942235D01*
X1559934D01*
X1560394Y941775D01*
Y941178D01*
X1560854Y940718D01*
X1561505D01*
X1561965Y941178D01*
Y941775D01*
X1562425Y942235D01*
X1563076D01*
X1563536Y941775D01*
Y941178D01*
X1563996Y940718D01*
X1564647D01*
X1565107Y941178D01*
Y941775D01*
X1565567Y942235D01*
X1568086D01*
X1573112Y937209D01*
Y936559D01*
X1572651Y936098D01*
X1572001D01*
X1567649Y940450D01*
X1566999D01*
X1566538Y939989D01*
Y939339D01*
X1606118Y899759D01*
Y896710D01*
X1612463Y890365D01*
Y889715D01*
X1611432Y888685D01*
Y888035D01*
X1611893Y887574D01*
X1612543D01*
X1613574Y888604D01*
X1614224D01*
X1614685Y888143D01*
Y887493D01*
X1613654Y886463D01*
Y885813D01*
X1614115Y885352D01*
X1614765D01*
X1615796Y886382D01*
X1616446D01*
X1617156Y885672D01*
Y881688D01*
X1621541Y877303D01*
X1623496D01*
G01X1557367Y944915D02*
X1569198D01*
X1587365Y926748D01*
Y926098D01*
X1586904Y925637D01*
X1586254D01*
X1578660Y933231D01*
X1578010D01*
X1577549Y932770D01*
Y932120D01*
X1608798Y900871D01*
Y897844D01*
X1619836Y886806D01*
Y884598D01*
X1620438Y883996D01*
X1623496D01*
G01X1557627Y946715D02*
X1569944D01*
X1589165Y927494D01*
Y923050D01*
X1610598Y901617D01*
Y898693D01*
X1619615Y889676D01*
G01X1557717Y948065D02*
X1570490D01*
X1598242Y920313D01*
Y919663D01*
X1597781Y919202D01*
X1597131D01*
X1591616Y924717D01*
X1590966D01*
X1590505Y924256D01*
Y923606D01*
X1611938Y902173D01*
Y899377D01*
X1618237Y893078D01*
X1619225D01*
X1621614Y890689D01*
X1623496D01*
G01X1558027Y950838D02*
X1572073D01*
X1592288Y930623D01*
X1593157D01*
X1594395Y931862D01*
X1595141D01*
X1595669Y931334D01*
Y930588D01*
X1594431Y929349D01*
Y928603D01*
X1594959Y928075D01*
X1595705D01*
X1596943Y929314D01*
X1597689D01*
X1598217Y928786D01*
Y928040D01*
X1596979Y926801D01*
Y926055D01*
X1597507Y925527D01*
X1598253D01*
X1599491Y926766D01*
X1600237D01*
X1600765Y926238D01*
Y925492D01*
X1599527Y924253D01*
Y923507D01*
X1600922Y922112D01*
Y916983D01*
X1614618Y903287D01*
Y900738D01*
X1616729Y898627D01*
X1618802Y897768D01*
X1619735Y897382D01*
X1623496D01*
G01X1556904Y964965D02*
X1581137D01*
X1617931Y928171D01*
G01X1556897Y966318D02*
X1581680D01*
X1582821Y965177D01*
X1583471D01*
X1584624Y966328D01*
X1585275D01*
X1585736Y965867D01*
Y965219D01*
X1584582Y964065D01*
Y963416D01*
X1585043Y962955D01*
X1585693D01*
X1587552Y964811D01*
X1588202D01*
X1588663Y964350D01*
Y963702D01*
X1586804Y961843D01*
Y961194D01*
X1587265Y960733D01*
X1587915D01*
X1588483Y961300D01*
X1589133D01*
X1589594Y960839D01*
Y960189D01*
X1589026Y959621D01*
Y958972D01*
X1589487Y958511D01*
X1590137D01*
X1590705Y959078D01*
X1591355D01*
X1591816Y958617D01*
Y957967D01*
X1591248Y957399D01*
Y956750D01*
X1591709Y956289D01*
X1592359D01*
X1592927Y956856D01*
X1593577D01*
X1594038Y956395D01*
Y955745D01*
X1593470Y955177D01*
Y954528D01*
X1617480Y930518D01*
X1618130D01*
X1618654Y931042D01*
X1619304D01*
X1619765Y930581D01*
Y929931D01*
X1619241Y929407D01*
Y928757D01*
X1620498Y927500D01*
X1623496D01*
G01X1557267Y969028D02*
X1589679D01*
X1592915Y965792D01*
Y965142D01*
X1591343Y963570D01*
Y962920D01*
X1594686Y959577D01*
X1595336D01*
X1595797Y960038D01*
Y960688D01*
X1593565Y962920D01*
Y963570D01*
X1594026Y964031D01*
X1594676D01*
X1597386Y961321D01*
Y954406D01*
X1615990Y935802D01*
X1617541Y935159D01*
X1618975Y934565D01*
X1619874Y934193D01*
X1623496D01*
G01X1558327Y959025D02*
X1574396D01*
X1593777Y939644D01*
X1598221D01*
X1612355Y925510D01*
Y924860D01*
X1611965Y924470D01*
Y923820D01*
X1612426Y923359D01*
X1613076D01*
X1613466Y923749D01*
X1614116D01*
X1615697Y922168D01*
Y916213D01*
X1615824Y916081D01*
X1615809Y915336D01*
X1614900Y914465D01*
X1614885Y913720D01*
X1615403Y913180D01*
X1616149Y913165D01*
X1617057Y914036D01*
X1617802Y914021D01*
X1618190Y913616D01*
X1618189Y913613D01*
X1619361Y912441D01*
G01X1558137Y960388D02*
X1574929D01*
X1594333Y940984D01*
X1594983D01*
X1595444Y941445D01*
Y942095D01*
X1588089Y949450D01*
Y950100D01*
X1588550Y950561D01*
X1589200D01*
X1617037Y922724D01*
Y917447D01*
X1620370Y914114D01*
X1623496D01*
G01X1557700Y963105D02*
X1580451D01*
X1581383Y962173D01*
Y961523D01*
X1579809Y959951D01*
Y959301D01*
X1585819Y953291D01*
X1586469D01*
X1586931Y953753D01*
Y954402D01*
X1582032Y959301D01*
Y959951D01*
X1582494Y960412D01*
X1583144D01*
X1619717Y923839D01*
Y921520D01*
X1620430Y920807D01*
X1623496D01*
G01X1553934Y985165D02*
X1562684Y985162D01*
X1566045D01*
X1567684Y983523D01*
X1597570D01*
X1618455Y962638D01*
X1619361D01*
G01X1556585Y976600D02*
X1557290D01*
X1557750Y977060D01*
Y978371D01*
X1558210Y978831D01*
X1558861D01*
X1559321Y978371D01*
Y977060D01*
X1559781Y976600D01*
X1560432D01*
X1560892Y977060D01*
Y978371D01*
X1561352Y978831D01*
X1562003D01*
X1562463Y978371D01*
Y977060D01*
X1562923Y976600D01*
X1592619D01*
X1607766Y961453D01*
Y959815D01*
X1618329Y949252D01*
X1619361D01*
G01X1557161Y980222D02*
X1563855D01*
X1565674Y978403D01*
X1592712D01*
X1608192Y962923D01*
X1608786D01*
X1609419Y963556D01*
X1610069D01*
X1610530Y963095D01*
Y962445D01*
X1609106Y961021D01*
Y960371D01*
X1609567Y959910D01*
X1610217D01*
X1611641Y961334D01*
X1612291D01*
X1612752Y960873D01*
Y960223D01*
X1611328Y958799D01*
Y958149D01*
X1611789Y957688D01*
X1612439D01*
X1613863Y959112D01*
X1614513D01*
X1614974Y958651D01*
Y958001D01*
X1613550Y956577D01*
Y955927D01*
X1614011Y955466D01*
X1614661D01*
X1616085Y956890D01*
X1616735D01*
X1617196Y956429D01*
Y955779D01*
X1615772Y954355D01*
Y953705D01*
X1616233Y953244D01*
X1616883D01*
X1618307Y954668D01*
X1618957D01*
X1619418Y954207D01*
Y953557D01*
X1617994Y952133D01*
Y951483D01*
X1618552Y950925D01*
X1623496D01*
G01X1556907Y982902D02*
X1564967D01*
X1566786Y981083D01*
X1596810D01*
X1597969Y979925D01*
Y979275D01*
X1597210Y978516D01*
Y977866D01*
X1597671Y977405D01*
X1598321D01*
X1599080Y978164D01*
X1599730D01*
X1600191Y977703D01*
Y977053D01*
X1599432Y976294D01*
Y975644D01*
X1599893Y975183D01*
X1600543D01*
X1601302Y975942D01*
X1601952D01*
X1602413Y975481D01*
Y974831D01*
X1601654Y974072D01*
Y973422D01*
X1602115Y972961D01*
X1602765D01*
X1603524Y973720D01*
X1604174D01*
X1604635Y973259D01*
Y972609D01*
X1603876Y971850D01*
Y971200D01*
X1604337Y970739D01*
X1604987D01*
X1605746Y971498D01*
X1606396D01*
X1606857Y971037D01*
Y970387D01*
X1606098Y969628D01*
Y968978D01*
X1606559Y968517D01*
X1607209D01*
X1607968Y969276D01*
X1608618D01*
X1609079Y968815D01*
Y968165D01*
X1608320Y967406D01*
Y966756D01*
X1608781Y966295D01*
X1609431D01*
X1609979Y966843D01*
X1610574D01*
X1617464Y959954D01*
X1618113D01*
X1618466Y960307D01*
X1619116D01*
X1619577Y959846D01*
Y959196D01*
X1619225Y958843D01*
Y958193D01*
X1619800Y957618D01*
X1623496D01*
G01X1549441Y985906D02*
X1550820Y987285D01*
X1565818D01*
X1568240Y984863D01*
X1598127D01*
X1618679Y964311D01*
X1623496D01*
G01X1557497Y996795D02*
X1565830D01*
X1571462Y991163D01*
X1601465D01*
X1616604Y976024D01*
X1619361D01*
G01X1557584Y998135D02*
X1566386D01*
X1572018Y992503D01*
X1604162D01*
X1604963Y991702D01*
Y991052D01*
X1604543Y990632D01*
Y989982D01*
X1605004Y989521D01*
X1605654D01*
X1606074Y989941D01*
X1606724D01*
X1607185Y989480D01*
Y988830D01*
X1606765Y988410D01*
Y987760D01*
X1607226Y987299D01*
X1607876D01*
X1608296Y987719D01*
X1608946D01*
X1609407Y987258D01*
Y986608D01*
X1608987Y986188D01*
Y985538D01*
X1609448Y985077D01*
X1610098D01*
X1610518Y985497D01*
X1611168D01*
X1611629Y985036D01*
Y984386D01*
X1611209Y983966D01*
Y983316D01*
X1611670Y982855D01*
X1612320D01*
X1612740Y983275D01*
X1613390D01*
X1613851Y982814D01*
Y982164D01*
X1613431Y981744D01*
Y981094D01*
X1613892Y980633D01*
X1614542D01*
X1614962Y981053D01*
X1615612D01*
X1616073Y980592D01*
Y979942D01*
X1615653Y979522D01*
Y978872D01*
X1616114Y978411D01*
X1616764D01*
X1617184Y978831D01*
X1617834D01*
X1618968Y977697D01*
X1623496D01*
G01X1556314Y990585D02*
X1565716D01*
X1569178Y987123D01*
X1599066D01*
X1619524Y966665D01*
G01X1557497Y1000815D02*
X1567498D01*
X1573130Y995183D01*
X1606282D01*
X1608082Y993383D01*
X1608732D01*
X1609567Y994218D01*
X1610217D01*
X1610678Y993757D01*
Y993107D01*
X1609843Y992272D01*
Y991622D01*
X1610304Y991161D01*
X1610954D01*
X1611789Y991996D01*
X1612439D01*
X1612900Y991535D01*
Y990885D01*
X1612065Y990050D01*
Y989400D01*
X1612526Y988939D01*
X1613176D01*
X1614011Y989774D01*
X1614661D01*
X1615122Y989313D01*
Y988663D01*
X1614287Y987828D01*
Y987178D01*
X1614748Y986717D01*
X1615398D01*
X1616233Y987552D01*
X1616883D01*
X1617344Y987091D01*
Y986441D01*
X1616509Y985606D01*
Y984956D01*
X1617075Y984390D01*
X1623496D01*
G01X1557527Y1003373D02*
X1566836D01*
X1573686Y996523D01*
X1609809D01*
X1616922Y989410D01*
X1619361D01*
G01X1557527Y1004713D02*
X1567392D01*
X1574227Y997878D01*
X1596877D01*
X1597337Y998338D01*
Y999968D01*
X1597797Y1000428D01*
X1598448D01*
X1598908Y999968D01*
Y998338D01*
X1599368Y997878D01*
X1600019D01*
X1600479Y998338D01*
Y999968D01*
X1600939Y1000428D01*
X1601590D01*
X1602050Y999968D01*
Y998338D01*
X1602510Y997878D01*
X1603161D01*
X1603621Y998338D01*
Y999968D01*
X1604081Y1000428D01*
X1604732D01*
X1605192Y999968D01*
Y998338D01*
X1605652Y997878D01*
X1606303D01*
X1606763Y998338D01*
Y999968D01*
X1607223Y1000428D01*
X1607874D01*
X1608334Y999968D01*
Y998338D01*
X1608794Y997878D01*
X1611188D01*
X1617983Y991083D01*
X1623496D01*
G01X1557267Y1007393D02*
X1568504D01*
X1575069Y1000828D01*
X1589848D01*
X1597132Y1003845D01*
X1610330D01*
X1618072Y996103D01*
X1619361D01*
G01X1543220Y1027008D02*
X1545058Y1028055D01*
G01X1558361Y1030857D02*
X1568327D01*
X1574972Y1037502D01*
X1590894D01*
X1602186Y1026210D01*
X1636000D01*
X1637684Y1027894D01*
X1639638D01*
G01X1558071Y1032197D02*
X1567771D01*
X1574416Y1038842D01*
X1591450D01*
X1599052Y1031240D01*
X1601764D01*
X1602224Y1030780D01*
Y1029288D01*
X1602684Y1028828D01*
X1603335D01*
X1603795Y1029288D01*
Y1030780D01*
X1604255Y1031240D01*
X1604906D01*
X1605366Y1030780D01*
Y1029288D01*
X1605826Y1028828D01*
X1606477D01*
X1606937Y1029288D01*
Y1030780D01*
X1607397Y1031240D01*
X1623496D01*
G01X1557727Y1033537D02*
X1567214D01*
X1573859Y1040182D01*
X1592006D01*
X1599274Y1032914D01*
X1619361D01*
G01X1557782Y1034877D02*
X1566657D01*
X1573302Y1041522D01*
X1592563D01*
X1596152Y1037933D01*
Y1037932D01*
X1599830Y1034254D01*
X1601249D01*
X1601709Y1034714D01*
Y1035451D01*
X1602169Y1035911D01*
X1602820D01*
X1603280Y1035451D01*
Y1034714D01*
X1603740Y1034254D01*
X1604391D01*
X1604851Y1034714D01*
Y1035451D01*
X1605311Y1035911D01*
X1605962D01*
X1606422Y1035451D01*
Y1034714D01*
X1606882Y1034254D01*
X1607533D01*
X1607993Y1034714D01*
Y1035451D01*
X1608453Y1035911D01*
X1609104D01*
X1609564Y1035451D01*
Y1034714D01*
X1610024Y1034254D01*
X1610675D01*
X1611135Y1034714D01*
Y1035451D01*
X1611595Y1035911D01*
X1612246D01*
X1612706Y1035451D01*
Y1034714D01*
X1613166Y1034254D01*
X1616026D01*
X1619705Y1037933D01*
X1623496D01*
G01X1558595Y1037420D02*
X1567224D01*
X1572666Y1042862D01*
X1593120D01*
X1598731Y1037251D01*
X1617005D01*
X1619361Y1039607D01*
G01X1558319Y1038760D02*
X1566668D01*
X1572110Y1044202D01*
X1593676D01*
X1599287Y1038591D01*
X1600322D01*
X1600782Y1039051D01*
Y1039855D01*
X1601242Y1040315D01*
X1601893D01*
X1602353Y1039855D01*
Y1039051D01*
X1602813Y1038591D01*
X1603464D01*
X1603924Y1039051D01*
Y1039855D01*
X1604384Y1040315D01*
X1605035D01*
X1605495Y1039855D01*
Y1039051D01*
X1605955Y1038591D01*
X1606606D01*
X1607066Y1039051D01*
Y1039855D01*
X1607526Y1040315D01*
X1608177D01*
X1608637Y1039855D01*
Y1039051D01*
X1609097Y1038591D01*
X1613768D01*
X1619803Y1044626D01*
X1623496D01*
G01X1558474Y1040100D02*
X1566111D01*
X1571553Y1045542D01*
X1594232D01*
X1598119Y1041655D01*
X1613111D01*
X1617756Y1046300D01*
X1619361D01*
G01X1558279Y1045138D02*
X1565460D01*
X1569884Y1049562D01*
X1595902D01*
X1599044Y1046420D01*
X1612188D01*
X1618761Y1052993D01*
X1619361D01*
G01X1558496Y1043798D02*
X1566016D01*
X1570440Y1048222D01*
X1581543D01*
X1582003Y1047762D01*
Y1047348D01*
X1582463Y1046888D01*
X1583114D01*
X1583574Y1047348D01*
Y1047762D01*
X1584034Y1048222D01*
X1584685D01*
X1585145Y1047762D01*
Y1047348D01*
X1585605Y1046888D01*
X1586256D01*
X1586716Y1047348D01*
Y1047762D01*
X1587176Y1048222D01*
X1587827D01*
X1588287Y1047762D01*
Y1047348D01*
X1588747Y1046888D01*
X1589398D01*
X1589858Y1047348D01*
Y1047762D01*
X1590318Y1048222D01*
X1590969D01*
X1591429Y1047762D01*
Y1047348D01*
X1591889Y1046888D01*
X1592540D01*
X1593000Y1047348D01*
Y1047762D01*
X1593460Y1048222D01*
X1595345D01*
X1598487Y1045080D01*
X1599892D01*
X1600352Y1044620D01*
Y1043618D01*
X1600812Y1043158D01*
X1601463D01*
X1601923Y1043618D01*
Y1044620D01*
X1602383Y1045080D01*
X1603034D01*
X1603494Y1044620D01*
Y1043618D01*
X1603954Y1043158D01*
X1604605D01*
X1605065Y1043618D01*
Y1044620D01*
X1605525Y1045080D01*
X1606176D01*
X1606636Y1044620D01*
Y1043618D01*
X1607096Y1043158D01*
X1607747D01*
X1608207Y1043618D01*
Y1044620D01*
X1608667Y1045080D01*
X1609318D01*
X1609778Y1044620D01*
Y1043618D01*
X1610238Y1043158D01*
X1610889D01*
X1611349Y1043618D01*
Y1044620D01*
X1611809Y1045080D01*
X1612744D01*
X1618983Y1051319D01*
X1623496D01*
G01X1557618Y1050174D02*
X1564807D01*
X1568215Y1053582D01*
X1613402D01*
X1619361Y1059541D01*
G01X1557973Y1058522D02*
X1559313Y1057182D01*
X1560647D01*
X1561107Y1057642D01*
Y1058438D01*
X1561567Y1058898D01*
X1562218D01*
X1562678Y1058438D01*
Y1057642D01*
X1563138Y1057182D01*
X1563789D01*
X1564249Y1057642D01*
Y1058438D01*
X1564709Y1058898D01*
X1565360D01*
X1565820Y1058438D01*
Y1057642D01*
X1566280Y1057182D01*
X1566931D01*
X1567391Y1057642D01*
Y1058438D01*
X1567851Y1058898D01*
X1568502D01*
X1568962Y1058438D01*
Y1057642D01*
X1569422Y1057182D01*
X1570073D01*
X1570533Y1057642D01*
Y1058438D01*
X1570993Y1058898D01*
X1571644D01*
X1572104Y1058438D01*
Y1057642D01*
X1572564Y1057182D01*
X1604387D01*
X1619637Y1072432D01*
G01X1557824Y1047818D02*
X1564347D01*
X1568771Y1052242D01*
X1600735D01*
X1601195Y1051782D01*
Y1049560D01*
X1601655Y1049100D01*
X1610727D01*
X1611187Y1049560D01*
Y1050211D01*
X1610727Y1050671D01*
X1603226D01*
X1602766Y1051131D01*
Y1051782D01*
X1603226Y1052242D01*
X1613958D01*
X1619728Y1058012D01*
X1623496D01*
G01X1557866Y1052854D02*
X1563695D01*
X1565763Y1054922D01*
X1608819D01*
X1619636Y1065739D01*
G01X1558155Y1071366D02*
X1594164D01*
X1615948Y1093150D01*
X1619361D01*
G01X1558314Y1074046D02*
X1590918D01*
X1616715Y1099843D01*
X1619361D01*
G01X1557932Y1072706D02*
X1593607D01*
X1594469Y1073568D01*
Y1074218D01*
X1594053Y1074634D01*
Y1075284D01*
X1594514Y1075745D01*
X1595164D01*
X1595580Y1075329D01*
X1596230D01*
X1596691Y1075790D01*
Y1076440D01*
X1596275Y1076856D01*
Y1077506D01*
X1596736Y1077967D01*
X1597386D01*
X1597802Y1077551D01*
X1598452D01*
X1598913Y1078012D01*
Y1078662D01*
X1598497Y1079078D01*
Y1079728D01*
X1598958Y1080189D01*
X1599608D01*
X1600024Y1079773D01*
X1600674D01*
X1601135Y1080234D01*
Y1080884D01*
X1600719Y1081300D01*
Y1081950D01*
X1601180Y1082411D01*
X1601830D01*
X1602246Y1081995D01*
X1602896D01*
X1603357Y1082456D01*
Y1083106D01*
X1602941Y1083522D01*
Y1084172D01*
X1603402Y1084633D01*
X1604052D01*
X1604468Y1084217D01*
X1605118D01*
X1605579Y1084678D01*
Y1085328D01*
X1605163Y1085744D01*
Y1086394D01*
X1605624Y1086855D01*
X1606274D01*
X1606690Y1086439D01*
X1607340D01*
X1607801Y1086900D01*
Y1087550D01*
X1607385Y1087966D01*
Y1088616D01*
X1607846Y1089077D01*
X1608496D01*
X1608912Y1088661D01*
X1609562D01*
X1610023Y1089122D01*
Y1089772D01*
X1609607Y1090188D01*
Y1090838D01*
X1610068Y1091299D01*
X1610718D01*
X1611134Y1090883D01*
X1611784D01*
X1612245Y1091344D01*
Y1091994D01*
X1611829Y1092410D01*
Y1093060D01*
X1612290Y1093521D01*
X1612940D01*
X1613356Y1093105D01*
X1614006D01*
X1614467Y1093566D01*
Y1094216D01*
X1614051Y1094632D01*
Y1095282D01*
X1614512Y1095743D01*
X1615162D01*
X1615578Y1095327D01*
X1616228D01*
X1616689Y1095788D01*
Y1096438D01*
X1616273Y1096854D01*
Y1097504D01*
X1616734Y1097965D01*
X1617384D01*
X1617800Y1097549D01*
X1618450D01*
X1619071Y1098170D01*
X1623496D01*
G01X1557524Y1062000D02*
X1605411D01*
X1619361Y1075950D01*
G01X1558673Y1060448D02*
X1573416D01*
X1573876Y1059988D01*
Y1059068D01*
X1574336Y1058608D01*
X1574987D01*
X1575447Y1059068D01*
Y1059988D01*
X1575907Y1060448D01*
X1576558D01*
X1577018Y1059988D01*
Y1059068D01*
X1577478Y1058608D01*
X1578129D01*
X1578589Y1059068D01*
Y1059988D01*
X1579049Y1060448D01*
X1579700D01*
X1580160Y1059988D01*
Y1059068D01*
X1580620Y1058608D01*
X1581271D01*
X1581731Y1059068D01*
Y1059988D01*
X1582191Y1060448D01*
X1582842D01*
X1583302Y1059988D01*
Y1059068D01*
X1583762Y1058608D01*
X1584413D01*
X1584873Y1059068D01*
Y1059988D01*
X1585333Y1060448D01*
X1585984D01*
X1586444Y1059988D01*
Y1059068D01*
X1586904Y1058608D01*
X1587555D01*
X1588015Y1059068D01*
Y1059988D01*
X1588475Y1060448D01*
X1589126D01*
X1589586Y1059988D01*
Y1059068D01*
X1590046Y1058608D01*
X1590697D01*
X1591157Y1059068D01*
Y1059988D01*
X1591617Y1060448D01*
X1592268D01*
X1592728Y1059988D01*
Y1059068D01*
X1593188Y1058608D01*
X1593839D01*
X1594299Y1059068D01*
Y1059988D01*
X1594759Y1060448D01*
X1595410D01*
X1595870Y1059988D01*
Y1059068D01*
X1596330Y1058608D01*
X1596981D01*
X1597441Y1059068D01*
Y1059988D01*
X1597901Y1060448D01*
X1598552D01*
X1599012Y1059988D01*
Y1059068D01*
X1599472Y1058608D01*
X1600123D01*
X1600583Y1059068D01*
Y1059988D01*
X1601043Y1060448D01*
X1601694D01*
X1602154Y1059988D01*
Y1059068D01*
X1602614Y1058608D01*
X1603265D01*
X1603725Y1059068D01*
Y1059988D01*
X1604185Y1060448D01*
X1605757D01*
X1619613Y1074304D01*
Y1074305D01*
X1620052Y1074744D01*
X1623496D01*
G01X1558227Y1063918D02*
X1605432D01*
X1618695Y1077181D01*
Y1077830D01*
X1618233Y1078292D01*
X1617583D01*
X1613133Y1073842D01*
X1612483D01*
X1612021Y1074304D01*
Y1074953D01*
X1618505Y1081437D01*
X1623496D01*
G01X1558382Y1075386D02*
X1559546D01*
X1560388Y1076228D01*
X1561117D01*
X1561959Y1075386D01*
X1562688D01*
X1563530Y1076228D01*
X1564259D01*
X1565101Y1075386D01*
X1565830D01*
X1566672Y1076228D01*
X1567401D01*
X1568243Y1075386D01*
X1568972D01*
X1569814Y1076228D01*
X1570543D01*
X1571385Y1075386D01*
X1572114D01*
X1572956Y1076228D01*
X1573685D01*
X1574527Y1075386D01*
X1575256D01*
X1576098Y1076228D01*
X1576827D01*
X1577669Y1075386D01*
X1578398D01*
X1579240Y1076228D01*
X1579969D01*
X1580811Y1075386D01*
X1581540D01*
X1582382Y1076228D01*
X1583111D01*
X1583953Y1075386D01*
X1584682D01*
X1585524Y1076228D01*
X1586253D01*
X1587095Y1075386D01*
X1590362D01*
X1591174Y1076198D01*
Y1076848D01*
X1589937Y1078086D01*
Y1078736D01*
X1590398Y1079197D01*
X1591048D01*
X1592285Y1077959D01*
X1592935D01*
X1593396Y1078420D01*
Y1079070D01*
X1592159Y1080308D01*
Y1080958D01*
X1592620Y1081419D01*
X1593270D01*
X1594507Y1080181D01*
X1595157D01*
X1619838Y1104862D01*
X1623496D01*
G01X1558515Y1078089D02*
X1586744D01*
X1591874Y1083219D01*
X1595648D01*
X1618187Y1105758D01*
Y1108608D01*
X1619361Y1109782D01*
G01X1557576Y1082310D02*
X1574831D01*
X1575291Y1081850D01*
Y1081327D01*
X1575751Y1080867D01*
X1576402D01*
X1576862Y1081327D01*
Y1081850D01*
X1577322Y1082310D01*
X1587172D01*
X1601193Y1096331D01*
X1604883D01*
X1615449Y1106897D01*
Y1110587D01*
X1618091Y1113229D01*
X1619361D01*
G01X1558380Y1079429D02*
X1559551D01*
X1560432Y1080310D01*
X1561122D01*
X1562003Y1079429D01*
X1562693D01*
X1563574Y1080310D01*
X1564264D01*
X1565145Y1079429D01*
X1565835D01*
X1566716Y1080310D01*
X1567406D01*
X1568287Y1079429D01*
X1568977D01*
X1569858Y1080310D01*
X1570548D01*
X1571429Y1079429D01*
X1572119D01*
X1573000Y1080310D01*
X1573690D01*
X1574571Y1079429D01*
X1586188D01*
X1592862Y1086103D01*
X1593512D01*
X1594707Y1084908D01*
X1595357D01*
X1595818Y1085369D01*
Y1086019D01*
X1594623Y1087214D01*
Y1087864D01*
X1595084Y1088325D01*
X1595734D01*
X1596929Y1087130D01*
X1597579D01*
X1598040Y1087591D01*
Y1088241D01*
X1596845Y1089436D01*
Y1090086D01*
X1597306Y1090547D01*
X1597956D01*
X1599151Y1089352D01*
X1599801D01*
X1600262Y1089813D01*
Y1090463D01*
X1599067Y1091658D01*
Y1092308D01*
X1599528Y1092769D01*
X1600178D01*
X1601373Y1091574D01*
X1602023D01*
X1602484Y1092035D01*
Y1092685D01*
X1601289Y1093880D01*
Y1094530D01*
X1601750Y1094991D01*
X1602400D01*
X1603595Y1093796D01*
X1604245D01*
X1616847Y1106398D01*
Y1110088D01*
X1618314Y1111555D01*
X1623496D01*
G01X1558583Y1083650D02*
X1586616D01*
X1602271Y1099305D01*
X1602921D01*
X1604011Y1098214D01*
X1604661D01*
X1605122Y1098675D01*
Y1099325D01*
X1604032Y1100416D01*
Y1101066D01*
X1604493Y1101527D01*
X1605143D01*
X1606233Y1100436D01*
X1606883D01*
X1607344Y1100897D01*
Y1101547D01*
X1606254Y1102638D01*
Y1103288D01*
X1606715Y1103749D01*
X1607365D01*
X1608455Y1102658D01*
X1609105D01*
X1609566Y1103119D01*
Y1103769D01*
X1608476Y1104860D01*
Y1105510D01*
X1608937Y1105971D01*
X1609587D01*
X1610677Y1104880D01*
X1611327D01*
X1611788Y1105341D01*
Y1105991D01*
X1610698Y1107082D01*
Y1107732D01*
X1611159Y1108193D01*
X1611809D01*
X1612899Y1107102D01*
X1613549D01*
X1614010Y1107563D01*
Y1108213D01*
X1612920Y1109304D01*
Y1109954D01*
X1621214Y1118248D01*
X1623496D01*
G01X1558617Y1098842D02*
X1573951D01*
X1574585Y1099476D01*
Y1100126D01*
X1574221Y1100490D01*
Y1101140D01*
X1574682Y1101601D01*
X1575332D01*
X1576710Y1100223D01*
X1577360D01*
X1577821Y1100684D01*
Y1101334D01*
X1576443Y1102712D01*
Y1103362D01*
X1576904Y1103823D01*
X1577554D01*
X1578932Y1102445D01*
X1579582D01*
X1580043Y1102906D01*
Y1103556D01*
X1578665Y1104934D01*
Y1105584D01*
X1579126Y1106045D01*
X1579776D01*
X1581154Y1104667D01*
X1581804D01*
X1582265Y1105128D01*
Y1105778D01*
X1580887Y1107156D01*
Y1107806D01*
X1581348Y1108267D01*
X1581998D01*
X1583376Y1106889D01*
X1584026D01*
X1584487Y1107350D01*
Y1108000D01*
X1583109Y1109378D01*
Y1110028D01*
X1583570Y1110489D01*
X1584220D01*
X1585598Y1109111D01*
X1586248D01*
X1586709Y1109572D01*
Y1110222D01*
X1585331Y1111600D01*
Y1112250D01*
X1585792Y1112711D01*
X1586442D01*
X1586806Y1112347D01*
X1587456D01*
X1589929Y1114820D01*
Y1115414D01*
X1589738Y1115605D01*
Y1116199D01*
X1590255Y1116716D01*
X1590849D01*
X1591040Y1116525D01*
X1591634D01*
X1592151Y1117042D01*
Y1117636D01*
X1591960Y1117827D01*
Y1118421D01*
X1592477Y1118938D01*
X1593071D01*
X1593262Y1118747D01*
X1593856D01*
X1594373Y1119264D01*
Y1119858D01*
X1594182Y1120049D01*
Y1120643D01*
X1594699Y1121160D01*
X1595293D01*
X1595484Y1120969D01*
X1596078D01*
X1596595Y1121486D01*
Y1122080D01*
X1596404Y1122271D01*
Y1122865D01*
X1596921Y1123382D01*
X1597515D01*
X1597706Y1123191D01*
X1598300D01*
X1617722Y1142613D01*
Y1146037D01*
X1620051Y1148366D01*
X1623496D01*
G01X1558231Y1101522D02*
X1570810D01*
X1597058Y1127770D01*
X1597708D01*
X1598028Y1127450D01*
X1598678D01*
X1599139Y1127911D01*
Y1128561D01*
X1598819Y1128881D01*
Y1129531D01*
X1599280Y1129992D01*
X1599930D01*
X1600250Y1129672D01*
X1600900D01*
X1601361Y1130133D01*
Y1130783D01*
X1601041Y1131103D01*
Y1131753D01*
X1601502Y1132214D01*
X1602152D01*
X1602472Y1131894D01*
X1603122D01*
X1603583Y1132355D01*
Y1133005D01*
X1603263Y1133325D01*
Y1133975D01*
X1603724Y1134436D01*
X1604374D01*
X1604694Y1134116D01*
X1605344D01*
X1605805Y1134577D01*
Y1135227D01*
X1605485Y1135547D01*
Y1136197D01*
X1605946Y1136658D01*
X1606596D01*
X1606916Y1136338D01*
X1607566D01*
X1608027Y1136799D01*
Y1137449D01*
X1607707Y1137769D01*
Y1138419D01*
X1608168Y1138880D01*
X1608818D01*
X1609138Y1138560D01*
X1609788D01*
X1610249Y1139021D01*
Y1139671D01*
X1609929Y1139991D01*
Y1140641D01*
X1610390Y1141102D01*
X1611040D01*
X1611360Y1140782D01*
X1612010D01*
X1612471Y1141243D01*
Y1141893D01*
X1612151Y1142213D01*
Y1142863D01*
X1612612Y1143324D01*
X1613262D01*
X1613582Y1143004D01*
X1614232D01*
X1614693Y1143465D01*
Y1144115D01*
X1614373Y1144435D01*
Y1145085D01*
X1615042Y1145754D01*
Y1148167D01*
X1618522Y1151647D01*
Y1152297D01*
X1618061Y1152758D01*
X1617411D01*
X1615819Y1151166D01*
X1615169D01*
X1614708Y1151627D01*
Y1152277D01*
X1617411Y1154980D01*
X1618061D01*
X1619633Y1153408D01*
X1620283D01*
X1621934Y1155059D01*
X1623496D01*
G01X1558718Y1091134D02*
X1583470D01*
X1590724Y1098388D01*
Y1103006D01*
X1617679Y1129961D01*
X1619361D01*
G01X1558312Y1094148D02*
X1577769D01*
X1619615Y1135994D01*
G01X1557587Y1092568D02*
X1578389D01*
X1579878Y1094057D01*
X1580528D01*
X1581947Y1092638D01*
X1582597D01*
X1583058Y1093099D01*
Y1093749D01*
X1581639Y1095168D01*
Y1095818D01*
X1582100Y1096279D01*
X1582750D01*
X1584169Y1094860D01*
X1584819D01*
X1585280Y1095321D01*
Y1095971D01*
X1583861Y1097390D01*
Y1098040D01*
X1584322Y1098501D01*
X1584972D01*
X1586391Y1097082D01*
X1587041D01*
X1587502Y1097543D01*
Y1098193D01*
X1586083Y1099612D01*
Y1100262D01*
X1586544Y1100723D01*
X1587194D01*
X1588273Y1099644D01*
X1588923D01*
X1589384Y1100105D01*
Y1100755D01*
X1588305Y1101834D01*
Y1102484D01*
X1598243Y1112422D01*
Y1112430D01*
X1620794Y1134981D01*
X1623496D01*
G01X1558809Y1095563D02*
X1577288D01*
X1605115Y1123390D01*
Y1123425D01*
X1607750Y1126060D01*
Y1126709D01*
X1607330Y1127129D01*
Y1127779D01*
X1607791Y1128240D01*
X1608441D01*
X1608861Y1127821D01*
X1609511D01*
X1609972Y1128282D01*
Y1128931D01*
X1609552Y1129351D01*
Y1130001D01*
X1610013Y1130462D01*
X1610663D01*
X1611083Y1130043D01*
X1611733D01*
X1612194Y1130504D01*
Y1131153D01*
X1611774Y1131573D01*
Y1132223D01*
X1612235Y1132684D01*
X1612885D01*
X1613305Y1132265D01*
X1613955D01*
X1614416Y1132726D01*
Y1133375D01*
X1613996Y1133795D01*
Y1134445D01*
X1614457Y1134906D01*
X1615107D01*
X1615527Y1134487D01*
X1616177D01*
X1616638Y1134948D01*
Y1135597D01*
X1616218Y1136017D01*
Y1136667D01*
X1616679Y1137128D01*
X1617329D01*
X1617749Y1136709D01*
X1618399D01*
X1618908Y1137218D01*
Y1139323D01*
X1621259Y1141674D01*
X1623496D01*
G01X1558414Y1097488D02*
X1576537D01*
X1589708Y1110659D01*
Y1111309D01*
X1589336Y1111681D01*
Y1112331D01*
X1589797Y1112792D01*
X1590447D01*
X1590819Y1112420D01*
X1591469D01*
X1591930Y1112881D01*
Y1113531D01*
X1591558Y1113903D01*
Y1114553D01*
X1592019Y1115014D01*
X1592669D01*
X1593041Y1114642D01*
X1593691D01*
X1594152Y1115103D01*
Y1115753D01*
X1593780Y1116125D01*
Y1116775D01*
X1594241Y1117236D01*
X1594891D01*
X1595263Y1116864D01*
X1595913D01*
X1596374Y1117325D01*
Y1117975D01*
X1596002Y1118347D01*
Y1118997D01*
X1596463Y1119458D01*
X1597113D01*
X1597485Y1119086D01*
X1598135D01*
X1598596Y1119547D01*
Y1120197D01*
X1598224Y1120569D01*
Y1121219D01*
X1598685Y1121680D01*
X1599335D01*
X1599707Y1121308D01*
X1600357D01*
X1600818Y1121769D01*
Y1122419D01*
X1600446Y1122791D01*
Y1123441D01*
X1600907Y1123902D01*
X1601557D01*
X1601929Y1123530D01*
X1602579D01*
X1603040Y1123991D01*
Y1124641D01*
X1602668Y1125013D01*
Y1125663D01*
X1603129Y1126124D01*
X1603779D01*
X1604151Y1125752D01*
X1604801D01*
X1605262Y1126213D01*
Y1126863D01*
X1604890Y1127235D01*
Y1127885D01*
X1619062Y1142057D01*
Y1145480D01*
X1619636Y1146054D01*
G01X1558482Y1100182D02*
X1571367D01*
X1596913Y1125728D01*
X1598941D01*
X1616382Y1143169D01*
Y1146596D01*
X1619361Y1149575D01*
G01X1558313Y1111716D02*
X1570408D01*
X1600344Y1141652D01*
Y1154730D01*
X1612386Y1166772D01*
X1619361D01*
G01X1558808Y1114526D02*
X1569426D01*
X1594522Y1139622D01*
Y1153201D01*
X1614786Y1173465D01*
X1619361D01*
G01X1557360Y1113056D02*
X1569852D01*
X1599004Y1142208D01*
Y1151073D01*
X1598544Y1151533D01*
X1597893D01*
X1597433Y1151073D01*
Y1143178D01*
X1596973Y1142718D01*
X1596322D01*
X1595862Y1143178D01*
Y1152644D01*
X1596322Y1153104D01*
X1598544D01*
X1599004Y1153564D01*
Y1155287D01*
X1615509Y1171792D01*
X1623496D01*
G01X1558774Y1115866D02*
X1568869D01*
X1593182Y1140179D01*
Y1153758D01*
X1615376Y1175952D01*
Y1176601D01*
X1614914Y1177063D01*
X1614264D01*
X1611422Y1174221D01*
X1610772D01*
X1610310Y1174682D01*
Y1175332D01*
X1614263Y1179285D01*
X1614913D01*
X1616487Y1177713D01*
X1617137D01*
X1617909Y1178485D01*
X1623496D01*
G01X1558113Y1117666D02*
X1568123D01*
X1591382Y1140925D01*
Y1154505D01*
X1608510Y1171633D01*
Y1176079D01*
X1615935Y1183504D01*
X1619361D01*
G01X1557452Y1120424D02*
X1567089D01*
X1588702Y1142037D01*
Y1155751D01*
X1591212Y1158261D01*
Y1162573D01*
X1615490Y1186851D01*
X1619361D01*
G01X1557629Y1119016D02*
X1567577D01*
X1590042Y1141481D01*
Y1155195D01*
X1594460Y1159613D01*
Y1160263D01*
X1592966Y1161757D01*
Y1162407D01*
X1593427Y1162868D01*
X1594077D01*
X1595571Y1161374D01*
X1596221D01*
X1596682Y1161835D01*
Y1162485D01*
X1595176Y1163991D01*
Y1164641D01*
X1595637Y1165102D01*
X1596287D01*
X1597793Y1163596D01*
X1598443D01*
X1598904Y1164057D01*
Y1164707D01*
X1597398Y1166213D01*
Y1166863D01*
X1597859Y1167324D01*
X1598509D01*
X1600015Y1165818D01*
X1600665D01*
X1601126Y1166279D01*
Y1166929D01*
X1599620Y1168435D01*
Y1169085D01*
X1600081Y1169546D01*
X1600731D01*
X1602237Y1168040D01*
X1602887D01*
X1603348Y1168501D01*
Y1169151D01*
X1601842Y1170657D01*
Y1171307D01*
X1602303Y1171768D01*
X1602953D01*
X1604459Y1170262D01*
X1605109D01*
X1605570Y1170723D01*
Y1171373D01*
X1604064Y1172879D01*
Y1173529D01*
X1604525Y1173990D01*
X1605175D01*
X1606059Y1173106D01*
X1606709D01*
X1607170Y1173567D01*
Y1174217D01*
X1606286Y1175101D01*
Y1175751D01*
X1615712Y1185177D01*
X1623496D01*
G01X1557277Y1121817D02*
X1566586D01*
X1585063Y1140294D01*
Y1141679D01*
X1585523Y1142139D01*
X1586797D01*
X1587257Y1142599D01*
Y1143250D01*
X1586797Y1143710D01*
X1585523D01*
X1585063Y1144170D01*
Y1144821D01*
X1585523Y1145281D01*
X1586797D01*
X1587257Y1145741D01*
Y1146392D01*
X1586797Y1146852D01*
X1585523D01*
X1585063Y1147312D01*
Y1147963D01*
X1585523Y1148423D01*
X1586797D01*
X1587257Y1148883D01*
Y1149534D01*
X1586797Y1149994D01*
X1585523D01*
X1585063Y1150454D01*
Y1151105D01*
X1585523Y1151565D01*
X1586797D01*
X1587257Y1152025D01*
Y1152676D01*
X1586797Y1153136D01*
X1585523D01*
X1585063Y1153596D01*
Y1154247D01*
X1585523Y1154707D01*
X1586797D01*
X1587257Y1155167D01*
Y1155818D01*
X1586797Y1156278D01*
X1585523D01*
X1585063Y1156738D01*
Y1158464D01*
X1586177Y1159573D01*
X1586826Y1159572D01*
X1588289Y1158102D01*
X1588939Y1158101D01*
X1589402Y1158562D01*
X1589403Y1159211D01*
X1587940Y1160680D01*
X1587941Y1161330D01*
X1618613Y1191870D01*
X1623496D01*
G01X1558391Y1131211D02*
X1559742D01*
X1560202Y1130751D01*
Y1130348D01*
X1560662Y1129888D01*
X1561313D01*
X1561773Y1130348D01*
Y1130751D01*
X1562233Y1131211D01*
X1564779D01*
X1577633Y1144065D01*
Y1165648D01*
X1615568Y1203583D01*
X1619361D01*
G01X1558479Y1133891D02*
X1563667D01*
X1574953Y1145177D01*
Y1169828D01*
X1587732Y1182607D01*
X1590798D01*
X1618467Y1210276D01*
X1619361D01*
G01X1558407Y1132551D02*
X1564223D01*
X1576293Y1144621D01*
Y1166205D01*
X1577601Y1167513D01*
Y1168163D01*
X1576717Y1169046D01*
Y1169696D01*
X1577178Y1170157D01*
X1577828D01*
X1578712Y1169274D01*
X1579362D01*
X1579823Y1169735D01*
Y1170385D01*
X1578939Y1171268D01*
Y1171918D01*
X1579400Y1172379D01*
X1580050D01*
X1580934Y1171496D01*
X1581584D01*
X1582045Y1171957D01*
Y1172607D01*
X1581161Y1173490D01*
Y1174140D01*
X1581622Y1174601D01*
X1582272D01*
X1583156Y1173718D01*
X1583806D01*
X1584267Y1174179D01*
Y1174829D01*
X1583383Y1175712D01*
Y1176362D01*
X1583844Y1176823D01*
X1584494D01*
X1585378Y1175940D01*
X1586028D01*
X1586489Y1176401D01*
Y1177051D01*
X1585605Y1177934D01*
Y1178584D01*
X1586066Y1179045D01*
X1586716D01*
X1587600Y1178162D01*
X1588250D01*
X1588711Y1178623D01*
Y1179273D01*
X1587827Y1180156D01*
Y1180806D01*
X1588288Y1181267D01*
X1588938D01*
X1589822Y1180384D01*
X1590472D01*
X1618619Y1208531D01*
X1618793Y1208603D01*
X1623496D01*
G01X1558612Y1135231D02*
X1563111D01*
X1573613Y1145733D01*
Y1170384D01*
X1588317Y1185088D01*
X1588967D01*
X1589807Y1184248D01*
X1590457D01*
X1590918Y1184709D01*
Y1185359D01*
X1590078Y1186199D01*
Y1186849D01*
X1590539Y1187310D01*
X1591189D01*
X1592029Y1186470D01*
X1592679D01*
X1593140Y1186931D01*
Y1187581D01*
X1592300Y1188421D01*
Y1189071D01*
X1592761Y1189532D01*
X1593411D01*
X1594251Y1188692D01*
X1594901D01*
X1595362Y1189153D01*
Y1189803D01*
X1594522Y1190643D01*
Y1191293D01*
X1594983Y1191754D01*
X1595633D01*
X1596473Y1190914D01*
X1597123D01*
X1597584Y1191375D01*
Y1192025D01*
X1596744Y1192865D01*
Y1193515D01*
X1597205Y1193976D01*
X1597855D01*
X1598695Y1193136D01*
X1599345D01*
X1621505Y1215296D01*
X1623496D01*
G01X1557648Y1137031D02*
X1562335D01*
X1571813Y1146509D01*
Y1171130D01*
X1596459Y1195776D01*
X1599439D01*
X1619137Y1215474D01*
Y1219176D01*
X1619637Y1219676D01*
G01X1557687Y1139711D02*
X1561223D01*
X1569133Y1147621D01*
Y1173706D01*
X1601808Y1206381D01*
X1606252D01*
X1612956Y1213085D01*
Y1217529D01*
X1619089Y1223662D01*
G01X1557790Y1138371D02*
X1561779D01*
X1570473Y1147065D01*
Y1173150D01*
X1602364Y1205041D01*
X1603014D01*
X1603475Y1204580D01*
Y1203930D01*
X1597772Y1198227D01*
Y1197577D01*
X1598233Y1197116D01*
X1598883D01*
X1614296Y1212529D01*
Y1216231D01*
X1614830Y1216765D01*
X1615480D01*
X1616607Y1215638D01*
X1617257D01*
X1617718Y1216099D01*
Y1216749D01*
X1616591Y1217876D01*
Y1218526D01*
X1620053Y1221988D01*
X1623496D01*
G01X1557585Y1141051D02*
X1560421D01*
X1567793Y1148423D01*
Y1174540D01*
X1602546Y1209293D01*
X1603196D01*
X1604768Y1207721D01*
X1605418D01*
X1611616Y1213919D01*
Y1214569D01*
X1611155Y1215030D01*
X1610505D01*
X1605418Y1209943D01*
X1604768D01*
X1604307Y1210404D01*
Y1211054D01*
X1621934Y1228681D01*
X1623496D01*
G01X1558370Y1150616D02*
X1560303Y1152549D01*
Y1177877D01*
X1584022Y1201596D01*
Y1202246D01*
X1582074Y1204193D01*
Y1204843D01*
X1582535Y1205304D01*
X1583185D01*
X1585133Y1203357D01*
X1585783D01*
X1591828Y1209402D01*
Y1214080D01*
X1618142Y1240394D01*
X1619361D01*
G01X1557622Y1155614D02*
Y1185200D01*
X1619361Y1246939D01*
G01X1557082Y1151340D02*
X1558963Y1153221D01*
Y1178724D01*
X1573287Y1193048D01*
Y1198208D01*
X1582847Y1207768D01*
X1583497D01*
X1585572Y1205693D01*
X1586222D01*
X1586683Y1206154D01*
Y1206804D01*
X1584608Y1208879D01*
Y1209529D01*
X1585069Y1209990D01*
X1585719D01*
X1587794Y1207915D01*
X1588444D01*
X1588905Y1208376D01*
Y1209026D01*
X1586830Y1211101D01*
Y1211751D01*
X1587291Y1212212D01*
X1587941D01*
X1589191Y1210962D01*
X1589841D01*
X1590302Y1211423D01*
Y1212073D01*
X1589052Y1213323D01*
Y1213973D01*
X1620493Y1245414D01*
X1623496D01*
G01X1550622Y1154567D02*
X1551653Y1155598D01*
X1554367D01*
X1556277Y1157508D01*
Y1186450D01*
X1605509Y1235682D01*
Y1236332D01*
X1604406Y1237434D01*
Y1238084D01*
X1604867Y1238545D01*
X1605517D01*
X1606620Y1237443D01*
X1607270D01*
X1607731Y1237904D01*
Y1238554D01*
X1606628Y1239656D01*
Y1240306D01*
X1607089Y1240767D01*
X1607739D01*
X1608842Y1239665D01*
X1609492D01*
X1609953Y1240126D01*
Y1240776D01*
X1608850Y1241878D01*
Y1242528D01*
X1609311Y1242989D01*
X1609961D01*
X1611064Y1241887D01*
X1611714D01*
X1612175Y1242348D01*
Y1242998D01*
X1611072Y1244100D01*
Y1244750D01*
X1611533Y1245211D01*
X1612183D01*
X1613286Y1244109D01*
X1613936D01*
X1614397Y1244570D01*
Y1245220D01*
X1613294Y1246322D01*
Y1246972D01*
X1613755Y1247433D01*
X1614405D01*
X1615110Y1246729D01*
X1615508Y1246331D01*
X1616158D01*
X1616619Y1246792D01*
Y1247441D01*
X1615827Y1248233D01*
Y1248882D01*
X1616288Y1249343D01*
X1616940D01*
X1617699Y1248584D01*
X1618411D01*
X1621934Y1252107D01*
X1623496D01*
G01X1579177Y1262213D02*
X1574622Y1257658D01*
X1559908D01*
X1551113Y1248863D01*
Y1238088D01*
G01X1548360Y1234750D02*
X1551905D01*
X1553398Y1236243D01*
Y1239580D01*
X1552233Y1240745D01*
Y1248383D01*
X1560090Y1256240D01*
X1581204D01*
X1587177Y1262213D01*
G01X1591177D02*
X1592475Y1260915D01*
Y1243750D01*
X1582168Y1233443D01*
X1551055D01*
X1550517Y1232905D01*
G01X1543519Y1248205D02*
X1546572D01*
X1550212Y1251845D01*
Y1262314D01*
G01X1547102Y1270188D02*
X1542842Y1265928D01*
G01D02*
Y1259450D01*
X1543980Y1258312D01*
G01X1550249Y1266271D02*
Y1262351D01*
X1550212Y1262314D01*
G01D02*
X1553960D01*
X1554434Y1262788D01*
X1556178D01*
G01X1558077Y1276363D02*
Y1279724D01*
X1557510Y1280291D01*
G01X1554377Y1276363D02*
Y1278763D01*
G01X1550252Y1282188D02*
X1550745D01*
X1553548Y1284991D01*
G01X1550252Y1286188D02*
X1550600D01*
X1553226Y1288814D01*
G01X1557973Y1302609D02*
X1557825Y1302757D01*
X1555222D01*
G01X1550396Y1539600D02*
Y1539202D01*
X1551598Y1538000D01*
X1555596D01*
G01D02*
Y1538647D01*
X1558924Y1541975D01*
G01X1553751Y1559953D02*
X1555549Y1561751D01*
X1557494D01*
X1559750Y1559495D01*
Y1555917D01*
X1558583Y1554750D01*
X1558247D01*
G01X1555047Y1551850D02*
Y1554750D01*
G01D02*
X1554523Y1554745D01*
X1553569Y1555688D01*
Y1557012D01*
X1553009Y1557572D01*
X1550798Y1558488D01*
X1550216D01*
X1548751Y1559953D01*
G01X1545397Y1568270D02*
Y1566725D01*
X1546028Y1566094D01*
X1560507D01*
X1561208Y1566795D01*
X1565209D01*
X1566153Y1565851D01*
G01X1564202Y214250D02*
X1582928D01*
G01X1564202Y234250D02*
X1582928D01*
G01X1564202Y239250D02*
X1582928D01*
G01X1564202Y229250D02*
X1582928D01*
G01X1564202Y244250D02*
X1582928D01*
G01X1563655Y290970D02*
X1561103D01*
X1559170Y292903D01*
Y294904D01*
G01X1558198Y486791D02*
Y531852D01*
X1565433Y539087D01*
X1588730D01*
X1590407Y537410D01*
Y536344D01*
G01X1565063Y1273445D02*
Y1273037D01*
X1561927Y1269901D01*
G01X1567737Y1271411D02*
X1567770Y1271378D01*
X1570717D01*
G01X1561123Y1302609D02*
X1564199Y1299533D01*
X1564776D01*
X1572012Y1292297D01*
Y1288136D01*
X1574168Y1285980D01*
Y1283300D01*
G01X1575680Y1303054D02*
X1572522D01*
X1572416Y1303160D01*
G01X1572331Y1348205D02*
Y1318867D01*
X1583345Y1307853D01*
Y1303780D01*
X1584847Y1302278D01*
G01X1569397Y1551040D02*
Y1549839D01*
X1570006Y1549230D01*
X1574757D01*
X1575532Y1550005D01*
Y1552121D01*
X1576218Y1552807D01*
X1579566D01*
G01X1566497Y1550640D02*
Y1551989D01*
X1565866Y1552620D01*
X1562087D01*
X1561507Y1553200D01*
G01X1566497Y1550640D02*
X1567584D01*
X1567984Y1551040D01*
X1569397D01*
G01X1579566Y1550445D02*
X1578812D01*
X1576170Y1547803D01*
Y1547248D01*
X1574532Y1545610D01*
X1570017D01*
X1569397Y1546230D01*
Y1547420D01*
G01D02*
X1566377D01*
X1566271Y1547314D01*
G01X1569397Y1543800D02*
Y1542522D01*
X1570228Y1541691D01*
X1574063D01*
X1577181Y1544809D01*
Y1547568D01*
X1578877Y1549264D01*
X1581612D01*
G01X1569397Y1543800D02*
X1565497D01*
G01D02*
Y1544135D01*
X1562318Y1547314D01*
X1561271D01*
G01X1558247Y1554750D02*
Y1551850D01*
G01X1572246Y1586688D02*
X1571145D01*
X1570564Y1587269D01*
Y1594565D01*
X1576321Y1600322D01*
X1580117D01*
G01X1581612Y1563437D02*
X1576084D01*
X1572798Y1566723D01*
Y1583552D01*
X1572246Y1584104D01*
Y1586688D01*
G01Y1588788D02*
X1576046D01*
G01X1587728Y214250D02*
X1582928D01*
G01X1587728Y234250D02*
X1582928D01*
G01X1587728Y239250D02*
X1582928D01*
G01X1587728Y229250D02*
X1582928D01*
G01X1587728Y244250D02*
X1582928D01*
G01X1586621Y484304D02*
Y532441D01*
X1587965Y533785D01*
X1590407D01*
G01X1577934Y531226D02*
X1573224D01*
X1573218Y531220D01*
G01X1582927Y531226D02*
Y533785D01*
G01Y531226D02*
X1577934D01*
G01X1576680Y574022D02*
X1572436D01*
G01X1579177Y1262213D02*
X1583177D01*
G01X1588602Y1278988D02*
X1585252D01*
G01X1573867Y1271378D02*
X1574308Y1270937D01*
X1577077D01*
G01X1580577D02*
Y1274767D01*
X1579890Y1275454D01*
X1578280D01*
G01X1584847Y1298278D02*
Y1302278D01*
G01X1575680Y1299904D02*
X1574560Y1298784D01*
Y1296410D01*
G01X1577982Y1288958D02*
X1579578D01*
X1580520Y1289900D01*
G01X1585252Y1292988D02*
X1586167Y1293903D01*
Y1295478D01*
G01X1578854Y1546218D02*
X1580928D01*
X1581612Y1546902D01*
G01X1577195Y1551121D02*
X1578190D01*
X1578695Y1551626D01*
X1581612D01*
G01Y1565799D02*
X1578150D01*
X1575895Y1568054D01*
Y1573245D01*
X1586554Y1583904D01*
Y1588570D01*
X1586818Y1588834D01*
G01X1579566Y1564618D02*
X1577191D01*
X1574450Y1567359D01*
Y1573869D01*
X1580833Y1580252D01*
Y1584952D01*
X1579897Y1585888D01*
X1579246D01*
G01X1577596Y1554612D02*
X1578220Y1553988D01*
X1581612D01*
G01Y1568162D02*
X1578178D01*
X1577642Y1568698D01*
G01X1579566Y1569343D02*
X1578011Y1570898D01*
X1577642D01*
G01X1574966Y1577038D02*
X1574280Y1577724D01*
Y1585096D01*
X1575072Y1585888D01*
X1576046D01*
G01X1583523Y1592939D02*
Y1590039D01*
G01D02*
X1585613D01*
X1586818Y1588834D01*
G01X1579246Y1588788D02*
Y1585888D01*
G01Y1588788D02*
X1580295D01*
X1581177Y1589670D01*
Y1593171D01*
X1580269Y1594079D01*
G01X1576046Y1585888D02*
Y1588788D01*
G01X1590878Y214250D02*
X1595264D01*
X1603970Y222956D01*
G01X1590878Y234250D02*
X1593303D01*
G01X1590878Y239250D02*
X1593303D01*
G01X1595878Y225250D02*
X1590878D01*
G01X1595878D02*
Y225796D01*
X1599091Y229009D01*
Y233462D01*
X1598303Y234250D01*
G01X1587728Y229250D02*
Y225250D01*
G01X1590878Y244250D02*
X1593303D01*
G01X1598724Y531226D02*
X1596299D01*
X1593740Y533785D01*
X1590407D01*
G01X1610490Y538723D02*
Y537377D01*
X1607221Y534108D01*
X1600247D01*
X1598724Y532585D01*
Y531226D01*
G01X1596299Y536344D02*
X1598724D01*
G01X1590407D02*
X1596299D01*
G01X1596363Y1286296D02*
X1595867Y1285800D01*
X1592279D01*
X1588602Y1282123D01*
Y1278988D01*
G01X1615020Y183050D02*
X1622560Y190590D01*
Y244070D01*
X1625517Y247027D01*
Y278520D01*
G01X1619909Y298742D02*
X1617250D01*
X1615250Y300742D01*
X1611663D01*
G01X1619909Y293742D02*
X1619433D01*
X1614993Y298182D01*
X1611663D01*
G01X1617534Y289742D02*
Y292265D01*
X1614471Y295328D01*
X1611663D01*
G01X1618859Y542820D02*
X1614762Y538723D01*
X1613640D01*
G01X1613694Y542733D02*
Y541565D01*
X1612816Y540687D01*
X1605677D01*
X1605241Y541123D01*
G01X1621536Y549540D02*
X1620162D01*
X1613694Y543072D01*
Y542733D01*
G01X1623452Y32756D02*
Y29384D01*
X1622329Y28261D01*
G01X1623452Y44370D02*
Y48457D01*
X1623189Y48720D01*
G01X1632822Y227157D02*
X1629597D01*
G01X1625517Y282728D02*
X1627986D01*
G01X1622367D02*
Y286709D01*
X1622334Y286742D01*
G01X1622367Y278520D02*
Y282728D01*
G01X1621680Y366920D02*
X1626370D01*
X1631940Y361350D01*
Y283070D01*
X1627390Y278520D01*
X1625517D01*
G01X1625484Y286742D02*
X1627909D01*
G01X1625484Y290742D02*
X1627909D01*
G01X1622334Y298742D02*
X1619909D01*
G01X1622334D02*
Y302742D01*
G01Y294742D02*
Y290742D01*
G01Y294742D02*
X1620909D01*
X1619909Y293742D01*
G01X1622334Y286742D02*
X1620534D01*
X1617534Y289742D01*
G01X1625484Y302742D02*
X1627909D01*
G01X1625000Y385925D02*
Y383399D01*
G01X1629000Y392925D02*
Y389075D01*
G01X1631657Y392925D02*
X1634760Y396028D01*
G01X1629000Y392925D02*
X1631657D01*
G01X1629000Y389075D02*
X1625000D01*
G01X1621536Y547571D02*
X1620324D01*
X1618859Y546106D01*
Y542820D01*
G01X1623496Y766870D02*
X1617200D01*
G01X1623496Y763524D02*
X1618946D01*
G01X1632803Y1432248D02*
Y1431462D01*
X1631754Y1430413D01*
X1628561D01*
X1628071Y1430903D01*
X1622522D01*
X1621000Y1432425D01*
G01Y1435575D02*
Y1439100D01*
X1622697Y1440797D01*
G01X1629592Y1444016D02*
X1625170D01*
G01X1632822Y224597D02*
X1636047D01*
G01X1646798Y221842D02*
X1650023D01*
G01X1646798Y224597D02*
X1654419D01*
G01X1646798Y227157D02*
X1650023D01*
G01X1632822Y229912D02*
X1636047D01*
G01X1653642Y418139D02*
Y419170D01*
X1652110Y420702D01*
X1649010D01*
X1646010Y423702D01*
G01D02*
Y427969D01*
X1646510Y428469D01*
G01X1639638Y766870D02*
X1644188D01*
G01X1639638Y770217D02*
X1644188D01*
G01X1639834Y1429478D02*
X1636677D01*
X1635619Y1430536D01*
G01D02*
X1633907Y1432248D01*
X1632803D01*
G01X1632778Y1428366D02*
Y1424466D01*
G01D02*
X1634794Y1422450D01*
X1635281D01*
G01D02*
Y1425485D01*
X1637699Y1427903D01*
X1639834D01*
G01X1635227Y1436528D02*
Y1434265D01*
X1638439Y1431053D01*
X1639834D01*
G01X1636167Y1446746D02*
X1634897Y1448016D01*
X1632742D01*
G01X1636167Y1442053D02*
Y1446746D01*
G01Y1438903D02*
Y1438538D01*
X1639834Y1434871D01*
Y1434478D01*
G01D02*
Y1432628D01*
G01X1642196Y1434990D02*
Y1436539D01*
X1642400Y1436743D01*
Y1439674D01*
G01D02*
Y1441886D01*
X1642742Y1442228D01*
G01X1643771Y1434990D02*
Y1436262D01*
X1644200Y1436691D01*
Y1439011D01*
X1645677Y1440488D01*
X1646602D01*
G01D02*
Y1441573D01*
X1646533Y1441642D01*
Y1445767D01*
G01X1632742Y1440016D02*
Y1436209D01*
X1632803Y1436148D01*
G01X1632742Y1440016D02*
Y1444016D01*
G01X1632803Y1436148D02*
X1633927D01*
X1634307Y1436528D01*
X1635227D01*
G01X1653614Y1452264D02*
Y1450203D01*
X1652890Y1449479D01*
X1643900D01*
X1641167Y1446746D01*
G01X1639592Y1442228D02*
X1639684Y1442320D01*
Y1443922D01*
X1639592Y1444014D01*
Y1445171D01*
X1641167Y1446746D01*
G01X1650513Y1715609D02*
X1645029D01*
G01Y1710609D02*
X1646179Y1711759D01*
X1650513D01*
G01X1645029Y1725759D02*
X1646179Y1726909D01*
X1650513D01*
G01Y1730759D02*
X1645029D01*
G01X1658100Y141762D02*
X1662900D01*
G01X1658100Y146762D02*
X1662900D01*
G01X1658100Y151762D02*
X1662900D01*
G01X1658100Y161762D02*
X1662900D01*
G01X1661928Y224597D02*
X1659419D01*
G01X1662000Y221075D02*
Y224525D01*
X1661928Y224597D01*
G01X1652610Y400277D02*
Y403002D01*
X1654610Y405002D01*
G01X1659610Y400277D02*
X1663610D01*
G01X1655610Y418139D02*
Y419703D01*
X1653610Y421703D01*
Y423702D01*
G01X1661210D02*
X1657578Y420070D01*
Y418139D01*
G01X1654610Y405002D02*
X1655610Y406002D01*
Y410265D01*
G01X1661610Y405202D02*
X1657578Y409234D01*
Y410265D01*
G01X1663610Y400277D02*
Y403202D01*
X1661610Y405202D01*
G01X1653790Y431619D02*
Y433857D01*
X1654110Y434177D01*
G01X1657545Y431619D02*
Y434506D01*
G01X1653610Y423702D02*
Y428289D01*
X1653790Y428469D01*
G01D02*
X1657545D01*
G01X1650035D02*
X1653790D01*
G01X1661110Y428627D02*
X1661210Y428527D01*
Y423702D01*
G01X1650035Y431619D02*
Y434750D01*
G01X1653197Y766870D02*
X1648647D01*
G01X1653197Y763524D02*
X1648647D01*
G01X1657892Y1452285D02*
Y1450585D01*
X1654020Y1446713D01*
X1649380D01*
G01D02*
X1649752Y1446341D01*
Y1440488D01*
G01X1657892Y1455435D02*
X1677625D01*
X1681538Y1451522D01*
G01X1653614Y1455414D02*
X1655341Y1457141D01*
X1683417D01*
X1689062Y1451496D01*
G01X1676685Y1537893D02*
X1672919Y1541659D01*
X1669434D01*
X1666392Y1538617D01*
X1662877D01*
X1661204Y1540290D01*
Y1542459D01*
G01Y1573477D02*
Y1576895D01*
X1663939Y1579630D01*
Y1585684D01*
X1662973Y1586650D01*
X1662129D01*
G01Y1589550D02*
X1658869D01*
G01X1656136Y1669336D02*
Y1671685D01*
X1656101Y1671720D01*
G01X1651146Y1669466D02*
Y1671788D01*
X1651101Y1671833D01*
G01X1656849Y1664949D02*
Y1666523D01*
X1656136Y1667236D01*
G01X1651146Y1667366D02*
Y1665597D01*
X1651698Y1665045D01*
G01X1656101Y1671720D02*
Y1675927D01*
G01X1651101Y1671833D02*
Y1675927D01*
G01X1656101Y1701094D02*
Y1696399D01*
G01X1654513Y1715609D02*
X1657813D01*
X1658513Y1714909D01*
G01X1663020Y1714318D02*
X1659104D01*
X1658513Y1714909D01*
G01X1654513Y1715609D02*
X1650513D01*
G01X1658513Y1711759D02*
X1654513D01*
G01X1663020D02*
X1658513D01*
G01X1654513D02*
X1650513D01*
G01X1656089Y1704237D02*
X1656101Y1704225D01*
Y1701094D01*
G01X1654513Y1726909D02*
X1663020D01*
G01X1650513D02*
X1654513D01*
G01Y1730759D02*
X1657813D01*
X1659104Y1729468D01*
X1663020D01*
G01X1654513Y1730759D02*
X1650513D01*
G01X1669100Y131762D02*
X1673100D01*
G01X1669100Y121762D02*
X1673100D01*
G01X1662900Y141762D02*
X1669100D01*
G01Y136762D02*
X1673100D01*
G01X1662900Y146762D02*
X1669100D01*
G01X1662900Y151762D02*
X1669100D01*
G01X1662900Y161762D02*
X1669100D01*
G01X1668612Y224597D02*
X1661928D01*
G01X1669339Y766870D02*
X1673889D01*
G01X1669339Y770217D02*
X1673889D01*
G01X1676685Y1537893D02*
X1676345Y1537553D01*
Y1535704D01*
G01X1676819Y1541979D02*
X1675920Y1542878D01*
X1668454D01*
X1665403Y1545929D01*
X1664286D01*
X1663685Y1545328D01*
X1663208D01*
X1662385Y1544505D01*
G01X1665282Y1548083D02*
X1666937Y1547073D01*
G01X1665282Y1550445D02*
X1666881Y1549336D01*
G01X1687537Y1567788D02*
X1686064Y1566315D01*
X1672123D01*
X1670885Y1565077D01*
Y1562841D01*
X1668309Y1560265D01*
Y1558196D01*
X1665282Y1555169D01*
G01X1694075Y1567158D02*
X1692352Y1565435D01*
X1672618D01*
X1671853Y1564670D01*
Y1562553D01*
X1669189Y1559889D01*
Y1557108D01*
X1666755Y1554674D01*
Y1554280D01*
X1665282Y1552807D01*
G01Y1564618D02*
X1667232D01*
G01X1665282Y1562256D02*
X1665840Y1561698D01*
X1667143D01*
G01X1663237Y1565799D02*
X1666118D01*
X1666399Y1566080D01*
X1668894D01*
X1670227Y1567413D01*
G01X1663237Y1563437D02*
X1666089D01*
X1666368Y1563158D01*
X1668750D01*
G01X1665928Y1573477D02*
Y1575419D01*
X1669955Y1579446D01*
X1671263Y1579988D01*
X1672018Y1580743D01*
X1673313Y1583871D01*
Y1585422D01*
X1672085Y1586650D01*
X1671689D01*
G01X1662385Y1571431D02*
Y1574661D01*
X1665359Y1577635D01*
Y1593995D01*
X1665726Y1594362D01*
G01X1665282Y1569343D02*
X1666934D01*
X1667231Y1569640D01*
G01X1665282Y1566980D02*
X1665281D01*
X1665841Y1567540D01*
X1667231D01*
G01X1671689Y1586650D02*
Y1587191D01*
X1672396Y1587898D01*
X1681838D01*
X1686064Y1583672D01*
Y1573892D01*
G01X1668489Y1591650D02*
X1665777Y1594362D01*
X1665726D01*
G01X1668489Y1589550D02*
Y1586650D01*
G01X1690353Y1591494D02*
X1688388Y1589529D01*
X1672012D01*
X1669133Y1586650D01*
X1668489D01*
G01X1662129D02*
Y1589550D01*
G01X1671400Y1661050D02*
Y1661952D01*
X1670202Y1663150D01*
G01D02*
X1671400Y1664348D01*
Y1665250D01*
G01X1674600Y1661050D02*
Y1662467D01*
X1675290Y1663157D01*
G01X1683561Y1685261D02*
X1681309D01*
X1681109Y1685461D01*
X1677040D01*
X1676397Y1684818D01*
G01X1683561Y1687229D02*
X1682250D01*
X1679661Y1689818D01*
X1676397D01*
G01X1686120Y1691757D02*
Y1693115D01*
X1684917Y1694318D01*
X1681897D01*
X1676397Y1699818D01*
G01X1683561Y1689198D02*
X1682017D01*
X1676397Y1694818D01*
G01X1670500Y1714318D02*
Y1716877D01*
G01X1675360Y1712077D02*
Y1716877D01*
G01X1670500D02*
X1675360D01*
G01X1670500Y1729468D02*
Y1732027D01*
G01X1675360Y1726827D02*
Y1732027D01*
G01X1670500D02*
X1675360D01*
G01X1678258Y220857D02*
X1682433D01*
G01X1692429Y401485D02*
X1688504D01*
G01X1694050Y416643D02*
X1691329D01*
X1687079Y420893D01*
Y424673D01*
X1687058Y424694D01*
G01X1697161Y406602D02*
X1690471D01*
X1688504Y404635D01*
G01X1687058Y424694D02*
X1687079Y424715D01*
Y427685D01*
X1686154Y428610D01*
G01X1690208Y421855D02*
X1693451Y418612D01*
X1697161D01*
G01X1690208Y424694D02*
Y421855D01*
G01Y424694D02*
Y428556D01*
X1690154Y428610D01*
G01X1682898Y766870D02*
X1678348D01*
G01X1682898Y763524D02*
X1678348D01*
G01X1676819Y1541979D02*
X1679328D01*
X1679972Y1541335D01*
G01D02*
Y1538135D01*
G01X1687537Y1567788D02*
Y1571226D01*
X1688338Y1573159D01*
X1689282Y1574103D01*
Y1576274D01*
X1690650Y1577642D01*
G01X1694075Y1573720D02*
Y1574217D01*
X1690650Y1577642D01*
G01X1688243Y1669377D02*
Y1670891D01*
X1684816Y1674318D01*
G01X1688243Y1669377D02*
X1684073D01*
X1684012Y1669316D01*
G01X1679816Y1669378D02*
Y1674318D01*
G01X1684012Y1666166D02*
Y1665087D01*
X1685500Y1663599D01*
G01D02*
X1688172Y1660927D01*
X1693016D01*
X1695987Y1663898D01*
Y1671618D01*
G01X1677800Y1661050D02*
X1680117Y1663367D01*
X1680367D01*
G01X1681000Y1661050D02*
X1684912D01*
X1686675Y1659287D01*
G01X1684816Y1674318D02*
X1688089Y1677591D01*
Y1680733D01*
G01X1679816Y1674318D02*
X1681416Y1675918D01*
X1682856D01*
X1686120Y1679182D01*
Y1680733D01*
G01X1692415Y1669315D02*
Y1671719D01*
X1689816Y1674318D01*
G01D02*
X1690057Y1674559D01*
Y1680733D01*
G01X1677930Y1679305D02*
X1679150Y1678085D01*
X1682007D01*
X1682700Y1678778D01*
Y1682792D01*
X1683200Y1683292D01*
X1683561D01*
G01X1685513Y1711759D02*
X1689513D01*
G01X1698020D02*
X1689513D01*
G01X1680029Y1710609D02*
X1681179Y1711759D01*
X1685513D01*
G01X1689513Y1715609D02*
X1685513D01*
G01D02*
X1680029D01*
G01X1698020Y1714318D02*
X1690804D01*
X1689513Y1715609D01*
G01X1706066Y57098D02*
X1711172Y62204D01*
X1711798D01*
G01X1707744Y44370D02*
Y55420D01*
X1706066Y57098D01*
G01X1699100Y126762D02*
X1695100D01*
G01X1699100Y131762D02*
X1695100D01*
G01X1699100Y121762D02*
X1695100D01*
G01X1699100Y141762D02*
X1695100D01*
G01X1699100Y136762D02*
X1695100D01*
G01X1699100Y146762D02*
X1695100D01*
G01X1699100Y156762D02*
X1695100D01*
G01X1699100Y151762D02*
X1695100D01*
G01X1699100Y161762D02*
X1695100D01*
G01X1699100Y166762D02*
X1695100D01*
G01X1692429Y403985D02*
Y401485D01*
G01X1702959D02*
Y404243D01*
G01D02*
X1699130Y408072D01*
Y408769D01*
G01X1703067Y410738D02*
X1707780D01*
G01X1697161Y416643D02*
X1694050D01*
G01X1697161Y408769D02*
Y406602D01*
G01X1707568Y420370D02*
X1705810Y418612D01*
X1703067D01*
G01X1701124Y423802D02*
Y420607D01*
X1701098Y420581D01*
G01X1701124Y428100D02*
Y423802D01*
G01X1695455Y422287D02*
X1694314Y423428D01*
Y428580D01*
G01X1697161Y420581D02*
X1695455Y422287D01*
G01X1703067Y420581D02*
X1704624Y422138D01*
Y428100D01*
G01X1707544Y431745D02*
Y429101D01*
X1706543Y428100D01*
X1704624D01*
G01X1699500Y654738D02*
X1702463Y651775D01*
X1713000D01*
G01Y676725D02*
X1702487D01*
X1699500Y673738D01*
G01X1699040Y766870D02*
X1703590D01*
G01X1699040Y770217D02*
X1703590D01*
G01X1694075Y1567158D02*
Y1570520D01*
G01D02*
X1695489Y1571934D01*
Y1576003D01*
X1693850Y1577642D01*
G01X1703050Y1595000D02*
X1713503D01*
X1715693Y1597190D01*
G01X1703050Y1607400D02*
X1704293D01*
X1709833Y1612940D01*
G01X1703050Y1604300D02*
X1704501D01*
X1709841Y1609640D01*
X1713593D01*
G01X1703050Y1601200D02*
X1711753D01*
X1713593Y1603040D01*
G01X1709964Y1597490D02*
X1707329D01*
X1706719Y1598100D01*
X1703050D01*
G01X1694585Y1685261D02*
X1698100D01*
X1700617Y1682744D01*
G01X1701984Y1671618D02*
Y1677371D01*
X1696063Y1683292D01*
X1694585D01*
G01X1695987Y1671618D02*
Y1675603D01*
X1695567Y1676023D01*
X1693233D01*
X1692026Y1677230D01*
Y1680733D01*
G01X1694585Y1687229D02*
X1697497D01*
X1698012Y1687744D01*
X1700617D01*
G01X1694585Y1689198D02*
X1697071D01*
X1700617Y1692744D01*
G01X1745463Y1692040D02*
Y1696728D01*
X1742672Y1699519D01*
X1706084D01*
X1702750Y1696185D01*
G01X1740463Y1692040D02*
Y1696416D01*
X1738944Y1697935D01*
X1712453D01*
X1706086Y1691568D01*
G01X1705500Y1714318D02*
Y1716877D01*
G01D02*
X1710360D01*
G01X1707744Y32756D02*
Y28453D01*
X1707055Y27764D01*
Y15839D01*
X1707186Y15708D01*
G01X1712468Y32756D02*
Y24021D01*
X1716579Y19910D01*
X1717148D01*
G01X1710106Y32756D02*
Y22857D01*
X1712977Y19986D01*
G01X1714830Y32756D02*
Y25414D01*
X1720334Y19910D01*
X1722148D01*
G01X1719555Y32756D02*
Y28438D01*
X1722085Y25908D01*
G01X1717192Y32756D02*
X1717055Y32619D01*
Y25908D01*
G01X1722566Y57098D02*
Y55066D01*
X1719555Y52055D01*
Y44370D01*
G01X1717566Y57098D02*
Y54098D01*
X1717192Y53724D01*
Y44370D01*
G01X1714830D02*
Y50618D01*
X1712566Y52882D01*
Y57098D01*
G01X1712468Y44370D02*
Y49905D01*
X1710089Y52284D01*
Y57828D01*
X1713799Y61538D01*
Y70531D01*
X1715861Y72593D01*
G01X1721344Y62381D02*
Y58320D01*
X1722566Y57098D01*
G01X1716931Y75680D02*
X1718730Y73881D01*
Y58262D01*
X1717566Y57098D01*
G01X1712566D02*
X1716558Y61090D01*
Y62204D01*
G01X1712486Y117908D02*
X1710786Y116208D01*
Y88808D01*
X1714286Y85308D01*
Y76508D01*
X1713470Y75692D01*
X1711798D01*
G01D02*
Y65354D01*
G01X1721344Y65531D02*
Y67813D01*
X1721646Y68115D01*
G01X1716558Y65354D02*
Y67866D01*
G01X1712686Y111908D02*
Y89208D01*
X1716931Y84963D01*
Y78830D01*
G01X1717808Y108959D02*
Y104959D01*
X1718608Y104159D01*
G01X1722608Y108959D02*
X1717808D01*
G01X1713312Y138147D02*
Y132945D01*
X1713399Y132858D01*
G01D02*
X1713418Y132839D01*
Y128242D01*
G01X1715044Y410120D02*
X1715052Y410112D01*
X1718931D01*
G01X1707780Y410738D02*
X1710426D01*
G01X1715044Y410120D02*
X1711044D01*
X1710426Y410738D01*
G01X1710408Y420370D02*
X1707568D01*
G01X1710408D02*
X1714922D01*
X1714952Y420340D01*
G01X1728854Y661285D02*
X1730070Y660069D01*
Y652332D01*
X1726880Y649142D01*
X1720050D01*
G01X1713000Y654925D02*
X1715072Y652853D01*
Y649996D01*
X1719616Y645452D01*
X1731326D01*
X1736848Y650974D01*
G01X1723814Y667191D02*
X1722653D01*
X1720606Y669238D01*
X1717086D01*
X1716030Y668182D01*
G01X1723814Y661285D02*
Y660785D01*
X1721011Y657982D01*
X1718465D01*
G01Y660982D02*
X1714165D01*
X1712909Y662238D01*
G01X1723814Y663254D02*
X1723614Y663054D01*
X1720537D01*
X1718465Y660982D01*
G01X1713000Y658075D02*
Y659909D01*
X1712909Y660000D01*
Y662238D01*
G01X1718576Y666238D02*
X1712909D01*
G01X1723814Y665222D02*
X1719592D01*
X1718576Y666238D01*
G01X1713000Y670425D02*
X1712909Y670334D01*
Y666238D01*
G01X1713000Y673575D02*
X1716107D01*
X1718686Y676154D01*
G01X1712599Y766870D02*
X1708049D01*
G01X1712599Y763524D02*
X1708049D01*
G01X1715693Y1606340D02*
X1709833D01*
G01X1715693Y1599740D02*
X1712214D01*
X1709964Y1597490D01*
G01X1715693Y1612940D02*
X1709833D01*
G01X1720845Y1676909D02*
X1722900Y1678964D01*
X1729724D01*
X1730038Y1678650D01*
Y1676965D01*
G01X1710360Y1716877D02*
Y1712077D01*
G01X1721172Y1712115D02*
X1724633D01*
G01Y1727265D02*
X1719218D01*
G01X1719148Y1721530D02*
X1721033Y1723415D01*
X1724633D01*
G01X1725493Y112867D02*
X1728891D01*
X1728965Y112941D01*
G01X1732099Y112895D02*
X1729011D01*
X1728965Y112941D01*
G01X1732099Y108959D02*
X1726608D01*
G01D02*
X1722608D01*
G01X1736418Y125092D02*
Y124206D01*
X1739686Y120938D01*
G01X1730571Y286855D02*
X1725569D01*
X1723492Y288932D01*
Y293068D01*
G01X1823094Y379552D02*
X1816690D01*
X1808287Y371149D01*
Y362021D01*
X1799538Y353272D01*
X1731406D01*
X1725344Y359334D01*
G01X1731470Y358022D02*
X1734008Y360560D01*
Y364872D01*
G01X1738480Y358082D02*
X1735976Y360586D01*
Y364872D01*
G01X1742770Y387112D02*
X1735976Y380318D01*
Y375896D01*
G01X1735870Y387082D02*
X1734008Y385220D01*
Y375896D01*
G01X1728860Y387032D02*
X1732039Y383853D01*
Y375896D01*
G01X1728854Y663254D02*
X1730140D01*
X1733043Y660351D01*
Y657091D01*
G01X1728854Y665222D02*
X1733704D01*
X1734710Y664216D01*
X1739502D01*
G01X1728854Y667191D02*
X1729005Y667342D01*
X1734134D01*
X1735004Y668212D01*
X1739498D01*
X1739502Y668216D01*
G01X1728741Y766870D02*
X1733727D01*
G01X1728741Y770217D02*
X1733291D01*
G01X1732462Y1667965D02*
X1734224Y1666203D01*
X1734589D01*
G01D02*
X1734980Y1666594D01*
X1739880D01*
G01X1730038Y1676965D02*
X1734412D01*
X1734863Y1676514D01*
G01X1739880Y1672893D02*
X1738484D01*
X1734863Y1676514D01*
G01X1737140Y1710824D02*
X1733224D01*
X1731933Y1712115D01*
X1728633D01*
G01X1724633D02*
X1728633D01*
G01X1724633Y1708265D02*
X1728633D01*
G01D02*
X1732251D01*
G01D02*
X1737140D01*
G01X1728633Y1727265D02*
X1731933D01*
X1732633Y1726565D01*
G01X1737140Y1725974D02*
X1733224D01*
X1732633Y1726565D01*
G01X1728633Y1727265D02*
X1724633D01*
G01X1732633Y1723415D02*
X1728633D01*
G01X1737140D02*
X1732633D01*
G01X1724633D02*
X1728633D01*
G01X1751031Y32756D02*
Y28964D01*
X1748708Y26641D01*
G01X1751031Y44370D02*
Y39063D01*
G01X1749422Y116340D02*
Y118654D01*
X1750786Y120018D01*
G01X1750918Y125092D02*
Y120150D01*
X1750786Y120018D01*
G01X1741548Y116439D02*
Y118801D01*
X1741835Y119088D01*
Y123757D01*
X1741852Y123774D01*
G01X1739580Y116439D02*
Y120832D01*
X1739686Y120938D01*
G01X1743516Y116439D02*
Y121538D01*
X1744976Y122998D01*
G01X1757322Y125096D02*
X1757318Y125092D01*
X1750918D01*
G01X1743418Y128592D02*
Y125340D01*
X1741852Y123774D01*
G01X1746918Y125092D02*
Y124940D01*
X1744976Y122998D01*
G01X1750918Y128242D02*
X1754339D01*
G01X1745490Y357002D02*
X1737945Y364547D01*
Y364872D01*
G01X1740504Y369400D02*
X1742282D01*
X1743550Y368132D01*
X1746120D01*
G01X1751012Y368048D02*
X1746204D01*
X1746120Y368132D01*
G01X1764852Y368148D02*
X1762687Y370313D01*
X1753277D01*
X1751012Y368048D01*
G01X1740504Y367431D02*
X1741440D01*
X1742290Y366581D01*
Y364206D01*
X1743384Y363112D01*
X1745910D01*
G01X1751012Y364048D02*
X1750076Y363112D01*
X1745910D01*
G01X1764852Y364148D02*
X1761999Y361295D01*
X1753765D01*
X1751012Y364048D01*
G01X1740504Y371368D02*
X1742086D01*
X1744240Y373522D01*
X1745910D01*
G01X1764645Y372452D02*
X1764221D01*
X1761721Y374952D01*
X1752220D01*
X1751145Y373877D01*
Y372452D01*
G01D02*
X1746980D01*
X1745910Y373522D01*
G01X1744510Y377452D02*
X1742220Y375162D01*
Y373962D01*
X1741595Y373337D01*
X1740504D01*
G01X1737945Y375896D02*
Y377407D01*
X1743430Y382892D01*
X1744380D01*
G01D02*
X1751085D01*
X1751145Y382952D01*
G01Y377452D02*
X1744510D01*
G01X1739502Y664216D02*
Y662510D01*
X1740980Y661032D01*
X1742306D01*
G01X1739502Y668216D02*
Y668622D01*
X1737002Y671122D01*
Y671494D01*
G01X1742300Y766870D02*
X1737926D01*
X1737850Y766794D01*
G01X1742300Y763524D02*
X1737750D01*
G01X1740463Y1688890D02*
Y1684165D01*
G01D02*
X1742242Y1682386D01*
Y1678405D01*
G01X1745463Y1684165D02*
Y1688890D01*
G01X1743817Y1678405D02*
Y1682519D01*
X1745463Y1684165D01*
G01X1744620Y1710824D02*
Y1713383D01*
G01D02*
Y1716018D01*
G01X1750380Y1713383D02*
Y1714375D01*
X1748654Y1716101D01*
X1744703D01*
X1744620Y1716018D01*
G01X1749480Y1728533D02*
X1744620D01*
G01Y1725974D02*
Y1728533D01*
G01X1749480Y1723733D02*
Y1728533D01*
G01X1762842Y32756D02*
Y20109D01*
X1765920Y17031D01*
G01X1765980Y27031D02*
X1765920D01*
X1765204Y27747D01*
Y32756D01*
G01X1767566D02*
Y30064D01*
X1768009Y29621D01*
Y24120D01*
X1765920Y22031D01*
G01X1762842Y44370D02*
Y51055D01*
X1763010Y51223D01*
G01X1765204Y44370D02*
Y51406D01*
X1765527Y51729D01*
Y53692D01*
G01X1763613Y68637D02*
X1766734D01*
X1767638Y69541D01*
G01X1763613Y72637D02*
X1767584D01*
X1767638Y72691D01*
G01X1764123Y83607D02*
X1767090D01*
X1767136Y83653D01*
G01X1763643Y76797D02*
X1767910D01*
X1767956Y76843D01*
G01X1771642Y85550D02*
X1770695D01*
X1769140Y87105D01*
X1764125D01*
X1764123Y87107D01*
G01D02*
Y89303D01*
X1763409Y90017D01*
X1761417D01*
G01X1847866Y165834D02*
X1850050Y163650D01*
Y152621D01*
X1843416Y145987D01*
X1822513D01*
X1816938Y140412D01*
X1764036D01*
X1759283Y135659D01*
Y133186D01*
X1754339Y128242D01*
G01X1757322Y128246D02*
X1760124D01*
G01X1754295Y372452D02*
X1756933D01*
G01X1754295Y382952D02*
X1770220D01*
G01X1754295Y377452D02*
X1770220D01*
G01X1756598Y677503D02*
X1772990Y693895D01*
Y704840D01*
X1768751Y709079D01*
X1764399D01*
G01X1762812Y677503D02*
X1775600Y690291D01*
Y705140D01*
X1779539Y709079D01*
X1785659D01*
G01X1758442Y766870D02*
X1762992D01*
G01X1758442Y770217D02*
X1762992D01*
G01X1777015Y32756D02*
Y28163D01*
X1775920Y27068D01*
G01X1769929Y32756D02*
Y23022D01*
X1770920Y22031D01*
G01X1774653Y32756D02*
Y29044D01*
X1774110Y28501D01*
Y18711D01*
X1775790Y17031D01*
X1775920D01*
G01X1772291Y32756D02*
Y24512D01*
X1773105Y23698D01*
Y19216D01*
X1770920Y17031D01*
G01X1779377Y32756D02*
Y23292D01*
X1778116Y22031D01*
X1775920D01*
G01X1767566Y44370D02*
Y48448D01*
X1767266Y48748D01*
G01X1779377Y44370D02*
Y50738D01*
G01X1769929Y44370D02*
Y48243D01*
X1769240Y48932D01*
Y50788D01*
G01X1774653Y44370D02*
Y48519D01*
X1774172Y49000D01*
X1773830D01*
G01X1769200Y54300D02*
X1771740Y51760D01*
Y47264D01*
X1772291Y46713D01*
Y44370D01*
G01X1780300Y54400D02*
X1779300D01*
X1776740Y51840D01*
Y48932D01*
X1777015Y48657D01*
Y44370D01*
G01X1775580Y79644D02*
Y73410D01*
X1775546Y73376D01*
G01X1767638Y69541D02*
X1771711D01*
X1775546Y73376D01*
G01X1773611Y79644D02*
Y76014D01*
X1770334Y72737D01*
G01X1767638Y72691D02*
X1770288D01*
X1770334Y72737D01*
G01X1771642Y83581D02*
X1767208D01*
X1767136Y83653D01*
G01X1771642Y79644D02*
Y79347D01*
X1769138Y76843D01*
X1767956D01*
G01X1773611Y85550D02*
Y88305D01*
X1773577Y88339D01*
G01X1771853Y92891D02*
Y90063D01*
X1773577Y88339D01*
G01X1771891Y97245D02*
Y92929D01*
X1771853Y92891D01*
G01X1784133Y165974D02*
X1780394D01*
X1779380Y164960D01*
Y159910D01*
X1780405Y158885D01*
X1784133D01*
G01X1778500Y190799D02*
Y189991D01*
X1776620Y188111D01*
Y180140D01*
X1776930Y179830D01*
Y179051D01*
G01X1772000Y766870D02*
X1767450D01*
G01X1772000Y763524D02*
X1767450D01*
G01X1781740Y44370D02*
Y48051D01*
X1783700Y50011D01*
G01X1781740Y32756D02*
Y35182D01*
X1784106Y37548D01*
X1787826D01*
G01X1790738Y70987D02*
Y74912D01*
G01D02*
X1788250D01*
X1788204Y74958D01*
G01X1785108Y76078D02*
Y73467D01*
X1787588Y70987D01*
G01X1790738Y85442D02*
X1788020D01*
X1787756Y85178D01*
G01X1783454Y81613D02*
X1784191D01*
X1787756Y85178D01*
G01X1781485Y85550D02*
Y88204D01*
X1781451Y88238D01*
G01D02*
Y92275D01*
X1782103Y92927D01*
G01X1785108Y76078D02*
Y77990D01*
X1783454Y79644D01*
G01X1782061Y100939D02*
Y96969D01*
X1782103Y96927D01*
G01D02*
Y92927D01*
G01X1792965Y146834D02*
X1797143D01*
X1797692Y146285D01*
G01X1784133Y155735D02*
Y147567D01*
X1788950Y142750D01*
G01X1784133Y162824D02*
X1781368D01*
G01X1789815Y156834D02*
X1787390D01*
G01X1792965D02*
X1797765D01*
G01X1792965Y165834D02*
Y161834D01*
G01D02*
X1797765D01*
G01X1792965Y151834D02*
X1797765D01*
G01X1789815Y165834D02*
X1787390D01*
G01X1784133Y165974D02*
X1785864Y167705D01*
X1791094D01*
X1792965Y165834D01*
G01X1781650Y190799D02*
X1783047D01*
X1785320Y193072D01*
G01D02*
X1786409Y194161D01*
X1787993D01*
G01X1781650Y186911D02*
X1781558Y187003D01*
Y188605D01*
X1781559Y188606D01*
Y190708D01*
X1781650Y190799D01*
G01X1792196Y367866D02*
Y390411D01*
G01Y367866D02*
X1789771D01*
G01X1795346Y372732D02*
Y367866D01*
G01X1805069Y371171D02*
X1803481D01*
X1800570Y374082D01*
X1796696D01*
X1795346Y372732D01*
G01X1800212Y390411D02*
X1795346D01*
G01X1792335Y418775D02*
X1788031D01*
X1787874Y418932D01*
G01X1798168Y418775D02*
X1792335D01*
G01X1792450Y410615D02*
X1788057D01*
X1787874Y410432D01*
G01X1798179Y410615D02*
X1792450D01*
G01X1792507Y403932D02*
X1796614D01*
X1798179Y405497D01*
G01X1787874Y403932D02*
X1792507D01*
G01X1792220Y425432D02*
X1796629D01*
X1798168Y423893D01*
G01X1787874Y425432D02*
X1792220D01*
G01X1788142Y766870D02*
X1792692D01*
G01X1788142Y770217D02*
X1792692D01*
G01X1797692Y146285D02*
Y146761D01*
X1800206Y149275D01*
X1802800D01*
G01X1810280Y146716D02*
X1814315D01*
X1815315Y145716D01*
G01X1797765Y156834D02*
X1798619D01*
X1801042Y154411D01*
X1828346D01*
X1831368Y157433D01*
Y163608D01*
X1832153Y164393D01*
X1835116D01*
G01X1810045D02*
Y161834D01*
G01Y164393D02*
X1812351D01*
X1814905Y166947D01*
G01X1802565Y161834D02*
X1797765D01*
G01X1802565Y159275D02*
Y156557D01*
G01X1802800Y151834D02*
X1797765D01*
G01X1811711Y180619D02*
Y180962D01*
X1810742Y181931D01*
X1808574Y187165D01*
Y193128D01*
X1807541Y194161D01*
X1806497D01*
G01X1800160Y362542D02*
X1800180Y362562D01*
Y367112D01*
X1801680Y368612D01*
X1805069D01*
G01X1797929Y385293D02*
X1800488Y387852D01*
X1805629D01*
G01Y390411D02*
X1800212D01*
G01X1805648Y418775D02*
Y412232D01*
X1805659Y412221D01*
Y410615D01*
G01X1805648Y418775D02*
X1803497D01*
X1802904Y419368D01*
Y422868D01*
X1803929Y423893D01*
X1805648D01*
G01X1805659Y410615D02*
X1804151D01*
X1802904Y409368D01*
Y406368D01*
X1803775Y405497D01*
X1805659D01*
G01X1815724Y427432D02*
X1810924D01*
G01D02*
X1809187D01*
X1805648Y423893D01*
G01X1822005Y151834D02*
Y147834D01*
G01D02*
X1819887Y145716D01*
X1815315D01*
G01X1825155Y147834D02*
X1829014D01*
X1831166Y149986D01*
G01X1819705Y156797D02*
X1814905D01*
G01X1819705D02*
X1825158D01*
X1827636Y159275D01*
G01X1819705Y166947D02*
X1814905D01*
G01X1811711Y177469D02*
X1816600D01*
X1818828Y175241D01*
G01X1817275Y180619D02*
X1811711D01*
G01X1818274Y366053D02*
X1813104D01*
X1813103Y366052D01*
X1812549Y366053D01*
G01X1818274D02*
X1822851D01*
X1824157Y367359D01*
G01Y371329D02*
Y367359D01*
G01X1813109Y385293D02*
X1818274D01*
G01D02*
X1819615Y383952D01*
X1823094D01*
G01X1818874Y427432D02*
X1822724D01*
G01D02*
Y424948D01*
G01X1815717Y431678D02*
X1815724Y431671D01*
Y427432D01*
G01X1818867Y431678D02*
X1822717D01*
G01X1822394Y436225D02*
X1822717Y435902D01*
Y431678D01*
G01X1827636Y161834D02*
Y159275D01*
G01X1835116Y161834D02*
X1839916D01*
G01X1844716D02*
X1839916D01*
G01X1827307Y371329D02*
X1829732D01*
G01X1826244Y379552D02*
X1828669D01*
G01X1826231Y388051D02*
Y383965D01*
X1826244Y383952D01*
G01Y379552D02*
Y383952D01*
G01X1844716Y165834D02*
Y161834D01*
G01X1844686Y170287D02*
X1844716Y170257D01*
Y165834D01*
G01X1847836Y170287D02*
X1850791D01*
G01X1869706Y1709011D02*
Y1414433D01*
X1868702Y1413429D01*
X1860650D01*
X1859706Y1414373D01*
Y1709011D01*
G54D332*
G01X20587Y523970D02*
X21272Y523285D01*
X33184D01*
G01X16342Y516951D02*
X18757D01*
G01X20587Y528851D02*
Y528693D01*
G01X16512Y533155D02*
Y525475D01*
X18017Y523970D01*
X20587D01*
G01X16512Y533155D02*
Y540445D01*
X17872Y541805D01*
X26887D01*
G01X20587Y528693D02*
Y523970D01*
G01X39410Y384582D02*
X39015Y384977D01*
X36595D01*
G01X29962Y401000D02*
X32910D01*
G01X36524Y395346D02*
Y398013D01*
G01Y395346D02*
X39226D01*
G01X33184Y523285D02*
X32774Y523695D01*
Y525795D01*
G01X26887Y537197D02*
Y537355D01*
G01X32847Y537615D02*
X33257Y538025D01*
Y540370D01*
G01X26887Y537355D02*
Y541805D01*
G01X33257Y540370D02*
X31822Y541805D01*
X26887D01*
G01X33257Y540370D02*
X33217D01*
G01X48172Y538879D02*
X43196Y543855D01*
X36742D01*
X33257Y540370D01*
G01X42809Y363337D02*
Y360862D01*
G01X46834Y363337D02*
Y360862D01*
G01X52052Y1684027D02*
Y1681489D01*
G01X55190Y363337D02*
Y360862D01*
G01X57032Y423746D02*
X56874Y423588D01*
Y419316D01*
X56163Y418605D01*
Y417078D01*
G01X53825Y421746D02*
Y422225D01*
X55346Y423746D01*
X57032D01*
G01X66127Y1687362D02*
Y1684962D01*
G01X62202Y1684579D02*
Y1682016D01*
G01X73015Y28406D02*
Y28409D01*
X73020Y28414D01*
Y32756D01*
G01X80101Y28406D02*
Y28409D01*
X80106Y28414D01*
Y32756D01*
G01X73020D02*
X73025Y37106D01*
G01X80106Y32756D02*
X80111Y37106D01*
G01X73020Y44370D02*
X73015Y40020D01*
G01X73025Y48720D02*
Y48717D01*
X73020Y48712D01*
Y44370D01*
G01X80106D02*
X80101Y40020D01*
G01X80111Y48720D02*
Y48717D01*
X80106Y48712D01*
Y44370D01*
G01X68683Y423746D02*
X68592Y423655D01*
Y420218D01*
X69523Y419287D01*
Y417078D01*
G01X71772Y421746D02*
X69772Y423746D01*
X68683D01*
G01X78127Y1687362D02*
Y1684962D01*
G01X74127Y1687362D02*
Y1684962D01*
G01X70127Y1687362D02*
Y1684962D01*
G01X94274Y28406D02*
Y28409D01*
X94279Y28414D01*
Y32756D01*
G01X87188Y28406D02*
Y28409D01*
X87193Y28414D01*
Y32756D01*
G01X94279D02*
Y37101D01*
X94284Y37106D01*
G01X87193Y32756D02*
Y37101D01*
X87198Y37106D01*
G01Y48720D02*
Y48717D01*
X87193Y48712D01*
Y44370D01*
G01D02*
X87188Y40020D01*
G01X94279Y44370D02*
Y40025D01*
X94274Y40020D01*
G01X94284Y48720D02*
Y48717D01*
X94279Y48712D01*
Y44370D01*
G01X84966Y376026D02*
X87654D01*
G01X84949Y386502D02*
X87520D01*
G01X86127Y1687362D02*
Y1684962D01*
G01X82127Y1687362D02*
Y1684962D01*
G01X90127Y1687362D02*
Y1684962D01*
G01X92192Y1716241D02*
Y1713741D01*
G01X108448Y28406D02*
Y28409D01*
X108453Y28414D01*
Y32756D01*
G01X101361Y28406D02*
Y28409D01*
X101366Y28414D01*
Y32756D01*
G01X108453D02*
Y37101D01*
X108458Y37106D01*
G01X101366Y32756D02*
Y37101D01*
X101371Y37106D01*
G01X101366Y44370D02*
Y40025D01*
X101361Y40020D01*
G01X101371Y48720D02*
Y48717D01*
X101366Y48712D01*
Y44370D01*
G01X108453D02*
Y40025D01*
X108448Y40020D01*
G01X108458Y48720D02*
Y48717D01*
X108453Y48712D01*
Y44370D01*
G01X104829Y153691D02*
Y151191D01*
G01X106448Y1696436D02*
X104057Y1698827D01*
X102529D01*
G01X122621Y28406D02*
Y28409D01*
X122626Y28414D01*
Y32756D01*
G01X115534Y28406D02*
Y28409D01*
X115539Y28414D01*
Y32756D01*
G01X122626D02*
Y37101D01*
X122631Y37106D01*
G01X115539Y32756D02*
Y37101D01*
X115544Y37106D01*
G01X115539Y44370D02*
Y40025D01*
X115534Y40020D01*
G01X115544Y48720D02*
Y48717D01*
X115539Y48712D01*
Y44370D01*
G01X122626D02*
Y40025D01*
X122621Y40020D01*
G01X122631Y48720D02*
Y48717D01*
X122626Y48712D01*
Y44370D01*
G01X116353Y1646612D02*
Y1649012D01*
G01X120353Y1646612D02*
Y1649012D01*
G01X124353Y1646612D02*
Y1649012D01*
G01X123278Y1658587D02*
Y1661087D01*
G01X115353Y1695941D02*
Y1693541D01*
G01X119353Y1695941D02*
Y1693541D01*
G01X120161Y1726116D02*
X124461D01*
G01X129708Y28406D02*
Y28409D01*
X129713Y28414D01*
Y32756D01*
G01D02*
Y37101D01*
X129718Y37106D01*
G01X129713Y44370D02*
Y40025D01*
X129708Y40020D01*
G01X129718Y48720D02*
Y48717D01*
X129713Y48712D01*
Y44370D01*
G01X128353Y1646612D02*
Y1649012D01*
G01X140353Y1646612D02*
Y1649012D01*
G01X131353Y1696062D02*
Y1693662D01*
G01X135353Y1696062D02*
Y1693662D01*
G01X139353Y1696062D02*
Y1693662D01*
G01X132643Y1709346D02*
Y1711846D01*
G01X151400Y28406D02*
Y28409D01*
X151405Y28414D01*
Y32756D01*
G01D02*
Y37101D01*
X151410Y37106D01*
G01X151405Y44370D02*
Y40025D01*
X151400Y40020D01*
G01X151410Y48720D02*
Y48717D01*
X151405Y48712D01*
Y44370D01*
G01X146982Y526997D02*
X144567D01*
G01X146982Y530997D02*
X144567D01*
G01X149672Y668361D02*
Y665500D01*
G01X152822Y668361D02*
Y665500D01*
G01X152705Y673782D02*
Y668478D01*
X152822Y668361D01*
G01X152705Y680396D02*
Y683218D01*
G01X148353Y1646612D02*
Y1649012D01*
G01X144253D02*
Y1646712D01*
X144353Y1646612D01*
G01X155328Y1670087D02*
X152928D01*
G01X146928Y1685087D02*
Y1682587D01*
G01X143353Y1696062D02*
Y1693662D01*
G01X158487Y28406D02*
Y28409D01*
X158492Y28414D01*
Y32756D01*
G01X165574Y28406D02*
Y28409D01*
X165579Y28414D01*
Y32756D01*
G01X158492D02*
Y37101D01*
X158497Y37106D01*
G01X165579Y32756D02*
Y37101D01*
X165584Y37106D01*
G01X158492Y44370D02*
Y40025D01*
X158487Y40020D01*
G01X158497Y48720D02*
Y48717D01*
X158492Y48712D01*
Y44370D01*
G01X165579D02*
Y40025D01*
X165574Y40020D01*
G01X165584Y48720D02*
Y48717D01*
X165579Y48712D01*
Y44370D01*
G01X172660Y28406D02*
Y28409D01*
X172665Y28414D01*
Y32756D01*
G01X179747Y28406D02*
Y28409D01*
X179752Y28414D01*
Y32756D01*
G01X172665D02*
Y37101D01*
X172670Y37106D01*
G01X179752Y32756D02*
Y37101D01*
X179757Y37106D01*
G01X172670Y48720D02*
Y48717D01*
X172665Y48712D01*
Y44370D01*
G01D02*
X172660Y44365D01*
Y40020D01*
G01X179752Y44370D02*
Y40025D01*
X179747Y40020D01*
G01X179757Y48720D02*
Y48717D01*
X179752Y48712D01*
Y44370D01*
G01X195534Y28406D02*
Y28409D01*
X195539Y28414D01*
Y32756D01*
G01D02*
Y37101D01*
X195544Y37106D01*
G01X195539Y44370D02*
Y40025D01*
X195534Y40020D01*
G01X195544Y48720D02*
Y48717D01*
X195539Y48712D01*
Y44370D01*
G01X202621Y28406D02*
Y28409D01*
X202626Y28414D01*
Y32756D01*
G01X209708Y28406D02*
Y28409D01*
X209713Y28414D01*
Y32756D01*
G01X202626D02*
Y37101D01*
X202631Y37106D01*
G01X209713Y32756D02*
Y37101D01*
X209718Y37106D01*
G01X202626Y44370D02*
Y40025D01*
X202621Y40020D01*
G01X202631Y48720D02*
Y48717D01*
X202626Y48712D01*
Y44370D01*
G01X209713D02*
Y40025D01*
X209708Y40020D01*
G01X209718Y48720D02*
Y48717D01*
X209713Y48712D01*
Y44370D01*
G01X216794Y28406D02*
Y28409D01*
X216799Y28414D01*
Y32756D01*
G01X223881Y28406D02*
Y28409D01*
X223886Y28414D01*
Y32756D01*
G01X230967Y28406D02*
Y28409D01*
X230972Y28414D01*
Y32756D01*
G01X216799D02*
Y37101D01*
X216804Y37106D01*
G01X223886Y32756D02*
Y37101D01*
X223891Y37106D01*
G01X230972Y32756D02*
Y37101D01*
X230977Y37106D01*
G01X216799Y44370D02*
Y40025D01*
X216794Y40020D01*
G01X216804Y48720D02*
Y48717D01*
X216799Y48712D01*
Y44370D01*
G01X223891Y48720D02*
Y48717D01*
X223886Y48712D01*
Y44370D01*
G01D02*
Y40025D01*
X223881Y40020D01*
G01X230977Y48720D02*
Y48717D01*
X230972Y48712D01*
Y44370D01*
G01D02*
Y40025D01*
X230967Y40020D01*
G01X242215Y149438D02*
Y151788D01*
G01X249695Y144320D02*
X252195D01*
G01X249735Y155044D02*
Y152694D01*
G01X271881Y74536D02*
X271655D01*
X269860Y72741D01*
G01X278984Y32756D02*
Y28414D01*
X278979Y28409D01*
Y28406D01*
G01X286071Y32756D02*
Y28414D01*
X286066Y28409D01*
Y28406D01*
G01X278984Y44370D02*
Y48712D01*
X278989Y48717D01*
Y48720D01*
G01X286071Y44370D02*
Y48712D01*
X286076Y48717D01*
Y48720D01*
G01X299628Y151703D02*
Y149203D01*
G01X334339Y165170D02*
Y171170D01*
G01X329221Y178610D02*
Y181093D01*
X327459Y182855D01*
X326475D01*
G01X328375Y552397D02*
Y548621D01*
X328966Y548030D01*
G01X347673Y122525D02*
X343036D01*
G01X370999Y135157D02*
X366874D01*
G01X366771Y130165D02*
Y127665D01*
G01X375920Y149077D02*
Y146577D01*
G01X389568Y142937D02*
Y145585D01*
X387712Y147441D01*
G01X391635Y157936D02*
Y161091D01*
G01X487590Y105969D02*
X485440D01*
X483020Y108389D01*
Y118813D01*
X485526Y121319D01*
X492230D01*
X492300Y121389D01*
G01X498385Y108124D02*
X496965D01*
X494810Y105969D01*
G01D02*
X487590D01*
G01X498314Y118493D02*
Y120365D01*
X497290Y121389D01*
X492300D01*
G01X501675Y108124D02*
X498385D01*
G01X510815Y53543D02*
Y49201D01*
X510810Y49196D01*
Y49193D01*
G01X510815Y65157D02*
Y69562D01*
G01X501675Y108124D02*
X502815Y106984D01*
G01X517902Y53543D02*
Y49199D01*
X517896Y49193D01*
G01X524988Y53543D02*
Y49414D01*
X524763Y49189D01*
G01X517902Y65157D02*
X517907Y65162D01*
Y69507D01*
G01X524988Y65157D02*
Y69499D01*
X524993Y69504D01*
Y69507D01*
G01X532075Y65157D02*
Y69499D01*
X532080Y69504D01*
Y69507D01*
G01X539161Y65157D02*
X539166Y65162D01*
Y69507D01*
G01X546248Y65157D02*
X546253Y65162D01*
Y69507D01*
G01X553335Y65157D02*
X553340Y65162D01*
Y69507D01*
G01X560421Y65157D02*
X560426Y65162D01*
Y69507D01*
G01X565908Y387227D02*
X562208D01*
G01X565908Y376427D02*
X562208D01*
G01X573782Y387227D02*
X579385D01*
G01Y376427D02*
X573782D01*
G01X565908Y401158D02*
X562208D01*
G01X573782D02*
X579385D01*
G01X595203Y175534D02*
X592757D01*
X590166Y178125D01*
X588194D01*
G01X595203Y172975D02*
X590194D01*
X588194Y174975D01*
G01X593925Y53543D02*
X593920Y53538D01*
Y49193D01*
G01X603374Y65157D02*
X603379Y65162D01*
Y70512D01*
G01X595203Y175534D02*
X599678D01*
G01X601908Y387227D02*
X598208D01*
G01X601908Y376427D02*
X598208D01*
G01X594848Y432209D02*
X599164D01*
G01X615185Y53543D02*
X615180Y53538D01*
Y49193D01*
G01X615185Y65157D02*
X615190Y65162D01*
Y70533D01*
G01X609782Y387227D02*
X615385D01*
G01Y376427D02*
X609782D01*
G01X610725Y406846D02*
X615385D01*
G01X645146Y65157D02*
X644970Y65333D01*
Y69326D01*
X645151Y69507D01*
G01X646146Y184862D02*
X642481D01*
G01X654595Y53543D02*
X654590Y53538D01*
Y49193D01*
G01X661681Y53543D02*
X661676Y53538D01*
Y49193D01*
G01X675854Y53543D02*
Y49198D01*
X675849Y49193D01*
G01X668768Y53543D02*
Y49201D01*
X668763Y49196D01*
Y49193D01*
G01X666406Y65157D02*
X666140Y65423D01*
Y69236D01*
X666411Y69507D01*
G01X682941Y65157D02*
Y69977D01*
X682946Y69982D01*
G01X682264Y224116D02*
X684132Y225984D01*
X694226D01*
G01X702035Y1564523D02*
Y1568523D01*
G01X702065Y1560573D02*
Y1564493D01*
X702035Y1564523D01*
G01Y1568523D02*
X699610D01*
G01X702035Y1572523D02*
X699610D01*
G01X702035Y1576523D02*
X699610D01*
G01X705185Y1580523D02*
X706374D01*
X707554Y1579343D01*
X711978D01*
X714110Y1581475D01*
G01X723866Y53543D02*
X723861Y53538D01*
Y50462D01*
X722581Y49182D01*
G01X714474Y1566333D02*
X717175D01*
G01X723050Y1602508D02*
X722146Y1603412D01*
Y1607469D01*
X723408Y1608731D01*
Y1608740D01*
G01X725286Y1610743D02*
X724686Y1611343D01*
X722876D01*
G01X738039Y65157D02*
X738044Y65162D01*
Y71526D01*
G01X730953Y65157D02*
X730958Y65162D01*
Y71014D01*
G01X723436Y648667D02*
X726952D01*
G01X745126Y53543D02*
Y49200D01*
X744988Y49062D01*
G01X747488Y53543D02*
Y49062D01*
G01X745126Y65157D02*
X745131Y65162D01*
Y69507D01*
G01X761245Y172636D02*
X758111D01*
G01X756691Y269322D02*
X754291D01*
G01X756691Y265322D02*
X755283D01*
X754286Y266319D01*
G01X756692Y276322D02*
Y278942D01*
G01X770450Y1584108D02*
X767750D01*
G01X755185Y1589023D02*
X757610D01*
G01X774485Y286879D02*
Y285116D01*
X773766Y284397D01*
G01X780618Y299279D02*
Y296345D01*
G01X773944Y312588D02*
X772867Y311511D01*
Y308755D01*
G01D02*
X772952Y308670D01*
Y303410D01*
G01X804575Y1578633D02*
X802150D01*
G01X810850Y1587733D02*
Y1586908D01*
X812750Y1585008D01*
G01X821588Y486496D02*
X818162D01*
X817426Y487232D01*
G01X836127Y62681D02*
X834537Y61091D01*
Y58632D01*
G01X834616Y94324D02*
Y88362D01*
X837792Y85186D01*
G01X840037Y81448D02*
Y78231D01*
X841427Y76841D01*
X849356D01*
X853498Y80983D01*
Y90622D01*
X854108Y91232D01*
G01X840037Y81448D02*
Y82941D01*
X837792Y85186D01*
G01X831298Y104206D02*
X834616D01*
G01D02*
Y94324D01*
G01X833715Y228143D02*
X830340D01*
G01X854108Y91232D02*
X854578Y91702D01*
Y99651D01*
G01D02*
Y109305D01*
X853587Y110296D01*
X842865D01*
G01X846575Y1578633D02*
X844150D01*
G01X852850Y1587733D02*
Y1586908D01*
X854750Y1585008D01*
G01X859688Y176332D02*
X863488D01*
G01X881150Y192055D02*
X878221D01*
G01X888575Y1578633D02*
X886150D01*
G01X894850Y1587733D02*
Y1586908D01*
X896750Y1585008D01*
G01X906597Y582412D02*
Y579695D01*
G01X916889Y582573D02*
X913943D01*
X913750Y582380D01*
X909779D01*
X909747Y582412D01*
G01D02*
Y579695D01*
G01X931348Y267222D02*
X925468D01*
G01X931455Y590251D02*
X935149D01*
X935649Y590751D01*
G01X938788Y272340D02*
X942763D01*
G01X997689Y293075D02*
X995383D01*
X992915Y290607D01*
Y280389D01*
G01X1011189Y488642D02*
X1008789D01*
G01X1008631Y517146D02*
X1012306D01*
X1013306Y518146D01*
G01X1008631Y514587D02*
Y510304D01*
G01Y529942D02*
X1012306D01*
X1013306Y528942D01*
G01X1027760Y451832D02*
Y454651D01*
X1028353Y455244D01*
X1029035D01*
G01X1040425Y427059D02*
X1045100D01*
G01X1062473D02*
X1057798D01*
G01X1062473Y429618D02*
X1057798D01*
G01X1069236Y393882D02*
X1080552D01*
X1081865Y395195D01*
X1083583D01*
G01X1086936Y373187D02*
Y370532D01*
G01X1097111Y378028D02*
X1093265D01*
X1091917Y376680D01*
Y375018D01*
X1090086Y373187D01*
G01D02*
Y370417D01*
G01X1101942Y395361D02*
Y391852D01*
X1100914Y390824D01*
X1097111D01*
G01X1113943Y452055D02*
Y453555D01*
X1115632Y455244D01*
X1118614D01*
G01X1148486Y53186D02*
X1142830D01*
G01X1147813Y489819D02*
Y492319D01*
G01X1146467Y1682412D02*
X1142033D01*
G01X1158936Y73939D02*
X1155577D01*
G01X1160713Y481691D02*
X1163113D01*
G01X1195962Y57015D02*
X1198694D01*
G01X1195882Y52815D02*
Y56935D01*
X1195962Y57015D01*
G01X1202437Y164987D02*
X1200037D01*
G01X1202437Y160987D02*
X1200037D01*
G01X1192127Y164987D02*
X1189727D01*
G01X1192127Y160987D02*
X1189727D01*
G01X1192127Y177187D02*
X1189727D01*
G01X1192127Y173187D02*
X1189701D01*
G01X1188352Y460202D02*
X1185707D01*
G01X1188412Y465272D02*
X1185707D01*
G01X1188472Y470392D02*
X1185707D01*
G01X1213866Y455376D02*
X1217866D01*
G01X1220178Y172395D02*
X1215528D01*
G01X1241618Y128239D02*
X1239218D01*
G01X1241618Y132739D02*
X1239218D01*
G01X1241618Y123739D02*
X1239218D01*
G01X1241618Y137239D02*
X1239218D01*
G01X1231118Y145239D02*
Y142125D01*
G01X1259835Y140053D02*
X1255185D01*
G01X1259835Y142553D02*
X1255185D01*
G01X1259835Y137553D02*
X1255175D01*
G01X1248902Y468152D02*
Y470733D01*
G01X1257016Y467253D02*
X1258022Y466247D01*
Y464372D01*
G01X1261182Y164051D02*
X1263582D01*
G01X1261182Y155730D02*
Y160051D01*
G01D02*
X1263582D01*
G01X1261182Y180551D02*
X1263582D01*
G01X1261182Y176051D02*
X1263582D01*
G01X1261182Y172051D02*
X1263582D01*
G01X1261182Y168051D02*
X1263582D01*
G01X1261182Y185051D02*
X1263582D01*
G01X1275686Y150030D02*
X1278111D01*
G01X1280741Y142553D02*
X1285391D01*
G01X1298268Y125739D02*
X1300668D01*
G01Y133739D02*
X1300477Y133548D01*
X1298459D01*
X1298268Y133739D01*
G01Y129739D02*
X1300668D01*
G01X1298268Y145739D02*
X1300668D01*
G01X1289682Y162051D02*
X1292082D01*
G01X1301743Y162055D02*
X1299186D01*
X1299182Y162051D01*
G01X1289682Y166051D02*
X1292082D01*
G01X1289682Y171551D02*
X1292082D01*
G01X1299182Y166051D02*
X1301582D01*
G01X1299182Y171551D02*
X1301582D01*
G01X1289682Y184051D02*
X1292082D01*
G01X1299182D02*
X1301582D01*
G01X1293277Y403625D02*
Y401125D01*
G01X1438312Y156866D02*
Y152166D01*
G01X1440871Y134818D02*
Y130118D01*
G01X1453667Y134818D02*
Y130242D01*
X1455667Y128242D01*
G01X1440871Y156866D02*
Y152166D01*
G01X1456226Y134818D02*
Y137837D01*
X1457907Y139518D01*
X1460508D01*
G01X1453667Y156866D02*
Y152166D01*
G01X1456226Y156866D02*
Y152166D01*
G01X1469652Y1679401D02*
X1466599D01*
G01X1542675Y555215D02*
Y561990D01*
X1542697Y562012D01*
G01X1554510Y28406D02*
Y28409D01*
X1554515Y28414D01*
Y32756D01*
G01X1547424Y28406D02*
Y28409D01*
X1547429Y28414D01*
Y32756D01*
G01X1554515D02*
X1554520Y37106D01*
G01X1547429Y32756D02*
X1547434Y37106D01*
G01X1554520Y48720D02*
Y48717D01*
X1554515Y48712D01*
Y44370D01*
G01D02*
X1554510Y40020D01*
G01X1547429Y44370D02*
X1547424Y40020D01*
G01X1547434Y48720D02*
Y48717D01*
X1547429Y48712D01*
Y44370D01*
G01X1557559Y1269095D02*
X1558887Y1270423D01*
Y1272403D01*
X1558077Y1273213D01*
G01X1550252Y1270188D02*
X1552352D01*
X1552852Y1269688D01*
X1554692D01*
G01X1558077Y1273213D02*
X1554377D01*
G01X1550252Y1274188D02*
Y1278188D01*
G01X1554377Y1273213D02*
X1553385D01*
X1552410Y1274188D01*
X1550252D01*
G01X1561597Y28406D02*
Y28409D01*
X1561602Y28414D01*
Y32756D01*
G01X1568683Y28406D02*
Y28409D01*
X1568688Y28414D01*
Y32756D01*
G01X1561602D02*
Y37101D01*
X1561607Y37106D01*
G01X1568688Y32756D02*
Y37101D01*
X1568693Y37106D01*
G01Y48720D02*
Y48717D01*
X1568688Y48712D01*
Y44370D01*
G01D02*
Y40025D01*
X1568683Y40020D01*
G01X1561602Y44370D02*
X1561597Y40020D01*
G01X1561607Y48720D02*
Y48717D01*
X1561602Y48712D01*
Y44370D01*
G01X1569592Y297316D02*
Y294816D01*
G01X1575770Y28406D02*
Y28409D01*
X1575775Y28414D01*
Y32756D01*
G01X1582857Y28406D02*
Y28409D01*
X1582862Y28414D01*
Y32756D01*
G01X1575775D02*
Y37101D01*
X1575780Y37106D01*
G01X1582862Y32756D02*
Y37101D01*
X1582867Y37106D01*
G01Y48720D02*
Y48717D01*
X1582862Y48712D01*
Y44370D01*
G01D02*
Y40025D01*
X1582857Y40020D01*
G01X1575780Y48720D02*
Y48717D01*
X1575775Y48712D01*
Y44370D01*
G01D02*
Y40025D01*
X1575770Y40020D01*
G01X1583177Y1265363D02*
X1587177D01*
G01D02*
X1591177D01*
G01X1581697Y1298278D02*
Y1297647D01*
X1580150Y1296100D01*
X1580010D01*
G01X1589943Y28406D02*
Y28409D01*
X1589948Y28414D01*
Y32756D01*
G01X1597030Y28406D02*
Y28409D01*
X1597035Y28414D01*
Y32756D01*
G01X1589948D02*
Y37101D01*
X1589953Y37106D01*
G01X1597035Y32756D02*
Y37101D01*
X1597040Y37106D01*
G01Y48720D02*
Y48717D01*
X1597035Y48712D01*
Y44370D01*
G01D02*
Y40025D01*
X1597030Y40020D01*
G01X1589953Y48720D02*
Y48717D01*
X1589948Y48712D01*
Y44370D01*
G01D02*
Y40025D01*
X1589943Y40020D01*
G01X1594152Y1282578D02*
Y1281388D01*
X1591752Y1278988D01*
G01X1604117Y28406D02*
Y28409D01*
X1604122Y28414D01*
Y32756D01*
G01D02*
Y37101D01*
X1604127Y37106D01*
G01Y48720D02*
Y48717D01*
X1604122Y48712D01*
Y44370D01*
G01D02*
Y40025D01*
X1604117Y40020D01*
G01X1616769Y552404D02*
X1615513D01*
X1613357Y550248D01*
G01X1610373Y554664D02*
X1607902D01*
X1606535Y553297D01*
G01X1613357Y550248D02*
X1610373Y553232D01*
Y554664D01*
G01X1625809Y28406D02*
Y28409D01*
X1625814Y28414D01*
Y32756D01*
G01D02*
Y37101D01*
X1625819Y37106D01*
G01Y48720D02*
Y48717D01*
X1625814Y48712D01*
Y44370D01*
G01D02*
Y40025D01*
X1625809Y40020D01*
G01X1618884Y530739D02*
Y533388D01*
G01X1629653Y1432248D02*
Y1436148D01*
G01X1627174Y1420450D02*
X1629674D01*
G01X1629628Y1428366D02*
X1627217D01*
G01X1629653Y1436148D02*
X1627242D01*
G01X1629592Y1440016D02*
X1629452Y1439876D01*
X1626158Y1438511D01*
X1624219Y1436572D01*
Y1434450D01*
X1625285Y1433384D01*
G01X1629592Y1448016D02*
X1627181D01*
G01X1632896Y28406D02*
Y28409D01*
X1632901Y28414D01*
Y32756D01*
G01X1647069Y28406D02*
Y28409D01*
X1647074Y28414D01*
Y32756D01*
G01X1639983Y28406D02*
Y28409D01*
X1639988Y28414D01*
Y32756D01*
G01X1632901D02*
Y37101D01*
X1632906Y37106D01*
G01X1647074Y32756D02*
Y37101D01*
X1647079Y37106D01*
G01X1639988Y32756D02*
Y37101D01*
X1639993Y37106D01*
G01X1632906Y48720D02*
Y48717D01*
X1632901Y48712D01*
Y44370D01*
G01D02*
Y40025D01*
X1632896Y40020D01*
G01X1647074Y44370D02*
X1647069Y44365D01*
Y40020D01*
G01X1647079Y48720D02*
Y48717D01*
X1647074Y48712D01*
Y44370D01*
G01X1639993Y48720D02*
Y48717D01*
X1639988Y48712D01*
Y44370D01*
G01D02*
Y40025D01*
X1639983Y40020D01*
G01X1644535Y414202D02*
X1642135D01*
G01X1646510Y431619D02*
Y433577D01*
X1647110Y434177D01*
G01X1645155Y1394395D02*
X1642810D01*
X1641087Y1396118D01*
G01X1654156Y28406D02*
Y28409D01*
X1654161Y28414D01*
Y32756D01*
G01D02*
Y37101D01*
X1654166Y37106D01*
G01Y48720D02*
Y48717D01*
X1654161Y48712D01*
Y44370D01*
G01D02*
Y40025D01*
X1654156Y40020D01*
G01X1661110Y431777D02*
Y434177D01*
G01X1657284Y1403041D02*
X1655196D01*
X1654774Y1402619D01*
G01X1649197Y1394343D02*
Y1396743D01*
G01X1653390Y1391260D02*
Y1388857D01*
G01X1658167Y1443316D02*
X1657757D01*
X1655957Y1445116D01*
G01D02*
X1654157Y1443316D01*
X1653667D01*
G01X1677030Y28406D02*
Y28409D01*
X1677035Y28414D01*
Y32756D01*
G01X1669943Y28406D02*
Y28409D01*
X1669948Y28414D01*
Y32756D01*
G01X1677035D02*
Y37101D01*
X1677040Y37106D01*
G01X1669948Y32756D02*
Y37101D01*
X1669953Y37106D01*
G01X1677040Y48720D02*
Y48717D01*
X1677035Y48712D01*
Y44370D01*
G01D02*
Y40025D01*
X1677030Y40020D01*
G01X1669953Y48720D02*
Y48717D01*
X1669948Y48712D01*
Y44370D01*
G01D02*
Y40025D01*
X1669943Y40020D01*
G01X1664329Y1402860D02*
X1666644D01*
X1666919Y1402585D01*
G01X1669385Y1416678D02*
X1672501D01*
G01X1672907Y1429928D02*
X1672157D01*
X1670574Y1428345D01*
X1669365D01*
G01D02*
Y1432181D01*
X1669331Y1432215D01*
G01X1669399Y1424483D02*
Y1420585D01*
X1669417Y1420567D01*
G01D02*
X1672273D01*
G01X1666290Y1441782D02*
Y1444391D01*
G01X1670147Y1441724D02*
Y1444311D01*
G01X1684117Y28406D02*
Y28409D01*
X1684122Y28414D01*
Y32756D01*
G01X1691203Y28406D02*
Y28409D01*
X1691208Y28414D01*
Y32756D01*
G01X1684122D02*
Y37101D01*
X1684127Y37106D01*
G01X1691208Y32756D02*
Y37101D01*
X1691213Y37106D01*
G01Y48720D02*
Y48717D01*
X1691208Y48712D01*
Y44370D01*
G01D02*
Y40025D01*
X1691203Y40020D01*
G01X1684127Y48720D02*
Y48717D01*
X1684122Y48712D01*
Y44370D01*
G01D02*
Y40025D01*
X1684117Y40020D01*
G01X1686172Y1386416D02*
Y1384010D01*
G01Y1388957D02*
Y1391360D01*
G01X1681000Y1433425D02*
X1683587D01*
G01X1681000Y1443075D02*
X1683741D01*
G01X1698290Y28406D02*
Y28409D01*
X1698295Y28414D01*
Y32756D01*
G01X1705376Y28406D02*
Y28409D01*
X1705381Y28414D01*
Y32756D01*
G01X1698295D02*
Y37101D01*
X1698300Y37106D01*
G01X1705381Y32756D02*
Y37108D01*
G01X1698295Y44370D02*
Y40025D01*
X1698290Y40020D01*
G01X1698300Y48720D02*
Y48717D01*
X1698295Y48712D01*
Y44370D01*
G01X1705381D02*
Y48712D01*
X1705386Y48717D01*
Y48720D01*
G01X1697111Y1402960D02*
X1699426D01*
X1699701Y1402685D01*
G01X1710886Y82208D02*
X1711798Y81296D01*
Y78842D01*
G01X1721400Y374462D02*
X1722500Y373362D01*
Y371937D01*
G01X1725400Y372062D02*
X1726094Y371368D01*
X1729480D01*
G01X1725500Y380937D02*
Y383662D01*
G01X1723259Y656238D02*
Y653641D01*
G01X1726409Y656238D02*
Y653641D01*
G01X1753393Y32756D02*
X1753388Y32751D01*
Y28406D01*
G01X1760480Y32756D02*
Y28414D01*
X1760475Y28409D01*
Y28406D01*
G01X1753393Y44370D02*
Y48712D01*
X1753398Y48717D01*
Y48720D01*
G01X1760480Y44370D02*
Y48712D01*
X1760485Y48717D01*
Y48720D01*
G01X1768002Y364148D02*
X1770520D01*
G01X1768002Y368148D02*
X1770520D01*
G01X1790738Y82292D02*
X1788250D01*
X1788204Y82338D01*
G01X1798179Y408056D02*
X1795479D01*
G01X1798168Y421334D02*
X1795468D01*
G01X1800511Y180569D02*
X1804111D01*
G01X1803129Y362293D02*
X1805069Y364233D01*
Y366053D01*
G01X1805629Y385293D02*
X1802929D01*
G01X1820307Y371329D02*
Y373829D01*
G01X1820144Y395552D02*
Y398052D01*
G01X1819374Y407932D02*
Y410432D01*
G01X1818874Y421432D02*
Y423932D01*
G54D23*
X21815Y516951D03*
X35968Y401000D03*
X51645Y1519335D03*
X41116Y1594396D03*
Y1607896D03*
Y1598896D03*
Y1603396D03*
Y1612896D03*
Y1617396D03*
X47410Y1668587D03*
Y1663587D03*
X48110Y1681645D03*
X60090Y423746D03*
X62110Y1682016D03*
X55110Y1681489D03*
X77234Y145191D03*
X77237Y149191D03*
Y153191D03*
X69708Y268223D03*
X76483Y1434000D03*
X82116Y1611896D03*
Y1625396D03*
Y1620896D03*
Y1616396D03*
X70116Y1630396D03*
X73650Y1634905D03*
X91984Y140950D03*
X84857Y382219D03*
Y391391D03*
Y395865D03*
X89983Y1417000D03*
Y1412500D03*
Y1408000D03*
Y1421500D03*
Y1435500D03*
X87388Y1519335D03*
X88679Y1549369D03*
X86179Y1544869D03*
X95250Y1716241D03*
X88403Y1706511D03*
X88240Y1716331D03*
X99541Y1353216D03*
X98983Y1426000D03*
Y1430500D03*
Y1440000D03*
Y1435500D03*
X107604Y1554069D03*
X106969Y1671361D03*
Y1667361D03*
Y1679564D03*
Y1675564D03*
X110483Y1712450D03*
X126336Y1661087D03*
X132141Y1353216D03*
X139903Y1701011D03*
X139801Y1705166D03*
X135750Y1718241D03*
X154683Y438810D03*
X144475Y521997D03*
Y530997D03*
Y534997D03*
X152730Y668361D03*
X143983Y1417500D03*
X147983Y1421500D03*
Y1425500D03*
X142750Y1726241D03*
Y1722241D03*
X171333Y395040D03*
X169349Y684799D03*
Y680799D03*
X164841Y1353216D03*
X158798Y1726500D03*
X177583Y416600D03*
X181463Y438270D03*
X179483Y672500D03*
Y676500D03*
X174983Y1711000D03*
Y1725000D03*
X195903Y140962D03*
X198619Y165325D03*
X197741Y1353216D03*
X200762Y1723000D03*
X201983Y1707000D03*
X225335Y144710D03*
X230541Y1353216D03*
X245203Y75862D03*
X237183Y142062D03*
X233503Y159071D03*
X235726Y715823D03*
X258883Y58400D03*
Y54400D03*
X257783Y73400D03*
X258883Y62400D03*
X260780Y87543D03*
X250280Y115743D03*
X270036Y151203D03*
Y147203D03*
X270086Y137302D03*
X272983Y211000D03*
X264983Y217500D03*
X263826Y583999D03*
X264141Y1307070D03*
X281939Y74536D03*
X278439Y78461D03*
X286783Y136962D03*
X279983Y215000D03*
X286774Y577698D03*
X283624Y574022D03*
X279909Y570398D03*
X286774Y581298D03*
X287450Y1342705D03*
X301149Y67128D03*
X305140Y91767D03*
X298910Y85983D03*
Y82483D03*
X297037Y1307042D03*
X320082Y95852D03*
X320086Y99837D03*
X317322Y227851D03*
Y231851D03*
X313483Y241000D03*
X311983Y263000D03*
X329129Y147120D03*
Y152120D03*
Y156120D03*
Y160120D03*
X329941Y1306985D03*
X346153Y229180D03*
X348640Y586415D03*
X341722Y702203D03*
X355416Y219343D03*
X356640Y582415D03*
Y578415D03*
X359040Y590415D03*
Y586415D03*
X362741Y1307185D03*
X378978Y149077D03*
X373946Y163173D03*
X377008Y235455D03*
X377038Y239615D03*
X365891Y294030D03*
X374782Y701935D03*
X384071Y287370D03*
X390640Y565915D03*
X390440Y571115D03*
X395323Y1326516D03*
X408624Y144300D03*
X405276Y157034D03*
Y152278D03*
X404483Y304000D03*
X402854Y555915D03*
Y561415D03*
X397088Y1611022D03*
Y1607022D03*
Y1603022D03*
Y1599022D03*
X408983Y1649500D03*
X422483Y54762D03*
X416184Y99148D03*
X417423Y226323D03*
Y230323D03*
Y240501D03*
X418198Y254165D03*
Y270165D03*
Y262165D03*
X418649Y1032304D03*
X422483Y1639000D03*
Y1634000D03*
X411983Y1641000D03*
X416983Y1649500D03*
Y1653500D03*
X434234Y1285694D03*
Y1289694D03*
X454282Y206620D03*
Y210620D03*
X454335Y283318D03*
X468482Y210620D03*
Y206620D03*
X468879Y222764D03*
Y235764D03*
Y243764D03*
X465639Y1013604D03*
Y1009864D03*
Y1006123D03*
Y1017344D03*
Y1024824D03*
Y1028564D03*
Y1021084D03*
Y1032304D03*
X467983Y1655500D03*
Y1672000D03*
X468483Y1701000D03*
Y1733500D03*
X483283Y288469D03*
X479288Y309809D03*
X475483Y1668000D03*
Y1659500D03*
Y1676000D03*
Y1697000D03*
Y1710500D03*
Y1733500D03*
X488866Y60105D03*
X489026Y55095D03*
X488756Y64965D03*
X492980Y167625D03*
X492165Y201516D03*
Y197516D03*
X497517Y233000D03*
Y243178D03*
X504259Y209285D03*
X500715Y197516D03*
X504259Y213285D03*
Y220166D03*
X514206Y280721D03*
X544679Y190256D03*
Y199256D03*
X541625Y292268D03*
X554319Y156667D03*
X546471Y222441D03*
Y235560D03*
X554421Y239566D03*
X546471Y226441D03*
X556156Y403586D03*
X548983Y459000D03*
X547220Y659489D03*
X570283Y297469D03*
X566288Y318809D03*
X561983Y473500D03*
X577486Y164356D03*
Y169415D03*
X581007Y257171D03*
X582943Y366827D03*
X586106Y415846D03*
Y427949D03*
X586125Y431976D03*
X574983Y454500D03*
X603252Y145640D03*
Y149640D03*
Y153640D03*
X594012Y213277D03*
X601206Y289721D03*
X596483Y445500D03*
Y449500D03*
X599981Y464349D03*
X593486Y474353D03*
X590654Y1266668D03*
Y1262668D03*
X603254Y1270598D03*
Y1278598D03*
Y1274598D03*
X605761Y157640D03*
X616265Y179720D03*
X608876Y260010D03*
X618943Y366827D03*
X618483Y418000D03*
X618374Y426901D03*
X630983Y427000D03*
X632486Y437881D03*
X633142Y461441D03*
X632892Y468856D03*
X622296Y1371182D03*
X622321Y1382864D03*
Y1378964D03*
X622296Y1375082D03*
X622260Y1390732D03*
X637592Y230975D03*
Y226975D03*
X645563Y401580D03*
X645507Y405449D03*
X645983Y433862D03*
Y437862D03*
Y442362D03*
Y453862D03*
Y449862D03*
X646107Y461853D03*
X645994Y457746D03*
X646124Y469863D03*
X645983Y488000D03*
X649204Y184862D03*
X651643Y307089D03*
X662483Y390000D03*
X649983Y418500D03*
X659483Y429862D03*
Y425862D03*
Y433862D03*
X649983Y422500D03*
X659483Y453862D03*
Y469862D03*
Y473862D03*
X649983Y519500D03*
X658705Y1363394D03*
X658737Y1367283D03*
X655683Y1687400D03*
X656283Y1708184D03*
Y1702400D03*
X667706Y363261D03*
X675483Y417862D03*
Y413362D03*
Y433862D03*
Y429862D03*
Y425862D03*
Y421862D03*
Y442362D03*
Y449862D03*
X675515Y486942D03*
X675772Y495084D03*
X668483Y533500D03*
X674083Y1312502D03*
X665483Y1712084D03*
X693703Y76962D03*
X683436Y119868D03*
X680788Y1635842D03*
Y1647842D03*
X693936Y91668D03*
X707097Y1371225D03*
X705093Y1564523D03*
X704983Y1556500D03*
X705093Y1576523D03*
Y1572523D03*
Y1568523D03*
Y1584523D03*
X704983Y1596500D03*
X705093Y1588523D03*
Y1592523D03*
X704983Y1604500D03*
X702211Y1623062D03*
X699822Y1681996D03*
X713204Y221862D03*
X716504Y1403571D03*
X720233Y1566333D03*
X732976Y86998D03*
X733486Y105468D03*
Y101968D03*
X727233Y1566333D03*
X728344Y1610743D03*
X728233Y1606733D03*
X741216Y111252D03*
X748728Y137864D03*
X751218Y161463D03*
X751483Y175500D03*
X739879Y1371325D03*
X749286Y1403671D03*
X754616Y115288D03*
X754618Y119172D03*
X757537Y228201D03*
X759749Y269322D03*
Y265322D03*
X766120Y1570633D03*
X755093Y1580023D03*
X766133Y1574733D03*
Y1578733D03*
Y1587733D03*
X777903Y163254D03*
X776010Y303410D03*
X775925Y308755D03*
X781983Y367500D03*
X779135Y415344D03*
X778135Y431344D03*
Y427344D03*
Y423344D03*
Y447344D03*
Y443344D03*
Y439344D03*
Y435344D03*
Y451344D03*
X791249Y274822D03*
X789110Y303410D03*
X789025Y308755D03*
X792483Y403000D03*
Y399000D03*
X792585Y419344D03*
X792483Y411500D03*
X792585Y431344D03*
Y427344D03*
Y423344D03*
X792635Y435344D03*
X792585Y443344D03*
X792635Y447344D03*
X808483Y392500D03*
X809518Y427344D03*
X809492Y435628D03*
X808392Y439628D03*
X809416Y459344D03*
Y455344D03*
X809483Y508000D03*
X807633Y1570633D03*
Y1578633D03*
Y1594633D03*
Y1582633D03*
Y1602633D03*
X815483Y392500D03*
X822983Y409500D03*
X823902Y427344D03*
Y431344D03*
Y443552D03*
X824029Y439279D03*
X823902Y435628D03*
Y449802D03*
Y459344D03*
X840309Y90451D03*
X842203Y129362D03*
Y135862D03*
X829983Y409500D03*
X840041Y435552D03*
Y439552D03*
Y443552D03*
Y459578D03*
Y455578D03*
Y463578D03*
X838483Y475000D03*
X851704Y135862D03*
Y129362D03*
X851483Y381000D03*
Y385000D03*
X855683Y401280D03*
X855745Y524413D03*
X849633Y1570633D03*
Y1578633D03*
Y1594633D03*
Y1582633D03*
Y1602633D03*
X868376Y223763D03*
X861075Y240441D03*
X868376Y227763D03*
X859286Y265057D03*
X859796Y283527D03*
Y280027D03*
X867526Y289311D03*
X861983Y391500D03*
X874203Y171362D03*
Y176862D03*
X884208Y192055D03*
X880926Y293347D03*
X880949Y297365D03*
X880983Y301500D03*
X880483Y326000D03*
X897106Y1137843D03*
X897513Y1149069D03*
Y1153497D03*
X902377Y1159831D03*
X891633Y1570633D03*
Y1578633D03*
Y1594633D03*
Y1582633D03*
Y1602633D03*
X909655Y582412D03*
X905434Y597449D03*
X906614Y611358D03*
X905283Y602182D03*
X909655Y625912D03*
X909531Y1161169D03*
X929507Y570703D03*
X944428Y185052D03*
Y189052D03*
X944131Y1137843D03*
X944538Y1149069D03*
Y1153497D03*
X933633Y1590233D03*
X948064Y590417D03*
X956556Y1161169D03*
X949402Y1159831D03*
X964608Y202096D03*
X968108Y198171D03*
X985407Y175483D03*
X987938Y264781D03*
Y275443D03*
X980208Y1055484D03*
X1001483Y152299D03*
X994483D03*
X997395Y217233D03*
X995867Y473675D03*
Y479175D03*
X999539Y521014D03*
Y516014D03*
Y526074D03*
Y531074D03*
X1012859Y175278D03*
Y171278D03*
X1016803Y194499D03*
X1017040Y425902D03*
X1014247Y460155D03*
Y456155D03*
Y452155D03*
Y464155D03*
Y468155D03*
Y476155D03*
Y472155D03*
Y493655D03*
Y488642D03*
Y480155D03*
X1015269Y550074D03*
Y545074D03*
X1030887Y287311D03*
Y298311D03*
X1024452Y378764D03*
Y383764D03*
Y388764D03*
X1024483Y402000D03*
X1024452Y393764D03*
X1031483Y566000D03*
X1046728Y406586D03*
X1042737Y516014D03*
Y521074D03*
Y526074D03*
Y534074D03*
X1045483Y538000D03*
X1044737Y544574D03*
Y549574D03*
X1044814Y553641D03*
X1071564Y369792D03*
X1068777Y475525D03*
X1077777Y471500D03*
Y467000D03*
X1077693Y483782D03*
Y487782D03*
X1068747Y483655D03*
Y487655D03*
X1071279Y1353197D03*
X1089994Y373187D03*
X1084718Y387226D03*
Y379226D03*
Y383226D03*
Y391226D03*
X1093421Y472105D03*
X1094597Y1687229D03*
Y1691229D03*
X1101931Y447355D03*
Y463355D03*
Y459355D03*
Y455355D03*
Y451355D03*
Y467355D03*
Y475355D03*
Y484391D03*
Y489391D03*
X1103879Y1353197D03*
X1101983Y1642500D03*
X1102547Y1696029D03*
X1111347Y1711244D03*
X1136579Y1353197D03*
X1161994Y73939D03*
X1169479Y1353197D03*
X1163258Y1454234D03*
X1181670Y61515D03*
Y57015D03*
X1181690Y52815D03*
X1172689Y442341D03*
Y447841D03*
Y464341D03*
Y453341D03*
Y458841D03*
Y469841D03*
Y481691D03*
X1188070Y99694D03*
X1195185Y177187D03*
Y173187D03*
X1191410Y432202D03*
Y448202D03*
Y440202D03*
Y460202D03*
X1191530Y470392D03*
X1191470Y465272D03*
X1188175Y574322D03*
X1190983Y1401000D03*
Y1396500D03*
Y1405500D03*
Y1410000D03*
X1199983Y1414500D03*
Y1419000D03*
Y1428500D03*
Y1433000D03*
X1190983Y1437500D03*
X1192520Y1693850D03*
X1199520D03*
X1195670Y1689850D03*
X1205495Y164987D03*
Y160987D03*
Y185187D03*
X1202595Y582443D03*
Y587443D03*
X1202279Y1353197D03*
X1207862Y1693859D03*
X1214862D03*
X1211012Y1689859D03*
X1202960Y1731803D03*
X1244676Y128239D03*
Y132739D03*
Y123739D03*
Y137239D03*
X1234176Y145239D03*
X1239937Y427255D03*
Y431255D03*
Y439255D03*
Y435255D03*
X1240270Y1307051D03*
X1242983Y1406500D03*
X1253045Y453182D03*
Y458182D03*
X1248483Y1410500D03*
Y1414500D03*
X1265682Y395125D03*
X1265685Y399125D03*
X1261930Y459182D03*
X1262000Y454372D03*
X1265983Y765000D03*
X1273166Y1307023D03*
X1263579Y1342686D03*
X1275594Y154030D03*
X1280432Y390884D03*
X1298176Y141739D03*
Y137739D03*
X1299090Y162051D03*
Y166051D03*
Y171551D03*
Y184051D03*
X1302134Y527418D03*
X1300215Y541634D03*
X1303749Y552813D03*
X1294817Y592871D03*
X1319324Y567148D03*
X1307206Y560209D03*
X1312170Y565771D03*
X1306070Y1306966D03*
X1321421Y1408282D03*
X1346279Y678393D03*
X1338870Y1307166D03*
X1371452Y1326497D03*
X1381198Y236594D03*
Y241594D03*
Y246594D03*
Y251594D03*
X1384976Y1670391D03*
X1391976Y1674391D03*
X1387528Y1700038D03*
X1391658Y1695238D03*
X1387528Y1712038D03*
Y1708038D03*
X1390087Y1728318D03*
X1394791Y1032303D03*
X1401116Y1622167D03*
X1408116Y1626167D03*
X1407798Y1646967D03*
X1410673Y1285765D03*
Y1289765D03*
X1421798Y1646967D03*
X1435165Y117664D03*
X1426780Y1609904D03*
X1435792Y1613904D03*
X1435980Y1623504D03*
X1426780Y1623366D03*
X1431869Y1647087D03*
X1441781Y1013603D03*
Y1009863D03*
Y1006122D03*
Y1017343D03*
Y1028563D03*
Y1021083D03*
Y1024823D03*
Y1032303D03*
X1465740Y537827D03*
X1461740Y576977D03*
X1469740Y580977D03*
Y572977D03*
Y568977D03*
Y576977D03*
X1484992Y702203D03*
X1513740Y547977D03*
Y551977D03*
X1503740Y556477D03*
X1503840Y561677D03*
X1513740Y563977D03*
X1517425Y130813D03*
X1522002Y209250D03*
Y213250D03*
Y221250D03*
Y225250D03*
Y231250D03*
Y238017D03*
Y249250D03*
Y244250D03*
Y253250D03*
X1518074Y702203D03*
X1541997Y288816D03*
X1542000Y292816D03*
Y296816D03*
X1556747Y284575D03*
X1550120Y1262314D03*
X1550160Y1270188D03*
Y1274188D03*
X1561031Y1302609D03*
X1585160Y1278988D03*
X1573775Y1271378D03*
X1578188Y1275454D03*
X1585160Y1292988D03*
X1584755Y1298278D03*
X1577890Y1288958D03*
X1590786Y225250D03*
Y214250D03*
Y229250D03*
Y234250D03*
Y239250D03*
Y244250D03*
X1601782Y536344D03*
Y531226D03*
X1591660Y1278988D03*
X1613548Y538723D03*
X1613431Y554664D03*
X1613494Y559092D03*
X1625392Y290742D03*
Y294742D03*
Y298742D03*
Y302742D03*
X1625449Y566803D03*
X1632711Y1432248D03*
X1632686Y1424466D03*
Y1428366D03*
X1632711Y1436148D03*
X1632650Y1448016D03*
X1638483Y381500D03*
X1647593Y414202D03*
X1637816Y1311874D03*
X1659631Y692328D03*
X1654830Y1370514D03*
X1649660Y1440488D03*
X1664237Y1402860D03*
X1669293Y1416678D03*
X1690116Y424694D03*
X1687612Y1370614D03*
X1687791Y1696427D03*
X1695487Y401485D03*
X1697019Y1402960D03*
X1718010Y424340D03*
Y420340D03*
X1735348Y53651D03*
Y57651D03*
X1736101Y89827D03*
X1725401Y116867D03*
X1726317Y656238D03*
X1729946Y1681465D03*
Y1676965D03*
X1743292Y89264D03*
X1746792Y85339D03*
X1742560Y668216D03*
Y664216D03*
X1738928Y1552371D03*
X1763521Y68637D03*
X1764031Y87107D03*
Y83607D03*
X1754070Y364048D03*
Y368048D03*
X1754203Y377452D03*
Y382952D03*
X1771761Y92891D03*
X1781558Y186911D03*
Y194399D03*
X1781614Y197899D03*
X1767910Y368148D03*
X1767703Y372452D03*
X1767910Y364148D03*
X1774671Y1552371D03*
X1775962Y1582405D03*
X1773462Y1577905D03*
X1767906Y1635686D03*
X1770946Y1661465D03*
Y1657465D03*
X1785161Y96927D03*
X1785119Y100939D03*
X1792873Y156834D03*
Y161834D03*
X1783987Y182463D03*
X1794887Y1587105D03*
X1825063Y151834D03*
X1826139Y388051D03*
X1825782Y427432D03*
X1825775Y431678D03*
X1847774Y165834D03*
X1847744Y170287D03*
G54D323*
X1790206Y204003D03*
G54D161*
X385023Y-23871D03*
X836502Y-20011D03*
Y-11D03*
Y19989D03*
X1240022Y-20011D03*
Y-11D03*
Y19989D03*
X1533316Y-24212D03*
G54D32*
X55374Y390301D03*
G54D233*
X721963Y1577932D03*
Y1586790D03*
G54D242*
X762913Y1490789D03*
Y1506538D03*
Y1502600D03*
Y1498663D03*
Y1494726D03*
Y1522286D03*
Y1518349D03*
Y1514412D03*
Y1510474D03*
Y1526223D03*
X779527Y1492758D03*
Y1488821D03*
Y1504569D03*
Y1500632D03*
Y1496695D03*
Y1520317D03*
Y1516380D03*
Y1512443D03*
Y1508506D03*
Y1528191D03*
Y1524254D03*
G54D107*
X186831Y151000D03*
X178169Y147260D03*
Y154740D03*
X396102Y536138D03*
X387440Y532398D03*
Y539878D03*
X588099Y253691D03*
Y261171D03*
X596761Y257431D03*
X608169Y447260D03*
X616831Y451000D03*
X608169Y454740D03*
X607557Y479606D03*
X616219Y475866D03*
Y483346D03*
X855184Y530845D03*
Y538325D03*
X863846Y534585D03*
X919968Y554548D03*
X928630Y558288D03*
X919968Y562028D03*
X1144118Y1445987D03*
Y1453467D03*
X1152780Y1449727D03*
G54D170*
X435262Y55016D03*
Y60016D03*
Y65016D03*
Y70016D03*
X456128Y60016D03*
Y55016D03*
Y70016D03*
Y65016D03*
X1148486Y53186D03*
Y58186D03*
Y63186D03*
Y68186D03*
X1169352Y58186D03*
Y53186D03*
Y68186D03*
Y63186D03*
G54D314*
X1738071Y271402D03*
G54D152*
X335823Y270260D03*
X326177D03*
X335823Y277740D03*
X326177Y274000D03*
Y277740D03*
X382323Y311240D03*
Y303760D03*
X372677D03*
Y307500D03*
Y311240D03*
X604494Y432209D03*
X594848D03*
X604494Y439689D03*
X594848Y435949D03*
Y439689D03*
X797551Y384932D03*
Y377452D03*
X787905D03*
Y381192D03*
Y384932D03*
X1246555Y90470D03*
X1236909D03*
X1246555Y97950D03*
X1236909Y94210D03*
Y97950D03*
X1678258Y220857D03*
X1668612D03*
Y224597D03*
X1678258Y228337D03*
X1668612D03*
G54D206*
X529815Y445740D03*
Y438260D03*
X519185D03*
Y442000D03*
Y445740D03*
X555185Y458760D03*
Y466240D03*
X565815Y462500D03*
Y458760D03*
Y466240D03*
G54D116*
X191038Y1572954D03*
Y1579954D03*
X197853Y1579110D03*
Y1586110D03*
X204768Y1579134D03*
Y1586134D03*
X289239Y598826D03*
Y605826D03*
X292747Y1578722D03*
Y1585722D03*
X296139Y598826D03*
X303039D03*
X296139Y605826D03*
X303039D03*
X299938Y1578884D03*
Y1585884D03*
X309939Y598826D03*
X317961Y598861D03*
X309939Y605826D03*
X317961Y605861D03*
X352618Y271310D03*
Y264310D03*
X392153Y209695D03*
Y216695D03*
X463751Y299601D03*
X456871Y299661D03*
X463751Y306601D03*
X456871Y306661D03*
X543871Y315661D03*
Y308661D03*
X550751Y315601D03*
Y308601D03*
X552400Y1578652D03*
X559348Y1578724D03*
X552400Y1585652D03*
X559348Y1585724D03*
X682200Y1521300D03*
Y1514300D03*
X773456Y253292D03*
Y260292D03*
X958452Y162103D03*
Y169103D03*
X969390Y209089D03*
Y216089D03*
X1198911Y1605954D03*
Y1612954D03*
X1205758Y1612274D03*
X1212608D03*
X1205758Y1619274D03*
X1212608D03*
X1295960Y1611652D03*
X1302908Y1611664D03*
X1295960Y1618652D03*
X1302908Y1618664D03*
X1312506Y94027D03*
Y101027D03*
X1567175Y571888D03*
Y578888D03*
X1560074Y1611242D03*
X1566978Y1611364D03*
X1560074Y1618242D03*
X1566978Y1618364D03*
X1597499Y558988D03*
Y565988D03*
X1590399Y558988D03*
Y565988D03*
X1667570Y414332D03*
Y421332D03*
X1679850Y435172D03*
Y428172D03*
X1690074Y1547300D03*
Y1554300D03*
X1750788Y183596D03*
Y190596D03*
X1749833Y205902D03*
Y212902D03*
X1764848Y183533D03*
Y190533D03*
X1757848Y183533D03*
Y190533D03*
X1763983Y205965D03*
X1756923Y205902D03*
X1763983Y212965D03*
X1756923Y212902D03*
X1765070Y255527D03*
X1757970Y255427D03*
X1765070Y262527D03*
X1757970Y262427D03*
X1771848Y183533D03*
Y190533D03*
X1770848Y211565D03*
Y204565D03*
X1777848Y211565D03*
Y204565D03*
G54D125*
X260521Y104291D03*
X258553D03*
Y115315D03*
X260521D03*
X274301Y104291D03*
X272333D03*
X270364D03*
X268395D03*
X266427D03*
X264459D03*
X262490D03*
Y115315D03*
X264459D03*
X266427D03*
X268395D03*
X270364D03*
X272333D03*
X691709Y108416D03*
Y119440D03*
X707457Y108416D03*
X705489D03*
X703520D03*
X701551D03*
X699583D03*
X697615D03*
X695646D03*
X693677D03*
Y119440D03*
X695646D03*
X697615D03*
X699583D03*
X701551D03*
X703520D03*
X705489D03*
X997487Y211742D03*
X1001423D03*
X1735642Y105415D03*
X1733674D03*
Y116439D03*
X1735642D03*
X1749422Y105415D03*
X1747454D03*
X1745485D03*
X1743516D03*
X1741548D03*
X1739580D03*
X1737611D03*
Y116439D03*
X1739580D03*
X1741548D03*
X1743516D03*
X1745485D03*
X1747454D03*
G54D215*
X607057Y771392D03*
X613470Y759230D03*
G54D134*
X275558Y589395D03*
G54D260*
X828780Y1684890D03*
X818780D03*
X828780Y1694890D03*
X818780D03*
X828780Y1704890D03*
X818780D03*
X828780Y1714890D03*
X818780D03*
X853780Y1684890D03*
Y1694890D03*
Y1704890D03*
Y1714890D03*
X863780Y1684890D03*
Y1694890D03*
Y1704890D03*
Y1714890D03*
X888780Y1684890D03*
Y1694890D03*
Y1704890D03*
Y1714890D03*
X898780Y1684890D03*
Y1694890D03*
Y1704890D03*
Y1714890D03*
X918780Y1684890D03*
Y1694890D03*
Y1704890D03*
Y1714890D03*
X928780Y1684890D03*
Y1694890D03*
Y1704890D03*
Y1714890D03*
X938780Y1684890D03*
Y1694890D03*
Y1704890D03*
X958780Y1684890D03*
Y1694890D03*
Y1704890D03*
Y1714890D03*
X968780Y1684890D03*
Y1694890D03*
Y1704890D03*
Y1714890D03*
X993780Y1684890D03*
Y1694890D03*
Y1704890D03*
Y1714890D03*
X1003780Y1684890D03*
Y1694890D03*
Y1704890D03*
Y1714890D03*
X1028780Y1684890D03*
X1038780D03*
X1028780Y1694890D03*
X1038780D03*
X1028780Y1704890D03*
Y1714890D03*
X1038780Y1704890D03*
Y1714890D03*
G54D14*
X20709Y139746D03*
X23563Y1590338D03*
X409259Y412106D03*
X864625Y1368522D03*
X925009Y1014595D03*
X1088663Y299646D03*
X1148239Y554216D03*
X1489957Y1403002D03*
X1568792Y178239D03*
X1704930Y1649379D03*
G54D224*
X676509Y224606D03*
G54D305*
X1500126Y609338D03*
X1520008D03*
G54D50*
X65205Y1519505D03*
X100948D03*
X112601Y1353627D03*
X145201D03*
X177901D03*
X210801D03*
X243601D03*
X258455Y676490D03*
X277201Y1307481D03*
X291185Y710731D03*
X310097Y1307453D03*
X323955Y730881D03*
X343001Y1307396D03*
X357015Y730613D03*
X375801Y1307596D03*
X390055Y730681D03*
X408383Y1326927D03*
X423055Y712881D03*
X455455Y688281D03*
X488055Y661781D03*
X521355Y627681D03*
X720157Y1371636D03*
X752939Y1371736D03*
X1084339Y1353608D03*
X1116939D03*
X1149639D03*
X1182539D03*
X1215339D03*
X1253330Y1307462D03*
X1286226Y1307434D03*
X1319130Y1307377D03*
X1351930Y1307577D03*
X1369007Y645824D03*
X1384512Y1326908D03*
X1401707Y678724D03*
X1434307Y711304D03*
X1467225Y730881D03*
X1500307Y731049D03*
X1533107Y730881D03*
X1566237Y708941D03*
X1599007Y675172D03*
X1632007Y656172D03*
X1667890Y1370925D03*
X1700672Y1371025D03*
X1752488Y1552541D03*
X1788231D03*
G54D41*
X50773Y777430D03*
G54D143*
X286784Y585177D03*
G54D251*
X785252Y1342245D03*
G54D342*
G01X1883273Y850816D02*
Y1145394D01*
X1884277Y1146398D01*
X1892329D01*
X1893273Y1145454D01*
Y850816D01*
G54D333*
G01X470309Y1692218D02*
Y1689000D01*
G01X664653Y1727718D02*
X662153D01*
G01X657173Y1722174D02*
X659673D01*
G01X657173Y1732836D02*
X659673D01*
G01X1095489Y1703764D02*
Y1699179D01*
G01Y1711244D02*
Y1708519D01*
G01X1107021Y1724109D02*
X1109521D01*
G01X1119067Y1546733D02*
Y1551457D01*
G01X1114501Y1718991D02*
X1112001D01*
G01X1126745Y1565237D02*
Y1567858D01*
X1127839Y1568952D01*
X1131256D01*
G01X1192612Y1677910D02*
Y1680410D01*
G01X1197980Y1688270D02*
X1197730Y1688020D01*
Y1685390D01*
G01X1194267Y1712261D02*
X1196767D01*
G01X1194314Y1726261D02*
X1196814D01*
G01X1201794Y1721143D02*
X1199294D01*
G01X1213072Y1685399D02*
Y1682899D01*
G01X1201747Y1707143D02*
X1204447D01*
G01X1383800Y1682898D02*
Y1685398D01*
G01X1388918Y1690378D02*
Y1687878D01*
G01X1387620Y1712038D02*
Y1716438D01*
G01X1399940Y1634627D02*
Y1637127D01*
G01X1405058Y1642107D02*
Y1639607D01*
G01X1418740Y1625627D02*
Y1622902D01*
G01X1413622Y1633107D02*
Y1637767D01*
G01X1670500Y1711759D02*
X1668000D01*
G01X1670500Y1726909D02*
X1668000D01*
G01X1663020Y1716877D02*
X1665520D01*
G01X1663020Y1732027D02*
X1665520D01*
G01X1705500Y1711759D02*
X1703000D01*
G01X1698020Y1716877D02*
X1700520D01*
G01X1737140Y1713383D02*
X1739640D01*
G01X1744620Y1708265D02*
X1742120D01*
G01X1737140Y1728533D02*
X1739640D01*
G01X1744620Y1723415D02*
X1742120D01*
G54D144*
X280810Y1545361D03*
X295180D03*
X416921D03*
X431291D03*
X544983D03*
X559353D03*
X714349Y1423623D03*
X728719D03*
X880297Y1068533D03*
X894667D03*
X971040Y1067984D03*
X985410D03*
X1288683Y1578361D03*
X1303053D03*
X1424795D03*
X1439165D03*
X1552857D03*
X1567227D03*
X1721146Y1419712D03*
X1735516D03*
G54D24*
X20587Y528693D03*
Y537355D03*
X26887D03*
Y528693D03*
X414963Y83352D03*
Y92014D03*
X421655D03*
Y83352D03*
G54D306*
X1545620Y209250D03*
Y224250D03*
Y219250D03*
Y214250D03*
Y239250D03*
Y234250D03*
Y229250D03*
Y254250D03*
Y249250D03*
Y244250D03*
X1564202Y209250D03*
Y224250D03*
Y219250D03*
Y214250D03*
Y239250D03*
Y234250D03*
Y229250D03*
Y254250D03*
Y249250D03*
Y244250D03*
G54D261*
X842596Y58448D03*
X840037D03*
Y81448D03*
X842596D03*
X847715Y58448D03*
X845156D03*
Y81448D03*
X847715D03*
G54D315*
X1764399Y709079D03*
X1785659D03*
G54D324*
X1797245Y212369D03*
G54D153*
X330934Y552397D03*
X328375D03*
X325816D03*
Y560271D03*
X328375D03*
X330934D03*
X1542675Y547341D03*
X1540116D03*
Y555215D03*
X1542675D03*
X1545234Y547341D03*
Y555215D03*
G54D33*
X51437Y380803D03*
X49468D03*
Y399799D03*
X51437D03*
X61280Y380803D03*
X59311D03*
X57342D03*
X55374D03*
X53406D03*
Y399799D03*
X55374D03*
X57342D03*
X59311D03*
X61280D03*
G54D180*
X467750Y1684738D03*
Y1692218D03*
X470309Y1684738D03*
X472868D03*
X470309Y1692218D03*
X472868D03*
X1387620Y1716438D03*
X1385061D03*
X1390179D03*
X1387620Y1723918D03*
X1385061D03*
X1390179D03*
G54D117*
X212224Y148760D03*
X202776D03*
X212224Y156240D03*
X202776Y152500D03*
Y156240D03*
X240708Y207651D03*
Y211391D03*
Y215131D03*
X250156Y207651D03*
Y215131D03*
X380447Y135157D03*
X370999D03*
X380447Y142637D03*
X370999Y138897D03*
Y142637D03*
X599776Y417760D03*
Y425240D03*
X609224Y417760D03*
Y425240D03*
Y421500D03*
X861416Y402450D03*
X870864D03*
X861416Y409930D03*
X870864D03*
Y406190D03*
X1002126Y428366D03*
Y420886D03*
X992678D03*
Y424626D03*
Y428366D03*
X1445372Y52933D03*
Y56673D03*
Y60413D03*
X1454820D03*
Y52933D03*
G54D252*
X785252Y1334469D03*
X796276Y1347855D03*
X905618Y1141976D03*
X916642Y1155362D03*
X952643Y1141976D03*
X963667Y1155362D03*
X1315411Y547916D03*
X1326435Y561302D03*
X1621536Y547571D03*
X1632560Y560957D03*
G54D126*
X260128Y109803D03*
X263671D03*
X267214D03*
X270758D03*
X693284Y113928D03*
X696827D03*
X700370D03*
X703914D03*
X1735249Y110927D03*
X1738792D03*
X1742335D03*
X1745879D03*
G54D162*
X388273Y-24855D03*
Y-22887D03*
X728493D03*
Y-24855D03*
X839752Y-20995D03*
Y-19027D03*
Y-995D03*
Y973D03*
Y19005D03*
Y20973D03*
X1179972Y-19027D03*
Y-20995D03*
Y973D03*
Y-995D03*
Y20973D03*
Y19005D03*
X1243272Y-20995D03*
Y-19027D03*
Y-995D03*
Y973D03*
Y19005D03*
Y20973D03*
X1438831Y-19027D03*
Y-20995D03*
Y973D03*
Y-995D03*
Y20973D03*
Y19005D03*
X1536566Y-25196D03*
Y-23228D03*
X1732125D03*
Y-25196D03*
X1803347Y201642D03*
G54D171*
X439169Y106684D03*
X437200D03*
X435232D03*
X433263D03*
X431295D03*
X429326D03*
Y141330D03*
X431295D03*
X433263D03*
X435232D03*
X437200D03*
X439169D03*
X452948Y106684D03*
X450980D03*
X449011D03*
X447043D03*
X445074D03*
X443106D03*
X441137D03*
Y141330D03*
X443106D03*
X445074D03*
X447043D03*
X449011D03*
X450980D03*
X452948D03*
X458854Y106684D03*
X456885D03*
X454917D03*
Y141330D03*
X456885D03*
X458854D03*
G54D243*
X771220Y1534963D03*
G54D15*
X11782Y174960D03*
X18691Y175132D03*
X33180Y301266D03*
X36524Y395255D03*
X32847Y537524D03*
X36372Y534279D03*
X50304Y61804D03*
X39008Y366396D03*
X51114D03*
X42809D03*
X48502Y507756D03*
X48626Y549744D03*
X52040Y1502281D03*
X48662Y1526319D03*
X50631Y1540155D03*
X50696Y1547353D03*
X51996Y1554426D03*
X46133Y1636380D03*
X51133D03*
X54616Y61804D03*
X63780Y301266D03*
X67681Y366396D03*
X59322D03*
X63429D03*
X56163Y416987D03*
X52902Y507569D03*
X58402D03*
X58633Y1593380D03*
X63633D03*
X56133Y1639480D03*
X61133D03*
X64427Y1649871D03*
X55427D03*
X69523Y416987D03*
X80378Y1412139D03*
X68768Y1550280D03*
X68133Y1593380D03*
X72660D03*
X81006Y1599391D03*
X77427Y1649871D03*
X78127Y1684871D03*
X70127D03*
X74127D03*
X94158Y1311085D03*
X90601Y1385773D03*
X94713Y1385821D03*
X84405Y1526319D03*
X86374Y1540655D03*
X82606Y1607691D03*
X86127Y1684871D03*
X92500Y1701934D03*
X98124Y1359700D03*
X98101Y1377021D03*
X101995Y1385652D03*
X107000Y1410484D03*
X104511Y1549980D03*
X112353Y1652071D03*
X120016Y297681D03*
Y318115D03*
X115590Y1384842D03*
X115353Y1693450D03*
X119353D03*
X130724Y1359700D03*
X130701Y1377021D03*
X134595Y1385652D03*
X141028Y1452096D03*
X137120Y1452142D03*
X133120D03*
X132353Y1652071D03*
X136353D03*
X139353Y1693571D03*
X131353D03*
X135353D03*
X132420Y1704495D03*
X144610Y427064D03*
X148190Y1384842D03*
X148000Y1417484D03*
X151000Y1445484D03*
X145028Y1452096D03*
X149028D03*
X152353Y1652071D03*
X151353Y1693571D03*
X143353D03*
X155353D03*
X163424Y1359700D03*
X163401Y1377021D03*
X167295Y1385652D03*
X158740Y1710484D03*
X183890Y393644D03*
X180890Y1384842D03*
X185760Y1710372D03*
X181760Y1728860D03*
X195979Y101126D03*
X190861Y128561D03*
X197645Y133671D03*
X196324Y1359700D03*
X196301Y1377021D03*
X200195Y1385652D03*
X189760Y1728860D03*
X208179Y101126D03*
X203061Y128561D03*
X213790Y1384842D03*
X229516Y155043D03*
X225090Y156454D03*
X229124Y1359700D03*
X229101Y1377021D03*
X243487Y107744D03*
X246297Y127027D03*
X242297D03*
X233595Y155055D03*
X244125Y666222D03*
X232995Y1385652D03*
X247487Y107744D03*
X261297Y127027D03*
X254297D03*
X250297D03*
X260100Y156946D03*
X254756Y159786D03*
X251424Y648243D03*
X246590Y1384842D03*
X271797Y127027D03*
X268297Y130527D03*
X275500Y233984D03*
X273069Y585054D03*
X272955Y666564D03*
X262724Y1313554D03*
X266595Y1339506D03*
X262701Y1330875D03*
X273597Y1522904D03*
X289357Y118987D03*
X284154Y682484D03*
X276855Y700463D03*
X280190Y1338696D03*
X279499Y1522904D03*
X302500Y253484D03*
X297815Y585938D03*
X305685Y700805D03*
X295620Y1313526D03*
X295597Y1330847D03*
X299491Y1339478D03*
X314602Y274075D03*
X316924Y702634D03*
X309655Y720323D03*
X313086Y1338668D03*
X325617Y84227D03*
X328524Y1313469D03*
X328501Y1330790D03*
X332395Y1339421D03*
X339811Y126161D03*
X346153Y273370D03*
X349984Y702366D03*
X342710Y720296D03*
X338455Y720955D03*
X345990Y1338611D03*
X352628Y286774D03*
X357582Y558274D03*
X353582D03*
X361324Y1313669D03*
X361301Y1330990D03*
X365195Y1339621D03*
X370064Y242620D03*
X371412Y275061D03*
X371962Y537151D03*
X375704Y720447D03*
X371515Y720687D03*
X378790Y1338811D03*
X395048Y126662D03*
X382184Y471835D03*
X393376Y472181D03*
X383024Y702434D03*
X393906Y1333000D03*
X393883Y1350321D03*
X384824Y1627197D03*
X394824D03*
X389824D03*
X384824Y1664604D03*
X394824D03*
X389824D03*
X406243Y105560D03*
X399264Y126628D03*
X400632Y144209D03*
X399299Y217555D03*
X402184Y471953D03*
Y504585D03*
X408739Y702578D03*
X404771Y696122D03*
X404555Y720755D03*
X397777Y1358952D03*
X401659Y1522904D03*
X407561D03*
X402969Y1625808D03*
X399824Y1664604D03*
X405000Y1680484D03*
X411299Y209604D03*
Y217555D03*
X415984Y471876D03*
Y504508D03*
X412771Y534122D03*
X416024Y684634D03*
X423921Y1009407D03*
X411372Y1358142D03*
X417000Y1667984D03*
Y1680484D03*
X433673Y80184D03*
X429997Y163609D03*
X433997Y156609D03*
X437997D03*
X439299Y217555D03*
X429784Y471799D03*
X439500Y496484D03*
X437309Y677911D03*
X437555Y702955D03*
X435141Y1009407D03*
X438882D03*
X427661D03*
X431401D03*
X427251Y1289178D03*
X441997Y163609D03*
X451299Y217555D03*
X443500Y489484D03*
X448424Y660034D03*
X441137Y677897D03*
X450102Y1009407D03*
X442622D03*
X446362D03*
X453842D03*
X453085Y1646917D03*
X466600Y145859D03*
X457997Y163609D03*
X465997D03*
X461931Y218162D03*
X458115Y244012D03*
X469038Y303622D03*
X469881Y651521D03*
X469955Y678355D03*
X457582Y1009407D03*
X461000Y1646984D03*
X475435Y209619D03*
X484754Y226436D03*
X481024Y633534D03*
X473732Y651523D03*
X483500Y1267846D03*
X478500Y1267984D03*
X474500D03*
X498314Y118402D03*
X485997Y163609D03*
X489997D03*
X494144Y218711D03*
X487107Y288213D03*
X488544Y295008D03*
X488538Y301687D03*
X487500Y1267846D03*
X492500D03*
X496500D03*
X501500Y429484D03*
X512000Y432484D03*
X501500Y422484D03*
X514324Y599434D03*
X502998Y617397D03*
X506964Y617405D03*
X502555Y651855D03*
X515539Y85626D03*
X522088Y207344D03*
X543131Y126314D03*
X536177Y246689D03*
X535855Y617755D03*
X537770Y1522904D03*
X543672D03*
X554196Y187740D03*
X556038Y312622D03*
X566460Y160553D03*
X574107Y297213D03*
X570216Y767496D03*
X582193Y86157D03*
Y93157D03*
X588194Y178034D03*
X575538Y310687D03*
X575567Y304152D03*
X579385Y379486D03*
X585585Y377536D03*
X579385Y390286D03*
Y404217D03*
X585585Y390286D03*
X575216Y767496D03*
X595260Y160553D03*
X602293Y209245D03*
X598294Y201245D03*
X602294D03*
X608793Y209245D03*
X608794Y201245D03*
X618705Y295789D03*
X615385Y379486D03*
Y390286D03*
Y409905D03*
X625310Y178593D03*
X626705Y295789D03*
X622705D03*
X621585Y377536D03*
Y390286D03*
X619500Y441984D03*
X626703Y1353168D03*
X630000Y1404484D03*
X635060Y146127D03*
X646231Y153035D03*
X638000Y425484D03*
X642500Y421984D03*
X643563Y1389881D03*
X647445Y1389905D03*
X635000Y1404484D03*
X637794Y1721454D03*
X653821Y87246D03*
X649500Y379484D03*
X655702Y1388407D03*
X659559Y1388349D03*
X651877Y1388374D03*
X652800Y1694284D03*
X656800D03*
X675843Y107169D03*
X666885Y408239D03*
X665832Y1530484D03*
X673113Y1722083D03*
Y1732745D03*
X680623Y111869D03*
X687453Y131152D03*
X683453D03*
X689440Y366388D03*
X690800Y379846D03*
X687500Y396346D03*
X679500Y523984D03*
X687310Y510846D03*
X692500D03*
X688500Y543346D03*
X688120Y1519510D03*
X704953Y131152D03*
X694453D03*
X700963Y131212D03*
X707545Y366305D03*
X703520Y366388D03*
X708300Y379846D03*
X704300D03*
X700300D03*
X707500Y396346D03*
X699500D03*
X695500D03*
X703500D03*
X700500Y510846D03*
X696500D03*
Y527346D03*
X700500Y543346D03*
X704500Y553346D03*
X704056Y580565D03*
X698996D03*
X708056D03*
X694996D03*
X698699Y1348854D03*
X705680Y1377709D03*
X705657Y1395030D03*
X701661Y1395052D03*
X697731Y1395022D03*
X698500Y1593984D03*
X696030Y1630761D03*
X699799Y1630677D03*
X723500Y366346D03*
X715395Y366336D03*
X712300Y379846D03*
X720300D03*
X715500Y396346D03*
X711500D03*
X720500Y553346D03*
Y543346D03*
X720787Y633815D03*
X716721Y633751D03*
X711702Y652240D03*
X709551Y1403661D03*
X723146Y1402661D03*
X710217Y1438722D03*
X723050Y1602417D03*
X717110Y1602507D03*
X715152Y1630565D03*
X729380Y78002D03*
X734380D03*
X723933Y138472D03*
X731500Y366346D03*
X727564Y379846D03*
X735500Y396346D03*
X732500Y510846D03*
X728500D03*
X736500D03*
X728500Y543346D03*
X736500D03*
X732500Y543484D03*
X738462Y1377809D03*
X738439Y1395130D03*
X732723Y1630004D03*
X736723D03*
X728723D03*
X737468Y1690187D03*
X732434Y1688157D03*
X728454Y1687988D03*
X745500Y202484D03*
X747500Y379846D03*
X743500Y396346D03*
X747500D03*
X751500D03*
X739652Y396328D03*
X744500Y510846D03*
X752500D03*
X748500D03*
X740895Y527365D03*
X748500Y527346D03*
X752500D03*
X744500D03*
X752500Y543346D03*
X742333Y1403761D03*
X740723Y1630004D03*
X741326Y1686796D03*
X752187Y1688478D03*
X760193Y103712D03*
X761000Y215484D03*
X759500Y379846D03*
Y396346D03*
X755500D03*
X764500Y510846D03*
X756500D03*
X760500D03*
X756500Y527346D03*
X760500D03*
X764500D03*
X765000Y543346D03*
X755928Y1402761D03*
X757770Y1631267D03*
X761770D03*
X754030Y1659067D03*
Y1666067D03*
X762030D03*
X767368Y1665546D03*
X767381Y1673225D03*
X773766Y284306D03*
X781456Y381101D03*
X775500Y396346D03*
X771500D03*
X773000Y543346D03*
X768700Y543484D03*
X779447Y1337240D03*
X770450Y1584017D03*
X789277Y1527313D03*
X809817Y564921D03*
X807669Y1304700D03*
X812750Y1584917D03*
X819114Y120682D03*
X823114D03*
X827114D03*
X826614Y150182D03*
X824500Y511484D03*
X820500D03*
X831114Y120682D03*
X839360Y120566D03*
X840221Y187846D03*
X840220Y200846D03*
X839000Y388984D03*
X841872Y538169D03*
X844936Y93235D03*
X844221Y187846D03*
X844220Y200846D03*
X848500Y457984D03*
X852000Y488984D03*
X848762Y527472D03*
X854750Y1584917D03*
X871500Y319484D03*
X867190Y387744D03*
X871190D03*
X864065Y519020D03*
X886503Y281771D03*
X876923Y1245404D03*
X889368Y1144562D03*
X893368D03*
X895394Y1162815D03*
X896750Y1584917D03*
X916268Y275343D03*
X945263Y277640D03*
X936393Y1144562D03*
X940393D03*
X942419Y1162815D03*
X935907Y1245404D03*
X965442Y174869D03*
X981445Y182567D03*
X977195Y210907D03*
X1005699Y174327D03*
X999915Y182057D03*
X996415D03*
X1005395Y221407D03*
X1009735Y160927D03*
X1014828Y264749D03*
Y273911D03*
X1015334Y294295D03*
X1007011Y544983D03*
X1019961Y560416D03*
X1023220Y189083D03*
X1024961Y560416D03*
X1039000Y560484D03*
X1064915Y1310972D03*
X1066363Y1385534D03*
X1062405Y1385502D03*
X1063751Y1650978D03*
X1064221Y1659904D03*
X1069322Y404032D03*
X1069862Y1359681D03*
X1073733Y1385633D03*
X1069839Y1377002D03*
X1068094Y1650979D03*
X1068221Y1659904D03*
X1087328Y1384823D03*
X1094514Y1725900D03*
X1102462Y1359681D03*
X1102439Y1377002D03*
X1106333Y1385633D03*
X1108747Y1531864D03*
X1109558Y1547570D03*
X1105000Y1679484D03*
X1098514Y1718900D03*
X1119928Y1384823D03*
X1114617Y1531864D03*
X1115005Y1582535D03*
X1116000Y1668484D03*
X1120303Y1679419D03*
X1119361Y1719218D03*
X1135162Y1359681D03*
X1135139Y1377002D03*
X1139033Y1385633D03*
X1129846Y1459432D03*
X1131256Y1572011D03*
X1140117Y1668636D03*
X1152628Y1384823D03*
X1144107Y1668550D03*
X1168062Y1359681D03*
X1168039Y1377002D03*
X1178340Y472649D03*
X1180849Y464674D03*
X1171933Y1385633D03*
X1185528Y1384823D03*
X1195488Y91034D03*
X1215581Y88830D03*
X1200862Y1359681D03*
X1200839Y1377002D03*
X1204733Y1385633D03*
X1208000Y1396984D03*
X1210254Y1709920D03*
Y1730920D03*
Y1716920D03*
Y1723920D03*
X1206254Y1727770D03*
X1223455Y88830D03*
X1218328Y1384823D03*
X1238853Y1313535D03*
X1242724Y1339487D03*
X1238830Y1330856D03*
X1245000Y1429984D03*
Y1436984D03*
Y1443984D03*
X1241000D03*
X1253152Y90379D03*
Y101009D03*
X1256319Y1338677D03*
X1247000Y1406484D03*
X1256859Y1422984D03*
X1249000Y1429984D03*
Y1436984D03*
X1253000D03*
X1263472Y90348D03*
X1271749Y1313507D03*
X1271726Y1330828D03*
X1275620Y1339459D03*
X1289215Y1338649D03*
X1281470Y1555904D03*
X1287372D03*
X1296386Y548307D03*
X1299986D03*
X1296156Y558932D03*
X1304653Y1313450D03*
X1304630Y1330771D03*
X1307857Y108837D03*
X1305187Y568755D03*
X1308524Y1339402D03*
X1331930Y64429D03*
X1322119Y1338592D03*
X1343840Y64395D03*
X1337453Y1313650D03*
X1337430Y1330971D03*
X1341324Y1339602D03*
X1355750Y64395D03*
X1361976Y617577D03*
X1350261Y635565D03*
X1354597D03*
X1354919Y1338792D03*
X1367950Y64395D03*
X1370035Y1332981D03*
X1373906Y1358933D03*
X1370012Y1350302D03*
X1383507Y635898D03*
X1387297Y668465D03*
X1387501Y1358123D03*
X1394676Y650477D03*
X1407543Y1009406D03*
X1403803D03*
X1400063D03*
X1416207Y668798D03*
X1420007Y700715D03*
X1415024Y1009406D03*
X1411283D03*
X1418764D03*
X1422504D03*
X1417711Y1261850D03*
X1421211D03*
X1409532Y1555904D03*
X1415434D03*
X1415622Y1613251D03*
X1410622D03*
X1413622Y1640826D03*
X1434262Y58376D03*
X1439049Y112927D03*
X1429169Y112797D03*
X1427276Y683057D03*
X1433724Y1009406D03*
X1429984D03*
X1426244D03*
X1438532Y1278244D03*
X1448549Y120127D03*
X1443049Y112927D03*
X1448807Y701378D03*
X1452765Y720391D03*
X1449334Y1274976D03*
X1453334D03*
X1442532Y1278244D03*
X1450500Y1620484D03*
Y1629984D03*
X1445500D03*
X1440500D03*
X1442579Y1670787D03*
X1447579D03*
X1452579D03*
X1459896Y61472D03*
X1454549Y112927D03*
X1460194Y702634D03*
X1457579Y1670787D03*
X1481725Y720955D03*
X1493276Y702634D03*
X1485897Y720622D03*
X1513644Y249409D03*
X1505477Y1273872D03*
X1526076Y702634D03*
X1518697Y720622D03*
X1514807Y720955D03*
X1533454Y91205D03*
X1537454D03*
X1542697Y565071D03*
X1547827Y698514D03*
X1551827D03*
X1547607Y720955D03*
X1556178Y1265847D03*
X1558077Y1276272D03*
X1554377D03*
X1545644Y1555904D03*
X1551546D03*
X1559206Y680694D03*
X1560157Y1265847D03*
X1584597Y664913D03*
X1580597D03*
X1580737Y699015D03*
X1583177Y1265272D03*
X1587177D03*
X1575680Y1302963D03*
X1588800Y306655D03*
X1591976Y646925D03*
X1591177Y1265272D03*
X1617400Y306655D03*
X1617506Y567910D03*
X1617597Y645913D03*
X1613597D03*
X1613507Y665246D03*
X1629000Y388984D03*
Y395984D03*
X1624976Y627925D03*
X1646510Y431528D03*
X1646507Y646246D03*
X1645155Y1394304D03*
X1634327Y1409424D03*
X1662000Y220984D03*
X1651910Y232971D03*
X1652610Y400186D03*
X1661110Y431686D03*
X1653413Y1376998D03*
X1657284Y1402950D03*
X1653390Y1394319D03*
X1649197Y1394252D03*
X1653667Y1443225D03*
X1658167D03*
X1662465Y1441658D03*
X1657892Y1455344D03*
X1653614Y1455323D03*
X1650513Y1711668D03*
Y1726818D03*
Y1718668D03*
Y1733818D03*
X1673872Y431129D03*
X1670879Y1401950D03*
X1666290Y1441691D03*
X1670147Y1441633D03*
X1673706Y1563484D03*
X1675360Y1711986D03*
Y1726736D03*
X1684942Y231396D03*
X1686154Y431669D03*
X1686195Y1377098D03*
X1690066Y1403050D03*
X1686172Y1394419D03*
X1688243Y1669286D03*
X1692415Y1669224D03*
X1679816Y1669287D03*
X1685513Y1711668D03*
Y1718668D03*
X1704624Y431159D03*
X1701124D03*
X1703661Y1402050D03*
X1718608Y104068D03*
X1721418Y128151D03*
X1717418D03*
X1713312Y141206D03*
X1715044Y410029D03*
X1718931Y410021D03*
X1710408Y423429D03*
X1720845Y1676818D03*
X1710360Y1711986D03*
X1722608Y108868D03*
X1736418Y128151D03*
X1729418D03*
X1725418D03*
X1730364Y174435D03*
X1722500Y371846D03*
X1725500Y380846D03*
X1735945Y1559355D03*
X1728633Y1708174D03*
X1724633Y1715174D03*
Y1708174D03*
Y1723324D03*
Y1730324D03*
X1746918Y128151D03*
X1743418Y131651D03*
X1740688Y1534088D03*
X1737914Y1573191D03*
X1737979Y1580389D03*
X1739279Y1587462D03*
X1750380Y1713292D03*
X1749480Y1723642D03*
X1764478Y120111D03*
X1756051Y1583316D03*
X1758963Y1688949D03*
X1763463D03*
X1771688Y1559355D03*
X1773657Y1573691D03*
X1790738Y85351D03*
X1784133Y165883D03*
Y158794D03*
X1783448Y210441D03*
X1791794Y1583016D03*
X1819705Y166856D03*
G54D216*
X609016Y274272D03*
G54D270*
X900240Y1143460D03*
X947265D03*
G54D51*
X57281Y1523287D03*
X66081D03*
X59881D03*
X63481D03*
X57281Y1526394D03*
X66081D03*
X65281Y1529501D03*
X59881Y1526394D03*
X63481D03*
X62681Y1529501D03*
X64235Y1533150D03*
X61755D03*
X59275D03*
X64235Y1538750D03*
X61755D03*
X59275D03*
X74325Y1523303D03*
X68870Y1523147D03*
X71359Y1523186D03*
X74440Y1526385D03*
X74462Y1529665D03*
X91000Y1350300D03*
X88500D03*
X95624Y1523287D03*
X93024D03*
X97498Y1533150D03*
X95624Y1526394D03*
X95018Y1533150D03*
X93024Y1526394D03*
X97498Y1538750D03*
X95018D03*
X112677Y1357409D03*
X110077D03*
X107477D03*
X104877D03*
X111581Y1372872D03*
X106721Y1367272D03*
Y1372872D03*
X109151D03*
X112677Y1363473D03*
X110077D03*
X112677Y1360516D03*
X110077D03*
X107477D03*
X104877D03*
X100347Y1361417D03*
X109151Y1367272D03*
X111581D03*
X98492Y1523287D03*
X100922D03*
X109635Y1523158D03*
X106713Y1523098D03*
X103513D03*
X99978Y1533150D03*
X98492Y1526394D03*
X98424Y1529501D03*
X100922Y1526394D03*
X101024Y1529501D03*
X108861Y1528840D03*
Y1526410D03*
X99978Y1538750D03*
X115277Y1357409D03*
X120221Y1357425D03*
X117777Y1357409D03*
X121207Y1363643D03*
Y1360686D03*
X115321Y1372872D03*
X120181D03*
X117751D03*
X114405Y1509335D03*
X140077Y1357409D03*
X137477D03*
X139321Y1367272D03*
Y1372872D03*
X141751D03*
X140077Y1360516D03*
X137477D03*
X132947Y1361417D03*
X141751Y1367272D03*
X152821Y1357425D03*
X145277Y1357409D03*
X147877D03*
X142677D03*
X150377D03*
X144181Y1367272D03*
X153767Y1360456D03*
Y1363413D03*
X144181Y1372872D03*
X142677Y1360516D03*
X145277Y1363473D03*
X142677D03*
X145277Y1360516D03*
X152781Y1372872D03*
X150351D03*
X147921D03*
X170177Y1357409D03*
X172021Y1367272D03*
Y1372872D03*
X170177Y1360516D03*
X165647Y1361417D03*
X172777Y1357409D03*
X183077D03*
X185521Y1357425D03*
X175377Y1357409D03*
X177977D03*
X180577D03*
X176881Y1367272D03*
X174451D03*
X186467Y1360456D03*
Y1363413D03*
X172777Y1360516D03*
X176881Y1372872D03*
X174451D03*
X177977Y1363473D03*
X175377D03*
Y1360516D03*
X177977D03*
X185481Y1372872D03*
X183051D03*
X180621D03*
X198547Y1361417D03*
X215977Y1357409D03*
X210877D03*
X208277D03*
X213477D03*
X205677D03*
X203077D03*
X207351Y1367272D03*
X209781Y1372872D03*
X204921Y1367272D03*
Y1372872D03*
X207351D03*
X210877Y1363473D03*
X208277D03*
Y1360516D03*
X210877D03*
X205677D03*
X203077D03*
X209781Y1367272D03*
X213521Y1372872D03*
X215951D03*
X218421Y1357425D03*
X219367Y1360456D03*
Y1363413D03*
X231347Y1361417D03*
X218381Y1372872D03*
X243677Y1357409D03*
X241077D03*
X238477D03*
X235877D03*
X246277D03*
X242581Y1367272D03*
X240151D03*
X243677Y1363473D03*
X241077D03*
Y1360516D03*
X243677D03*
X242581Y1372872D03*
X240151D03*
X237721D03*
Y1367272D03*
X238477Y1360516D03*
X235877D03*
X246321Y1372872D03*
X259475Y657245D03*
X255735D03*
X253305D03*
X250875D03*
X259475Y662845D03*
X250835Y672692D03*
X253279Y672708D03*
X258379Y666644D03*
Y669601D03*
Y672708D03*
X255779D03*
X260979Y666644D03*
Y669601D03*
Y672708D03*
X251221Y1357425D03*
X248777Y1357409D03*
X252167Y1363413D03*
Y1360456D03*
X248751Y1372872D03*
X251181D03*
X252211Y1370232D03*
Y1367332D03*
X264335Y657245D03*
X261905D03*
Y662845D03*
X264335D03*
X263579Y669601D03*
X266179D03*
Y672708D03*
X263579D03*
X272077Y1314370D03*
X269477D03*
X274677D03*
X272077Y1311263D03*
X269477D03*
X274677D03*
X271321Y1326726D03*
Y1321126D03*
X276181Y1326726D03*
X273751D03*
X274677Y1317327D03*
X264947Y1315271D03*
X276181Y1321126D03*
X273751D03*
X291109Y700885D03*
X283062Y700979D03*
X288465Y691493D03*
X283605D03*
X286035D03*
X283565Y706933D03*
X286009Y706949D03*
X291109Y703842D03*
Y706949D03*
X288509D03*
X283062Y703936D03*
X284821Y1311279D03*
X282377Y1311263D03*
X279877D03*
X277277Y1314370D03*
Y1311263D03*
X285767Y1314310D03*
Y1317267D03*
X277277Y1317327D03*
X284781Y1326726D03*
X282351D03*
X279921D03*
X285891Y1320942D03*
Y1323842D03*
X292205Y691486D03*
X297065D03*
X294635D03*
X293709Y700885D03*
X297065Y697086D03*
X303657Y702815D03*
X292205Y697086D03*
X294635D03*
X293709Y703842D03*
Y706949D03*
X298909Y703842D03*
Y706949D03*
X296309Y703842D03*
Y706949D03*
X302373Y1314342D03*
X304973D03*
X302373Y1311235D03*
X304973D03*
X304217Y1326698D03*
Y1321098D03*
X297843Y1315243D03*
X321235Y711636D03*
X316375D03*
X318805D03*
X315912Y721039D03*
Y723996D03*
X321279Y727099D03*
X316335Y727083D03*
X318779Y727099D03*
X317717Y1311251D03*
X315273Y1311235D03*
X312773D03*
X307573Y1314342D03*
Y1311235D03*
X310173Y1314342D03*
Y1311235D03*
X318663Y1314282D03*
X309077Y1321098D03*
X306647D03*
X318663Y1317239D03*
X309077Y1326698D03*
X306647D03*
X307573Y1317299D03*
X310173D03*
X312817Y1326698D03*
X315247D03*
X317677D03*
X318811Y1320902D03*
Y1323802D03*
X329835Y711636D03*
X324975D03*
X329835Y717236D03*
X327405Y711636D03*
X324975Y717236D03*
X327405D03*
X326479Y721035D03*
X323879D03*
Y727099D03*
X326479D03*
X329079D03*
X331679D03*
X323879Y723992D03*
X326479D03*
X329079D03*
X331679D03*
X335277Y1314285D03*
Y1311178D03*
X330747Y1315186D03*
X349435Y711368D03*
X348449Y720827D03*
Y723784D03*
X349395Y726815D03*
X336457Y722815D03*
X340477Y1314285D03*
X337877D03*
Y1311178D03*
X340477D03*
X350621Y1311194D03*
X348177Y1311178D03*
X343077Y1314285D03*
X345677Y1311178D03*
X343077D03*
X341981Y1321041D03*
X339551D03*
X341981Y1326641D03*
X337121Y1321041D03*
X339551Y1326641D03*
X337121D03*
X340477Y1317242D03*
X343077D03*
X348151Y1326641D03*
X350581D03*
X345721D03*
X362895Y716968D03*
X360465Y711368D03*
X362895D03*
X358035D03*
Y716968D03*
X360465D03*
X351865Y711368D03*
X354295D03*
X359539Y720767D03*
X356939D03*
X351839Y726831D03*
X354339D03*
X356939D03*
X362139D03*
X359539D03*
X364739D03*
X356939Y723724D03*
X362139D03*
X359539D03*
X364739D03*
X351567Y1314225D03*
Y1317182D03*
X363547Y1315386D03*
X351651Y1320942D03*
Y1323842D03*
X369557Y722615D03*
X380977Y1311378D03*
X375877Y1314485D03*
X378477Y1311378D03*
X375877D03*
X370677Y1314485D03*
X368077D03*
X373277D03*
X368077Y1311378D03*
X370677D03*
X373277D03*
X375877Y1317442D03*
X372351Y1326841D03*
X369921D03*
Y1321241D03*
X374781Y1326841D03*
X373277Y1317442D03*
X374781Y1321241D03*
X372351D03*
X380951Y1326841D03*
X378521D03*
X395935Y717036D03*
Y711436D03*
X393505D03*
X391075D03*
Y717036D03*
X393505D03*
X382475Y711436D03*
X387335D03*
X384905D03*
X392579Y720835D03*
X389979D03*
X381802Y720789D03*
Y723746D03*
X387379Y726899D03*
X384879D03*
X389979D03*
Y723792D03*
X382435Y726883D03*
X392579Y726899D03*
X395179D03*
X392579Y723792D03*
X395179D03*
X383421Y1311394D03*
X384367Y1314425D03*
Y1317382D03*
X383381Y1326841D03*
X384481Y1321192D03*
Y1324092D03*
X397779Y726899D03*
Y723792D03*
X402457Y722615D03*
X396129Y1334717D03*
X408459Y1330709D03*
X405859D03*
X400659D03*
X403259D03*
X408459Y1333816D03*
X405859D03*
X403259D03*
X400659D03*
X408459Y1336773D03*
X405859D03*
X402503Y1340572D03*
X407363D03*
X404933D03*
X407363Y1346172D03*
X404933D03*
X402503D03*
X424075Y693636D03*
X425579Y703035D03*
X422979D03*
X424075Y699236D03*
X414682Y703139D03*
X420335Y693636D03*
X415475D03*
X417905D03*
X415435Y709083D03*
X417879Y709099D03*
X425579D03*
X422979D03*
X420379D03*
X425579Y705992D03*
X422979D03*
X414682Y706096D03*
X416949Y1336713D03*
Y1333756D03*
X411059Y1330709D03*
X416003Y1330725D03*
X413559Y1330709D03*
X417063Y1340523D03*
Y1343423D03*
X415963Y1346172D03*
X413533D03*
X411103D03*
X426505Y693636D03*
X428935D03*
Y699236D03*
X426505D03*
X430779Y709099D03*
Y705992D03*
X428179Y709099D03*
Y705992D03*
X435457Y704915D03*
X450305Y669036D03*
X452735D03*
X447875D03*
X455379Y678435D03*
X450279Y684499D03*
X455379D03*
X452779D03*
X455379Y681392D03*
X447835Y684483D03*
X447162Y678409D03*
Y681366D03*
X458905Y669036D03*
X456475D03*
X461335D03*
X457979Y678435D03*
X460579Y684499D03*
X457979D03*
X460579Y681392D03*
X457979D03*
X467957Y680315D03*
X463179Y684499D03*
Y681392D03*
X461335Y674636D03*
X456475D03*
X458905D03*
X485335Y642536D03*
X480475D03*
X482905D03*
X482879Y657999D03*
X480435Y657983D03*
X485379Y657999D03*
X479822Y651989D03*
Y654946D03*
X493935Y642536D03*
X489075D03*
X491505D03*
X493935Y648136D03*
X487979Y651935D03*
X490579D03*
X493179Y654892D03*
Y657999D03*
X487979Y654892D03*
X490579D03*
Y657999D03*
X487979D03*
X495779Y654892D03*
Y657999D03*
X489075Y648136D03*
X491505D03*
X513775Y608436D03*
X513735Y623883D03*
X513012Y620706D03*
Y617749D03*
X500457Y653715D03*
X524805Y608436D03*
X522375D03*
X527235D03*
X516205D03*
X518635D03*
X526479Y620792D03*
Y623899D03*
X523879Y620792D03*
X521279D03*
X523879Y623899D03*
X521279D03*
X518679D03*
X516179D03*
X529079Y620792D03*
Y623899D03*
X523879Y617835D03*
X521279D03*
X527235Y614036D03*
X522375D03*
X524805D03*
X533857Y619615D03*
X703568Y1379476D03*
X716707Y1385281D03*
X719137D03*
X720233Y1378525D03*
Y1381482D03*
Y1375418D03*
X722833D03*
X714277Y1385281D03*
X715033Y1378525D03*
X717633D03*
X712433D03*
X717633Y1381482D03*
X715033Y1375418D03*
X717633D03*
X712433D03*
X719137Y1390881D03*
X714277D03*
X716707D03*
X722877D03*
X728348Y1380832D03*
Y1377875D03*
X736280Y1379580D03*
X725333Y1375418D03*
X727777Y1375434D03*
X727737Y1390881D03*
X725307D03*
X753015Y1381582D03*
Y1378625D03*
Y1375518D03*
X747059Y1385381D03*
X745215Y1378625D03*
X747815D03*
Y1375518D03*
X745215D03*
X750415Y1381582D03*
Y1378625D03*
Y1375518D03*
X749489Y1385381D03*
X751919D03*
Y1390981D03*
X747059D03*
X749489D03*
X761130Y1380932D03*
Y1377975D03*
X755615Y1375518D03*
X758115D03*
X760559Y1375534D03*
X758089Y1390981D03*
X760519D03*
X755659D03*
X1048684Y1350724D03*
X1051684D03*
X1060684D03*
X1057684D03*
X1054684D03*
X1079215Y1357390D03*
X1076615D03*
X1071908Y1361660D03*
X1080889Y1367253D03*
X1076615Y1360497D03*
X1079215D03*
X1078459Y1367253D03*
Y1372853D03*
X1080889D03*
X1087015Y1357390D03*
X1089515D03*
X1091959Y1357406D03*
X1084415Y1357390D03*
X1081815D03*
X1092905Y1363394D03*
Y1360437D03*
X1083319Y1367253D03*
X1081815Y1360497D03*
X1084415D03*
X1081815Y1363454D03*
X1084415D03*
X1083319Y1372853D03*
X1087059D03*
X1089489D03*
X1091919D03*
X1109215Y1357390D03*
X1104448Y1361680D03*
X1109215Y1360497D03*
X1111059Y1367253D03*
Y1372853D03*
X1119615Y1357390D03*
X1122115D03*
X1124559Y1357406D03*
X1117015Y1357390D03*
X1111815D03*
X1114415D03*
X1117015Y1363454D03*
Y1360497D03*
X1115919Y1372853D03*
X1125505Y1363394D03*
Y1360437D03*
X1115919Y1367253D03*
X1113489D03*
X1114415Y1363454D03*
X1111815Y1360497D03*
X1114415D03*
X1113489Y1372853D03*
X1124519D03*
X1119659D03*
X1122089D03*
X1137218Y1361660D03*
X1152315Y1357390D03*
X1154815D03*
X1147115D03*
X1149715D03*
X1141915D03*
X1144515D03*
X1147115Y1360497D03*
X1149715Y1363454D03*
Y1360497D03*
X1147115Y1363454D03*
X1146189Y1372853D03*
X1148619D03*
Y1367253D03*
X1146189D03*
X1141915Y1360497D03*
X1144515D03*
X1143759Y1367253D03*
Y1372853D03*
X1152359D03*
X1154789D03*
X1157259Y1357406D03*
X1170138Y1361800D03*
X1158205Y1363394D03*
Y1360437D03*
X1157219Y1372853D03*
X1182615Y1357390D03*
X1185215D03*
X1177415D03*
X1174815D03*
X1180015D03*
X1182615Y1363454D03*
Y1360497D03*
X1180015Y1363454D03*
X1174815Y1360497D03*
X1177415D03*
X1180015D03*
X1176659Y1367253D03*
Y1372853D03*
X1179089D03*
X1181519D03*
Y1367253D03*
X1179089D03*
X1185259Y1372853D03*
X1190159Y1357406D03*
X1187715Y1357390D03*
X1191105Y1363394D03*
Y1360437D03*
X1190119Y1372853D03*
X1187689D03*
X1215415Y1357390D03*
X1212815D03*
X1210215D03*
X1207615D03*
X1202988Y1361490D03*
X1215415Y1363454D03*
Y1360497D03*
X1212815Y1363454D03*
Y1360497D03*
X1210215D03*
X1207615D03*
X1214319Y1372853D03*
X1211889D03*
X1209459D03*
Y1367253D03*
X1214319D03*
X1211889D03*
X1222959Y1357406D03*
X1220515Y1357390D03*
X1218015D03*
X1223905Y1363394D03*
Y1360437D03*
X1222919Y1372853D03*
X1220489D03*
X1218059D03*
X1245606Y1314351D03*
Y1311244D03*
X1258506D03*
X1256006D03*
X1253406Y1314351D03*
X1250806D03*
X1253406Y1311244D03*
X1250806D03*
X1248206Y1314351D03*
Y1311244D03*
X1252310Y1321107D03*
X1249880D03*
X1252310Y1326707D03*
X1253406Y1317308D03*
X1250806D03*
X1247450Y1326707D03*
Y1321107D03*
X1249880Y1326707D03*
X1256050D03*
X1258480D03*
X1261896Y1314291D03*
X1260950Y1311260D03*
X1261896Y1317248D03*
X1260910Y1326707D03*
X1288902Y1311216D03*
X1286302Y1314323D03*
X1283702D03*
X1286302Y1311216D03*
X1283702D03*
X1278502Y1314323D03*
X1281102D03*
Y1311216D03*
X1278502D03*
X1285206Y1326679D03*
X1286302Y1317280D03*
X1283702D03*
X1285206Y1321079D03*
X1282776D03*
Y1326679D03*
X1280346Y1321079D03*
Y1326679D03*
X1288946D03*
X1294792Y1314263D03*
X1291402Y1311216D03*
X1293846Y1311232D03*
X1294792Y1317220D03*
X1293806Y1326679D03*
X1291376D03*
X1316606Y1314266D03*
Y1311159D03*
X1314006Y1314266D03*
Y1311159D03*
X1319206Y1314266D03*
Y1311159D03*
X1311406Y1314266D03*
Y1311159D03*
X1315680Y1326622D03*
X1318110D03*
X1316606Y1317223D03*
X1319206D03*
X1318110Y1321022D03*
X1315680D03*
X1313250D03*
Y1326622D03*
X1333878Y637721D03*
X1327696Y1314206D03*
X1321806Y1311159D03*
X1324306D03*
X1326750Y1311175D03*
X1327696Y1317163D03*
X1326710Y1326622D03*
X1324280D03*
X1321850D03*
X1336558Y637721D03*
X1339238D03*
X1344438D03*
X1341838D03*
X1346806Y1311359D03*
X1349406D03*
X1346806Y1314466D03*
X1349406D03*
X1344206Y1311359D03*
Y1314466D03*
X1348480Y1326822D03*
X1349406Y1317423D03*
X1346050Y1321222D03*
Y1326822D03*
X1348480Y1321222D03*
X1363857Y626579D03*
X1361427D03*
X1363831Y642042D03*
X1361387Y642026D03*
X1360944Y638999D03*
Y636042D03*
X1360496Y1314406D03*
X1359550Y1311375D03*
X1352006Y1311359D03*
X1357106D03*
X1354606D03*
X1352006Y1314466D03*
X1360496Y1317363D03*
X1350910Y1326822D03*
X1352006Y1317423D03*
X1350910Y1321222D03*
X1359510Y1326822D03*
X1357080D03*
X1354650D03*
X1374887Y626579D03*
X1372457D03*
X1370027D03*
X1366287D03*
X1366331Y642042D03*
X1376731Y638935D03*
Y642042D03*
X1371531Y638935D03*
Y642042D03*
Y635978D03*
X1374887Y632179D03*
X1374131Y638935D03*
Y642042D03*
X1368931Y638935D03*
Y642042D03*
Y635978D03*
X1370027Y632179D03*
X1372457D03*
X1372149Y1334890D03*
X1379388Y1330690D03*
Y1333797D03*
X1378632Y1340553D03*
X1376788Y1330690D03*
Y1333797D03*
X1378632Y1346153D03*
X1381457Y637865D03*
X1393664Y671949D03*
Y668992D03*
X1394127Y659479D03*
X1394087Y674926D03*
X1389688Y1330690D03*
X1392132Y1330706D03*
X1393078Y1333737D03*
Y1336694D03*
X1383492Y1340553D03*
X1381062D03*
X1381988Y1336754D03*
X1384588D03*
X1387188Y1330690D03*
X1381988D03*
Y1333797D03*
X1384588Y1330690D03*
Y1333797D03*
X1381062Y1346153D03*
X1383492D03*
X1392092D03*
X1389662D03*
X1387232D03*
X1404231Y671835D03*
X1406831D03*
X1409431D03*
X1404231Y668878D03*
X1407587Y665079D03*
X1405157Y659479D03*
X1407587D03*
X1401631Y671835D03*
Y668878D03*
X1402727Y659479D03*
Y665079D03*
X1405157D03*
X1398987Y659479D03*
X1396557D03*
X1404231Y674942D03*
X1409431D03*
X1406831D03*
X1396531D03*
X1399031D03*
X1401631D03*
X1436831Y701458D03*
X1435327Y692059D03*
X1437757D03*
X1434231Y701458D03*
X1435327Y697659D03*
X1437757D03*
X1426264Y701572D03*
X1431617Y692359D03*
X1429187D03*
X1426757D03*
X1436831Y704415D03*
Y707522D03*
X1439431Y704415D03*
Y707522D03*
X1431631D03*
X1429131D03*
X1426687Y707506D03*
X1434231Y704415D03*
Y707522D03*
X1426264Y704529D03*
X1440187Y697659D03*
Y692059D03*
X1442031Y704415D03*
Y707522D03*
X1468245Y711636D03*
Y717236D03*
X1462045Y711826D03*
X1464475D03*
X1459615D03*
X1467149Y721035D03*
X1458599Y721045D03*
Y724002D03*
X1459605Y727083D03*
X1462049Y727099D03*
X1464549D03*
X1467149Y723992D03*
Y727099D03*
X1473105Y717236D03*
X1470675Y711636D03*
X1473105D03*
X1470675Y717236D03*
X1469749Y721035D03*
Y723992D03*
X1474949D03*
X1472349D03*
Y727099D03*
X1469749D03*
X1474949D03*
X1497587Y711636D03*
X1495157D03*
X1492727D03*
X1492264Y721149D03*
Y724106D03*
X1492687Y727083D03*
X1495131Y727099D03*
X1497631D03*
X1506187Y717236D03*
Y711636D03*
X1501327D03*
X1503757D03*
X1501327Y717404D03*
X1503757D03*
X1502831Y721035D03*
X1500231D03*
Y723992D03*
X1502831D03*
X1505431D03*
X1508031D03*
X1500231Y727099D03*
X1502831D03*
X1505431D03*
X1508031D03*
X1525527Y711636D03*
X1527957D03*
X1525064Y721149D03*
Y724106D03*
X1525487Y727083D03*
X1527931Y727099D03*
X1536557Y711636D03*
X1534127D03*
X1538987Y717236D03*
Y711636D03*
X1534127Y717236D03*
X1536557D03*
X1530387Y711636D03*
X1535631Y721035D03*
X1533031D03*
X1538231Y723992D03*
X1540831D03*
X1538231Y727099D03*
X1540831D03*
X1530431D03*
X1533031Y723992D03*
X1535631D03*
X1533031Y727099D03*
X1535631D03*
X1558194Y702166D03*
Y699209D03*
X1558657Y689696D03*
X1558617Y705143D03*
X1545557Y722897D03*
X1568176Y568423D03*
X1570676D03*
X1565676D03*
X1561376Y572258D03*
X1572117Y695296D03*
X1568761Y702052D03*
X1571361D03*
X1568761Y699095D03*
X1566161Y702052D03*
Y699095D03*
X1569687Y689696D03*
X1572117D03*
X1567257D03*
Y695296D03*
X1569687D03*
X1563517Y689696D03*
X1561087D03*
X1563561Y705159D03*
X1561061D03*
X1568761D03*
X1571361D03*
X1566161D03*
X1584160Y558973D03*
X1578757Y700965D03*
X1573961Y702052D03*
Y705159D03*
X1600027Y655927D03*
X1602457D03*
X1596287D03*
X1591427D03*
X1593857D03*
X1591387Y671374D03*
X1593831Y671390D03*
X1596331D03*
X1601531D03*
Y668283D03*
Y665326D03*
X1598931Y671390D03*
Y668283D03*
Y665326D03*
X1600027Y661527D03*
X1602457D03*
X1590964Y668397D03*
Y665440D03*
X1604887Y655927D03*
X1611557Y667165D03*
X1606731Y671390D03*
Y668283D03*
X1604131Y671390D03*
Y668283D03*
X1604887Y661527D03*
X1633027Y636927D03*
Y642527D03*
X1626857Y636927D03*
X1629287D03*
X1624427D03*
X1631931Y652390D03*
Y649283D03*
X1626831Y652390D03*
X1629331D03*
X1631931Y646326D03*
X1624387Y652374D03*
X1623964Y649397D03*
Y646440D03*
X1637887Y642527D03*
Y636927D03*
X1635457D03*
Y642527D03*
X1644457Y648265D03*
X1639731Y652390D03*
X1634531D03*
X1637131D03*
X1639731Y649283D03*
X1634531D03*
X1637131D03*
X1634531Y646326D03*
X1659618Y659021D03*
X1662298D03*
X1656938D03*
X1662010Y1384570D03*
X1662766Y1377814D03*
X1660166D03*
X1662766Y1374707D03*
X1660166D03*
X1651301Y1378765D03*
X1662010Y1390170D03*
X1667498Y659021D03*
X1664898D03*
X1675901Y1377594D03*
Y1380551D03*
X1666870Y1384570D03*
X1664440D03*
X1675510Y1374723D03*
X1667966Y1374707D03*
X1670566D03*
X1665366Y1377814D03*
Y1380771D03*
Y1374707D03*
X1667966Y1377814D03*
Y1380771D03*
X1673066Y1374707D03*
X1666870Y1390170D03*
X1664440D03*
X1675470D03*
X1673040D03*
X1670610D03*
X1683896Y1378765D03*
X1692948Y1377914D03*
Y1374807D03*
X1694792Y1384670D03*
X1700748Y1377914D03*
Y1380871D03*
Y1374807D03*
X1703348D03*
X1705848D03*
X1698148Y1377914D03*
X1695548D03*
X1698148Y1380871D03*
X1695548Y1374807D03*
X1698148D03*
X1699652Y1384670D03*
X1697222D03*
X1699652Y1390270D03*
X1694792D03*
X1697222D03*
X1703392D03*
X1705822D03*
X1708678Y1380621D03*
Y1377664D03*
X1708292Y1374823D03*
X1708252Y1390270D03*
X1752364Y1556323D03*
Y1559430D03*
X1744564Y1556323D03*
Y1559430D03*
X1749764Y1556323D03*
Y1559430D03*
X1747164Y1556323D03*
Y1559430D03*
X1752564Y1562537D03*
X1751518Y1566186D03*
X1746558D03*
X1749038D03*
X1749964Y1562537D03*
X1751518Y1571786D03*
X1746558D03*
X1749038D03*
X1758238Y1556238D03*
X1761108Y1556339D03*
Y1559446D03*
X1761079Y1562605D03*
X1755038Y1556238D03*
X1780307Y1559430D03*
Y1556323D03*
X1782301Y1566186D03*
Y1571786D03*
X1796838Y1556125D03*
X1788107Y1556323D03*
X1793833Y1556195D03*
X1790633D03*
X1788107Y1559430D03*
X1788307Y1562537D03*
X1787261Y1566186D03*
X1782907Y1559430D03*
Y1556323D03*
X1784781Y1566186D03*
X1785507Y1559430D03*
Y1556323D03*
X1785707Y1562537D03*
X1796257Y1561255D03*
Y1558755D03*
X1787261Y1571786D03*
X1784781D03*
X1801688Y1542371D03*
G54D207*
X539016Y274272D03*
X549016D03*
X559016D03*
X569016D03*
X579016D03*
X589016D03*
X599016D03*
G54D108*
G01X36790Y277798D02*
X34281D01*
G01X36790Y282916D02*
X34281D01*
G01X33180Y298207D02*
X35689D01*
G01X28068D02*
X33180D01*
G01Y301357D02*
X35689D01*
G01X36790Y312916D02*
X34281D01*
G01X36790Y307798D02*
X34281D01*
G01X44600Y280357D02*
X47300D01*
G01X50500Y311100D02*
X47260D01*
G01X62930Y282866D02*
Y280357D01*
G01X59780Y272357D02*
X57271D01*
G01X59780Y280357D02*
X54780D01*
G01X59780Y282866D02*
Y280357D01*
G01X63780Y298207D02*
X58668D01*
G01X66289D02*
X63780D01*
G01X66289Y301357D02*
X63780D01*
G01X62930Y312866D02*
Y310357D01*
G01X59780Y312866D02*
Y310357D01*
G01D02*
X57643D01*
X56900Y311100D01*
X54740D01*
G01X115016Y297772D02*
Y300281D01*
G01Y318206D02*
Y320715D01*
G01X120891Y521216D02*
X118407D01*
G01Y526766D02*
Y524366D01*
G01X130811Y529484D02*
X133341D01*
X134812Y530955D01*
G01X190861Y125502D02*
X184930D01*
G01X190861Y120502D02*
Y125502D01*
G01X203061D02*
X200577D01*
G01X203061Y120502D02*
Y125502D01*
G01X266975Y142892D02*
Y140114D01*
X266971Y140110D01*
G01X334339Y162580D02*
Y165170D01*
G01X333988Y593729D02*
Y590633D01*
G01X339914Y165170D02*
X337489D01*
G01X384668Y471926D02*
X382184D01*
G01X387184Y470495D02*
Y472920D01*
G01Y476070D02*
Y482395D01*
G01X389784Y476070D02*
X387184D01*
G01X382992Y1678021D02*
X387275D01*
X387324Y1678070D01*
G01X402184Y466469D02*
Y468894D01*
G01Y507101D02*
Y504676D01*
G01X397184Y507101D02*
Y504676D01*
G01X415984Y466392D02*
Y468817D01*
G01Y507024D02*
Y504599D01*
G01X411500Y510800D02*
X410984Y510284D01*
Y504599D01*
G01X427500Y510553D02*
X424784Y507837D01*
Y504522D01*
G01X428899Y225205D02*
X433124D01*
G01X429784Y466315D02*
Y468740D01*
G01X451931Y240953D02*
X458115D01*
G01X506945Y227882D02*
X511170D01*
G01X536177Y243630D02*
X529977D01*
G01X550573Y399586D02*
X553098D01*
G01X550573Y414274D02*
X553098D01*
G01Y423949D02*
X551636Y425411D01*
X547529D01*
G01X568433Y415846D02*
X565908D01*
G01X588194Y174975D02*
X585685D01*
G01X577859Y217771D02*
X580343D01*
G01X581985Y379577D02*
X579385D01*
G01X581985Y387227D02*
X579385D01*
G01X581985Y376427D02*
X579385D01*
G01X581985Y390377D02*
X579385D01*
G01X581985Y404308D02*
X579385D01*
G01X581985Y401158D02*
X579385D01*
G01X588723Y415846D02*
X586198D01*
G01X588723Y423949D02*
X586198D01*
G01X580523Y435949D02*
X583048D01*
G01X590428Y468893D02*
X588915D01*
X587500Y470308D01*
G01X590446Y479631D02*
X587795D01*
G01X590746Y1267747D02*
Y1266668D01*
G01X600520Y401728D02*
X603245D01*
G01X590552Y458461D02*
Y459586D01*
X592529Y461563D01*
G01X603346Y1270598D02*
Y1266598D01*
G01D02*
X605271D01*
X605771Y1267098D01*
G01X590746Y1266668D02*
X595253D01*
G01X590746Y1262668D02*
X595532D01*
G01X603346Y1262598D02*
X605271D01*
X605771Y1263098D01*
G01X603346Y1274598D02*
Y1270598D01*
G01Y1278598D02*
X604397D01*
X604693Y1278302D01*
X606619D01*
G01X613207Y179720D02*
Y182229D01*
G01X621310Y178684D02*
X620274Y179720D01*
X616357D01*
G01X617985Y379577D02*
X615385D01*
G01X617985Y387227D02*
X615385D01*
G01X617985Y376427D02*
X615385D01*
G01X617985Y390377D02*
X615385D01*
G01X610935Y409996D02*
X615385D01*
G01X617985Y407346D02*
X617485Y406846D01*
X615385D01*
G01X633234Y461441D02*
X635690D01*
G01X632984Y468856D02*
Y471462D01*
G01X705660Y588934D02*
Y589511D01*
X707112Y590963D01*
X711674D01*
X711845Y590792D01*
G01D02*
X714583D01*
G01X716822Y648667D02*
X715350D01*
X714836Y649181D01*
X711702D01*
G01D02*
Y646533D01*
G01X748125Y167537D02*
Y170618D01*
G01X778227Y491344D02*
X778737D01*
X779271Y491878D01*
X785895D01*
X787092Y490681D01*
G01X772000Y527437D02*
Y529862D01*
G01X792727Y439344D02*
X796333D01*
G01X786203Y447054D02*
X786235Y447086D01*
X789319D01*
X789577Y447344D01*
G01X792727Y459344D02*
X797252D01*
G01X827114Y117623D02*
X823114D01*
G01D02*
Y115224D01*
X823115Y115223D01*
G01X827593Y497912D02*
Y493049D01*
X829028Y491614D01*
G01X828259Y501027D02*
X827593Y500361D01*
Y497912D01*
G01X839360Y117507D02*
Y114863D01*
X839361Y114862D01*
G01X906597Y625912D02*
Y628426D01*
G01X909747Y625912D02*
Y628426D01*
G01X916889Y626073D02*
X909908D01*
X909747Y625912D01*
G01X928224Y264072D02*
X925468D01*
G01X988481Y521014D02*
Y516014D01*
G01Y526074D02*
Y521014D01*
G01Y531074D02*
Y526074D01*
G01X1002126Y428366D02*
X1004536D01*
X1007127Y430957D01*
Y433426D01*
G01D02*
X1003651D01*
G01X1017132Y425902D02*
X1020748D01*
G01X1030979Y298311D02*
X1033590D01*
G01X1030979Y287311D02*
X1033590D01*
G01X1150458Y1436579D02*
Y1433146D01*
G01X1166203Y74202D02*
X1168687D01*
G01X1183354Y75185D02*
Y77685D01*
G01X1176972Y83488D02*
Y86788D01*
G01X1175004Y89556D02*
X1177429D01*
G01X1175004Y93556D02*
X1177429D01*
G01X1189063Y87125D02*
X1191488D01*
G01X1189063Y91125D02*
X1191488D01*
G01X1188472Y82665D02*
Y80165D01*
G01X1195488Y91125D02*
Y93550D01*
G01X1188162Y99694D02*
X1190587D01*
G01X1202181Y128748D02*
X1199756D01*
G01X1253152Y97950D02*
X1246555D01*
G01X1275981Y87539D02*
Y85114D01*
G01X1333399Y95659D02*
Y98084D01*
G01X1341399Y95659D02*
Y98084D01*
G01X1348199Y95659D02*
Y98084D01*
G01X1360109Y95625D02*
Y98050D01*
G01X1352199Y95625D02*
Y98050D01*
G01X1455667Y128242D02*
Y125733D01*
G01X1460508Y136368D02*
X1463017D01*
G01X1460508Y139518D02*
X1463017D01*
G01X1570068Y531220D02*
Y534095D01*
G01X1588800Y303596D02*
X1586291D01*
G01X1594537D02*
X1588800D01*
G01X1601874Y536344D02*
X1604991D01*
G01X1617400Y306746D02*
X1619909D01*
G01X1611663Y303596D02*
X1617400D01*
G01X1646798Y229912D02*
X1646916Y230030D01*
X1651792D01*
X1651910Y229912D01*
G01D02*
X1654419D01*
G01X1743072Y1435005D02*
Y1432211D01*
G01X1815005Y151834D02*
Y149325D01*
G01X1819705Y163797D02*
X1817196D01*
G01X1819705Y159947D02*
X1817196D01*
X182947Y1507512D03*
X180780Y1507509D03*
X178580D03*
X186530Y1521453D03*
X185688Y1519195D03*
X186860Y1514243D03*
X177487Y1521612D03*
X177086Y1518121D03*
X178745Y1513218D03*
X186579Y1536063D03*
X177579Y1528725D03*
Y1523810D03*
X177533Y1535698D03*
Y1537898D03*
X186530Y1523953D03*
X183051Y1542425D03*
X178980Y1540317D03*
X183051Y1544625D03*
X185966Y1592380D03*
Y1624292D03*
X188254Y1507295D03*
X192979D03*
X197703D03*
X191254Y1521453D03*
X195979D03*
X200703D03*
X196309Y1514243D03*
X201033D03*
X191584D03*
X188155Y1516970D03*
X192879D03*
X197604D03*
X189730Y1519698D03*
X194454D03*
X199178D03*
X187081Y1528853D03*
X191805D03*
X196530D03*
X201254D03*
X196029Y1536063D03*
X200753D03*
X191304D03*
X188155Y1530608D03*
X192879D03*
X197604D03*
X189730Y1533336D03*
X194454D03*
X199178D03*
X195979Y1523953D03*
X196530Y1526353D03*
X191805D03*
X187081D03*
X200703Y1523953D03*
X201254Y1526353D03*
X191254Y1523953D03*
X197703Y1542641D03*
X188254D03*
X192979D03*
X198026Y1592380D03*
X193766D03*
X192006Y1602380D03*
X199786D03*
X193766Y1624292D03*
X198026D03*
X199786Y1614292D03*
X192006D03*
X202427Y1507295D03*
X207152D03*
X211876D03*
X216601D03*
X205427Y1521453D03*
X210152D03*
X214876D03*
X205758Y1514243D03*
X215206D03*
X210482D03*
X202328Y1516970D03*
X207052D03*
X211777D03*
X216501D03*
X203903Y1519698D03*
X208627D03*
X213352D03*
X205478Y1536063D03*
X210202D03*
X205978Y1528853D03*
X210703D03*
X215427D03*
X214926Y1536063D03*
X202328Y1530608D03*
X207052D03*
X211777D03*
X216501D03*
X203903Y1533336D03*
X208627D03*
X213352D03*
X205427Y1523953D03*
X205978Y1526353D03*
X210703D03*
X210152Y1523953D03*
X214876D03*
X215427Y1526353D03*
X211876Y1542641D03*
X202427D03*
X207152D03*
X216601D03*
X210086Y1592380D03*
X205826D03*
X216126Y1602380D03*
X204066D03*
X211846D03*
X205826Y1624292D03*
X210086D03*
X216126Y1614292D03*
X211846D03*
X204066D03*
X221325Y1507295D03*
X226049D03*
X230774D03*
X219601Y1521453D03*
X224325D03*
X229049D03*
X219931Y1514243D03*
X224655D03*
X229380D03*
X221226Y1516970D03*
X225950D03*
X230674D03*
X218076Y1519698D03*
X222800D03*
X227525D03*
X219651Y1536063D03*
X229100D03*
X220152Y1528853D03*
X224876D03*
X229600D03*
X224375Y1536063D03*
X221226Y1530608D03*
X225950D03*
X230674D03*
X218076Y1533336D03*
X222800D03*
X227525D03*
X220152Y1526353D03*
X224876D03*
X224325Y1523953D03*
X219601D03*
X229049D03*
X229600Y1526353D03*
X226049Y1542641D03*
X230774D03*
X221325D03*
X229946Y1592380D03*
X217886D03*
X222146D03*
X223906Y1602380D03*
X228186D03*
X229946Y1624292D03*
X222146D03*
X217886D03*
X228186Y1614292D03*
X223906D03*
X235498Y1507295D03*
X240223D03*
X244947D03*
X243223Y1521453D03*
X238498D03*
X233774D03*
X234104Y1514243D03*
X238828D03*
X243553D03*
X235399Y1516970D03*
X240123D03*
X244848D03*
X236974Y1519698D03*
X241698D03*
X246422D03*
X232249D03*
X233824Y1536063D03*
X243273D03*
X243774Y1528853D03*
X239049D03*
X234325D03*
X238548Y1536063D03*
X235399Y1530608D03*
X240123D03*
X244848D03*
X236974Y1533336D03*
X241698D03*
X246422D03*
X232249D03*
X243223Y1523953D03*
X243774Y1526353D03*
X238498Y1523953D03*
X239049Y1526353D03*
X233774Y1523953D03*
X234325Y1526353D03*
X240223Y1542641D03*
X235498D03*
X244947D03*
X242006Y1592380D03*
X234206D03*
X246266D03*
X235966Y1602380D03*
X240246D03*
X246266Y1624292D03*
X242006D03*
X234206D03*
X240246Y1614292D03*
X235966D03*
X259120Y1507295D03*
X249671D03*
X254396D03*
X253002Y1514243D03*
X257396Y1521453D03*
X252672D03*
X247947D03*
X248277Y1514243D03*
X257726D03*
X249572Y1516970D03*
X254297D03*
X259021D03*
X251147Y1519698D03*
X255871D03*
X260596D03*
X252722Y1536063D03*
X257947Y1528853D03*
X253223D03*
X248498D03*
X257446Y1536063D03*
X247997D03*
X249572Y1530608D03*
X254297D03*
X259021D03*
X251147Y1533336D03*
X255871D03*
X260596D03*
X257396Y1523953D03*
X253223Y1526353D03*
X252672Y1523953D03*
X257947Y1526353D03*
X248498D03*
X247947Y1523953D03*
X254396Y1542641D03*
X259120D03*
X249671D03*
X258326Y1592380D03*
X254066D03*
X248026Y1602380D03*
X252306D03*
X260086D03*
X258326Y1624292D03*
X254066D03*
X248026Y1614292D03*
X252306D03*
X260086D03*
X265421Y1507355D03*
X263321D03*
X262141Y1521453D03*
X266828Y1514073D03*
X266772Y1516336D03*
X262777Y1536063D03*
X267123Y1536640D03*
Y1534540D03*
X267124Y1531618D03*
X267035Y1528698D03*
X266538Y1538658D03*
X270386Y1592380D03*
X266126D03*
X264366Y1602380D03*
X272146D03*
X270386Y1624292D03*
X266126D03*
X272146Y1614292D03*
X264366D03*
X290246Y1592380D03*
X278186D03*
X282446D03*
X276426Y1602380D03*
X284206D03*
X288486D03*
X290236Y1624292D03*
X282446D03*
X278186D03*
X288486Y1614292D03*
X284206D03*
X276426D03*
X303154Y879624D03*
Y886002D03*
X305004Y882813D03*
X303154Y892380D03*
Y898758D03*
X302413Y906182D03*
Y912560D03*
Y918938D03*
Y925316D03*
Y931694D03*
Y938072D03*
Y944450D03*
Y950828D03*
Y957206D03*
Y963584D03*
Y969962D03*
Y976340D03*
Y982718D03*
Y989096D03*
Y995474D03*
Y1008230D03*
Y1001852D03*
X303594Y1030198D03*
Y1036576D03*
Y1042954D03*
Y1055710D03*
Y1049332D03*
Y1062088D03*
Y1074844D03*
Y1068466D03*
Y1081222D03*
Y1087600D03*
Y1093978D03*
Y1100356D03*
Y1106734D03*
Y1113112D03*
Y1119490D03*
Y1125868D03*
Y1132246D03*
Y1138623D03*
Y1145001D03*
Y1157757D03*
Y1151379D03*
X305549Y1521612D03*
X305148Y1518121D03*
X305641Y1528725D03*
Y1523810D03*
X305595Y1535698D03*
Y1537898D03*
X302306Y1592380D03*
X294506D03*
X296266Y1602380D03*
X300546D03*
X302306Y1624292D03*
X294516D03*
X300546Y1614292D03*
X296266D03*
X310555Y873246D03*
X317957Y879624D03*
X310555D03*
X319807Y876435D03*
X314256Y873246D03*
X310555Y886002D03*
X314256D03*
X316107Y882813D03*
Y889191D03*
X308705D03*
X319807Y882813D03*
X314256Y892380D03*
X308705Y895569D03*
Y882813D03*
X317957Y886002D03*
X319807Y889191D03*
Y895569D03*
X317957Y892380D03*
X316107Y895569D03*
X314256Y898758D03*
X316107Y901947D03*
X308705D03*
Y908325D03*
X314256Y911513D03*
X316107Y908325D03*
X319807D03*
X317957Y898758D03*
X319807Y901947D03*
X317957Y905135D03*
Y911513D03*
X314256Y905135D03*
Y917891D03*
X308705Y914702D03*
Y921080D03*
X316107D03*
X317957Y917891D03*
X319807Y921080D03*
X317957Y924269D03*
X319807Y914702D03*
X314256Y924269D03*
X316107Y914702D03*
Y940214D03*
X308705Y927458D03*
X316107D03*
X308705Y933836D03*
X314256Y930647D03*
Y937025D03*
X308705Y940214D03*
X319807Y927458D03*
X317957Y937025D03*
X319807Y940214D03*
Y933836D03*
X317957Y930647D03*
X316107Y933836D03*
X314256Y949781D03*
X316107Y946592D03*
X308705D03*
Y952970D03*
X314256Y956159D03*
X317957Y943403D03*
X319807Y946592D03*
X317957Y956159D03*
X319807Y952970D03*
X317957Y949781D03*
X316107Y952970D03*
X314256Y943403D03*
X316107Y959348D03*
X308705D03*
Y965726D03*
X316107D03*
X314256Y968915D03*
X317957Y962537D03*
X319807Y965726D03*
Y959348D03*
X317957Y968915D03*
X314256Y962537D03*
X317957Y981671D03*
X308705Y978482D03*
X316107D03*
X314256Y975293D03*
X308705Y972104D03*
X316107Y984860D03*
X308705D03*
X312406D03*
X319807D03*
X317957Y975293D03*
X319807Y978482D03*
Y972104D03*
X316107D03*
X314256Y981671D03*
X308705Y991238D03*
X310555Y988049D03*
X314256D03*
X316107Y997616D03*
X308705D03*
X314256Y994427D03*
X317957D03*
X319807Y997616D03*
X317957Y1000805D03*
X319807Y991238D03*
X314256Y1000805D03*
X316107Y991238D03*
X317957Y988049D03*
X316107Y1003994D03*
X314256Y1007183D03*
X316107Y1010372D03*
X308705D03*
Y1003994D03*
X319807Y1010372D03*
X317957Y1007183D03*
X319807Y1003994D03*
X309886Y1028056D03*
X317288D03*
X313587D03*
X320988D03*
X315437Y1031245D03*
X317288Y1040812D03*
X309886D03*
X317288Y1034434D03*
X309886D03*
X315437Y1044001D03*
X320988Y1034434D03*
X319138Y1037623D03*
X320988Y1040812D03*
X319138Y1044001D03*
X315437Y1037623D03*
X319138Y1031245D03*
X309886Y1047190D03*
X311736Y1056757D03*
X309886Y1053568D03*
X315437Y1050379D03*
X317288Y1053568D03*
Y1059946D03*
X309886D03*
X313587D03*
X320988D03*
X319138Y1050379D03*
X320988Y1053568D03*
X315437Y1056757D03*
X317288Y1047190D03*
X319138Y1056757D03*
X320988Y1047190D03*
X315437Y1063135D03*
X317288Y1072702D03*
X309886D03*
Y1066324D03*
X315437Y1069513D03*
X320988Y1072702D03*
X319138Y1063135D03*
Y1069513D03*
X320988Y1066324D03*
X317288D03*
Y1079080D03*
X309886D03*
X315437Y1082269D03*
Y1088647D03*
X309886Y1085458D03*
X319138Y1075891D03*
X320988Y1079080D03*
X319138Y1082269D03*
Y1088647D03*
X320988Y1085458D03*
X317288D03*
X315437Y1075891D03*
X309886Y1091836D03*
X317288D03*
X309886Y1104592D03*
X315437Y1101403D03*
X317288Y1098214D03*
X309886D03*
X319138Y1101403D03*
X320988Y1091836D03*
X319138Y1095025D03*
X320988Y1098214D03*
Y1104592D03*
X317288D03*
X315437Y1095025D03*
Y1107781D03*
X309886Y1110970D03*
X317288D03*
X309886Y1117348D03*
X317288D03*
X320988Y1110970D03*
X319138Y1114159D03*
X320988Y1117348D03*
X319138Y1107781D03*
X315437Y1114159D03*
X309886Y1123726D03*
X315437Y1120537D03*
Y1126915D03*
X309886Y1130103D03*
X317288D03*
X319138Y1120537D03*
X320988Y1130103D03*
X319138Y1133293D03*
Y1126915D03*
X320988Y1123726D03*
X315437Y1133293D03*
X317288Y1123726D03*
X309886Y1136481D03*
X315437Y1139670D03*
X317288Y1136481D03*
X309886Y1142859D03*
X317288Y1149237D03*
X309886D03*
X315437Y1146048D03*
X320988Y1136481D03*
X319138Y1139670D03*
X320988Y1149237D03*
X319138Y1146048D03*
X320988Y1142859D03*
X317288D03*
X315437Y1158804D03*
X317288Y1155615D03*
X309886D03*
X313587D03*
X308036Y1158804D03*
X311736Y1165182D03*
X320988Y1155615D03*
Y1161993D03*
X319138Y1152426D03*
X315437D03*
X319138Y1158804D03*
X311115Y1214093D03*
X310957Y1219126D03*
X311009Y1507514D03*
X316316Y1507295D03*
X321041D03*
X306694Y1507279D03*
X308893Y1507460D03*
X319316Y1521453D03*
X314592D03*
X313750Y1519195D03*
X314922Y1514243D03*
X319646D03*
X316217Y1516970D03*
X320941D03*
X317792Y1519698D03*
X306807Y1513218D03*
X319867Y1528853D03*
X315143D03*
X319366Y1536063D03*
X314641D03*
X316217Y1530608D03*
X320941D03*
X317792Y1533336D03*
X319867Y1526353D03*
X315143D03*
X319316Y1523953D03*
X314592D03*
X311113Y1542425D03*
X316316Y1542641D03*
X321041D03*
X311113Y1544625D03*
X307042Y1540317D03*
X318626Y1592380D03*
X306566D03*
X314366D03*
X308326Y1602380D03*
X312606D03*
X320386D03*
X314366Y1624292D03*
X318626D03*
X306566D03*
X320386Y1614292D03*
X312606D03*
X308326D03*
X327209Y876435D03*
X332760Y879624D03*
X325358D03*
X334598Y872066D03*
X327209Y882813D03*
X334610D03*
X321658Y886002D03*
X325358D03*
X330910Y882813D03*
X329059Y886002D03*
X334610Y889191D03*
X327209D03*
X334610Y895569D03*
X321658Y892380D03*
X327209Y895569D03*
X329059Y892380D03*
X323508Y889191D03*
X325358Y892380D03*
X323508Y895569D03*
X332760Y886002D03*
X330910Y889191D03*
Y895569D03*
X332760Y892380D03*
X323508Y882813D03*
X334610Y901947D03*
X321658Y898758D03*
X327209Y901947D03*
X329059Y898758D03*
X321658Y905135D03*
Y911513D03*
X329059Y905135D03*
Y911513D03*
X327209Y908325D03*
X334610Y908324D03*
X325358Y911513D03*
X323508Y901947D03*
X325358Y905135D03*
X323508Y908325D03*
X325358Y898758D03*
X330910Y908325D03*
X332760Y898758D03*
X330910Y901947D03*
X332760Y905135D03*
Y911513D03*
X334610Y914702D03*
X321658Y917891D03*
X327209Y914702D03*
X329059Y917891D03*
X334610Y921080D03*
X321658Y924269D03*
X329059D03*
X327209Y921080D03*
X323508D03*
X325358Y924269D03*
X323508Y914702D03*
X325358Y917891D03*
X332760D03*
X330910Y921080D03*
X332760Y924269D03*
X330910Y914702D03*
X334610Y927458D03*
Y933836D03*
X321658Y930647D03*
X327209Y927458D03*
Y933836D03*
X329059Y930647D03*
X334610Y940214D03*
X321658Y937025D03*
X327209Y940214D03*
X329059Y937025D03*
X323508Y927458D03*
X325358Y930647D03*
X323508Y940214D03*
Y933836D03*
X325358Y937025D03*
X330910Y927458D03*
X332760Y937025D03*
X330910Y940214D03*
Y933836D03*
X332760Y930647D03*
X329059Y956159D03*
X334610Y946592D03*
X321658Y943403D03*
Y949781D03*
X329059Y943403D03*
Y949781D03*
X327209Y946592D03*
X334610Y952970D03*
X321658Y956159D03*
X327209Y952970D03*
X325358Y943403D03*
X323508Y946592D03*
X325358Y949781D03*
X323508Y952970D03*
X325358Y956159D03*
X332760Y943403D03*
X330910Y946592D03*
X332760Y956159D03*
X330910Y952970D03*
X332760Y949781D03*
X334610Y959348D03*
Y965726D03*
X329059Y962537D03*
X327209Y965726D03*
X321658Y962537D03*
X327209Y959348D03*
X321658Y968915D03*
X329059D03*
X323508Y965726D03*
X325358Y968915D03*
X323508Y959348D03*
X325358Y962537D03*
X332760D03*
X330910Y965726D03*
Y959348D03*
X332760Y968915D03*
X334610Y972104D03*
Y978482D03*
X321658Y975293D03*
Y981671D03*
X329059Y975293D03*
X327209Y972104D03*
X332760Y981671D03*
X329059D03*
X327209Y978482D03*
X334610Y984860D03*
X327209D03*
X330910D03*
X323508D03*
Y978482D03*
X325358Y981671D03*
X323508Y972104D03*
X325358Y975293D03*
X332760D03*
X330910Y978482D03*
Y972104D03*
X334610Y991238D03*
Y997616D03*
X321658Y988049D03*
Y994427D03*
X327209Y991238D03*
X329059Y988049D03*
Y994427D03*
X327209Y997616D03*
X321658Y1000805D03*
X329059D03*
X325358Y988049D03*
X323508Y997616D03*
X325358Y1000805D03*
Y994427D03*
X332760D03*
X330910Y997616D03*
X332760Y1000805D03*
X330910Y991238D03*
X332760Y988049D03*
X323508Y991238D03*
X334610Y1003994D03*
Y1010372D03*
X321658Y1007183D03*
X327209Y1010372D03*
X329059Y1007183D03*
X327209Y1003994D03*
X323508D03*
X325358Y1007183D03*
X330910Y1010372D03*
X332760Y1007183D03*
X330910Y1003994D03*
X323508Y1010372D03*
X328390Y1028056D03*
X335791D03*
X324689D03*
X332091D03*
X322839Y1031245D03*
Y1037623D03*
Y1044001D03*
X328390Y1040812D03*
Y1034434D03*
X330240Y1031245D03*
Y1037623D03*
Y1044001D03*
X335791Y1040812D03*
Y1034434D03*
X326539Y1031245D03*
X324689Y1034434D03*
X326539Y1037623D03*
X324689Y1040812D03*
X332091Y1034434D03*
X333941Y1037623D03*
X332091Y1040812D03*
X333941Y1044001D03*
Y1031245D03*
X326540Y1044001D03*
X328390Y1047190D03*
X322839Y1050379D03*
Y1056757D03*
X326539D03*
X328390Y1053568D03*
Y1059946D03*
X324689D03*
X330240Y1050379D03*
Y1056757D03*
X335791Y1047190D03*
Y1053568D03*
Y1059946D03*
X326539Y1050379D03*
X324689Y1047190D03*
X332091Y1059946D03*
X333941Y1050379D03*
X332091Y1053568D03*
X333941Y1056757D03*
X332091Y1047190D03*
X324689Y1053568D03*
X328390Y1072702D03*
X330240Y1069513D03*
X335791Y1072702D03*
Y1066324D03*
X322839Y1063135D03*
X330240D03*
X322839Y1069513D03*
X328390Y1066324D03*
X326539Y1063135D03*
X324689Y1066324D03*
X326539Y1069513D03*
X324689Y1072702D03*
X332091D03*
X333941Y1063135D03*
Y1069513D03*
X332091Y1066324D03*
X322839Y1075891D03*
X330240D03*
X328390Y1079080D03*
X322839Y1088647D03*
X328390Y1085458D03*
X330240Y1088647D03*
X322839Y1082269D03*
X330240D03*
X335791Y1079080D03*
Y1085458D03*
X326539Y1075891D03*
X324689Y1079080D03*
X326539Y1082269D03*
X324689Y1085458D03*
X326539Y1088647D03*
X333941Y1075891D03*
X332091Y1079080D03*
X333941Y1082269D03*
Y1088647D03*
X332091Y1085458D03*
X328390Y1091836D03*
X322839Y1095025D03*
X330240D03*
X328390Y1104592D03*
Y1098214D03*
X322839Y1101403D03*
X330240D03*
X335791Y1091836D03*
Y1104592D03*
Y1098214D03*
X324689Y1104592D03*
X326539Y1095025D03*
X324689Y1098214D03*
X326539Y1101403D03*
X324689Y1091836D03*
X333941Y1101403D03*
X332091Y1091836D03*
X333941Y1095025D03*
X332091Y1098214D03*
Y1104592D03*
X322839Y1107781D03*
X330240D03*
X328390Y1110970D03*
Y1117348D03*
X330240Y1114159D03*
X322839D03*
X335791Y1110970D03*
Y1117348D03*
X326539Y1114159D03*
X324689Y1117348D03*
X326539Y1107781D03*
X324689Y1110970D03*
X332091D03*
X333941Y1114159D03*
X332091Y1117348D03*
X333941Y1107781D03*
X330240Y1126915D03*
X322839D03*
X328390Y1123726D03*
X330240Y1120537D03*
X322839D03*
Y1133293D03*
X330240D03*
X328390Y1130103D03*
X335791Y1123726D03*
X335792Y1130105D03*
X326539Y1120537D03*
X324689Y1123726D03*
X326539Y1133293D03*
Y1126915D03*
X324689Y1130103D03*
X333941Y1120537D03*
X332091Y1130103D03*
X333941Y1133293D03*
Y1126915D03*
X332091Y1123726D03*
X328390Y1142859D03*
X322839Y1139670D03*
X328390Y1136481D03*
X330240Y1139670D03*
X328390Y1149237D03*
X330240Y1146048D03*
X322839D03*
X335791Y1136481D03*
Y1142859D03*
Y1149237D03*
X324689Y1136481D03*
X326539Y1139670D03*
X324689Y1142859D03*
X326539Y1146048D03*
X324689Y1149237D03*
X332091Y1136481D03*
X333941Y1139670D03*
X332091Y1149237D03*
X333941Y1146048D03*
X332091Y1142859D03*
X328390Y1155615D03*
X330240Y1152426D03*
X322839D03*
X326539Y1158804D03*
X330240D03*
X333941D03*
X322839D03*
X328390Y1161993D03*
X330240Y1165182D03*
X335791Y1155615D03*
Y1161993D03*
X326539Y1152426D03*
X324689Y1155615D03*
X333941Y1152426D03*
X332091Y1155615D03*
Y1161993D03*
X333941Y1165182D03*
X326539D03*
X324689Y1161993D03*
X330489Y1507295D03*
X335214D03*
X325765D03*
X333489Y1521453D03*
X328765D03*
X324041D03*
X324371Y1514243D03*
X329095D03*
X333820D03*
X325666Y1516970D03*
X330390D03*
X335114D03*
X322516Y1519698D03*
X327240D03*
X331965D03*
X333540Y1536063D03*
X334040Y1528853D03*
X329316D03*
X324592D03*
X324091Y1536063D03*
X328815D03*
X325666Y1530608D03*
X330390D03*
X335114D03*
X322516Y1533336D03*
X327240D03*
X331965D03*
X324041Y1523953D03*
X324592Y1526353D03*
X328765Y1523953D03*
X329316Y1526353D03*
X334040D03*
X333489Y1523953D03*
X325765Y1542641D03*
X330489D03*
X335214D03*
X330686Y1592380D03*
X326426D03*
X324666Y1602380D03*
X332446D03*
X326426Y1624292D03*
X330686D03*
X332446Y1614292D03*
X324666D03*
X343862Y879624D03*
X340162Y879568D03*
X345713Y882813D03*
X336461Y886002D03*
X340162D03*
X347563D03*
X342012Y882813D03*
X347563Y892380D03*
X342012Y889191D03*
X340162Y892380D03*
X343862Y886002D03*
X349414Y889191D03*
X345713D03*
Y895569D03*
X349414D03*
X343862Y892380D03*
X338311Y889191D03*
X336461Y892380D03*
X338311Y895569D03*
X342012D03*
X347563Y898758D03*
Y905135D03*
Y911513D03*
X342012Y901947D03*
X340162Y898758D03*
Y911513D03*
X342012Y908325D03*
X345713D03*
X343862Y898758D03*
X349414Y901947D03*
X345713D03*
X343862Y905135D03*
X349414Y908325D03*
X343862Y911513D03*
X336461D03*
X338311Y901947D03*
X336461Y905135D03*
X338311Y908325D03*
X336461Y898758D03*
X340162Y905135D03*
X347563Y917891D03*
Y924269D03*
X340162Y917891D03*
X342012Y921080D03*
X343862Y917891D03*
X349414Y921080D03*
X345713D03*
X343862Y924269D03*
X345713Y914702D03*
X349414D03*
X338311Y921080D03*
X336461Y924269D03*
X338311Y914702D03*
X336461Y917891D03*
X340162Y924269D03*
X342012Y914702D03*
X347563Y930647D03*
Y937025D03*
X342012Y927458D03*
X340162Y930647D03*
X342012Y940214D03*
X340162Y937025D03*
X349414Y927458D03*
X345713D03*
X343862Y937025D03*
X349414Y940214D03*
X345713D03*
Y933836D03*
X349414D03*
X343862Y930647D03*
X338311Y927458D03*
X336461Y930647D03*
X338311Y940214D03*
Y933836D03*
X336461Y937025D03*
X342012Y933836D03*
X347563Y943403D03*
Y949781D03*
Y956159D03*
X340162Y949781D03*
X342012Y946592D03*
X340162Y956159D03*
X343862Y943403D03*
X349414Y946592D03*
X345713D03*
X343862Y956159D03*
X345713Y952970D03*
X349414D03*
X343862Y949781D03*
X336461Y943403D03*
X338311Y946592D03*
X336461Y949781D03*
X338311Y952970D03*
X336461Y956159D03*
X342012Y952970D03*
X340162Y943403D03*
X347563Y962537D03*
Y968915D03*
X342012Y959348D03*
Y965726D03*
X340162Y968915D03*
X343862Y962537D03*
X349414Y965726D03*
X345713D03*
X349414Y959348D03*
X345713D03*
X343862Y968915D03*
X338311Y965726D03*
X336461Y968915D03*
X338311Y959348D03*
X336461Y962537D03*
X340162D03*
X347563Y975293D03*
Y981671D03*
X345713Y984860D03*
X340162Y975293D03*
X343862Y981671D03*
X342012Y978482D03*
Y984860D03*
X349414D03*
X343862Y975293D03*
X349414Y978482D03*
X345713D03*
Y972104D03*
X349414D03*
X338311Y984860D03*
Y978482D03*
X336461Y981671D03*
X338311Y972104D03*
X336461Y975293D03*
X342012Y972104D03*
X340162Y981671D03*
X347563Y988049D03*
Y994427D03*
Y1000805D03*
X340162Y988049D03*
X342012Y997616D03*
X340162Y994427D03*
X343862D03*
X345713Y997616D03*
X349414D03*
X343862Y1000805D03*
X345713Y991238D03*
X336461Y988049D03*
X338311Y997616D03*
X336461Y1000805D03*
Y994427D03*
X340162Y1000805D03*
X342012Y991238D03*
X338311D03*
X349414D03*
X343862Y988049D03*
X347563Y1007183D03*
X342012Y1010372D03*
X340162Y1007183D03*
X342012Y1003994D03*
X345713Y1010372D03*
X343862Y1007183D03*
X345713Y1003994D03*
X349414D03*
X338311D03*
X336461Y1007183D03*
X338311Y1010372D03*
X349414D03*
X343193Y1028056D03*
X350595D03*
X339492D03*
X346894D03*
X348744Y1031245D03*
X341343D03*
X343193Y1040812D03*
X348744Y1037623D03*
X343193Y1034434D03*
X348744Y1044001D03*
X341343D03*
X350595Y1034434D03*
X346894D03*
X345043Y1037623D03*
X350595Y1040812D03*
X346894D03*
X345043Y1044001D03*
X337642Y1031245D03*
X339492Y1034434D03*
X337642Y1037623D03*
X339492Y1040812D03*
X341343Y1037623D03*
X337642Y1044001D03*
X345043Y1031245D03*
X350595Y1059946D03*
X337642Y1056757D03*
X348744D03*
X343193Y1053568D03*
X341343Y1050379D03*
X348744D03*
X343193Y1059946D03*
X339492D03*
X346894D03*
X350595Y1047190D03*
X345043Y1050379D03*
X346894Y1053568D03*
X337642Y1050379D03*
X339492Y1047190D03*
X341343Y1056757D03*
X343193Y1047190D03*
X339492Y1053568D03*
X345043Y1056757D03*
X346894Y1047190D03*
X350595Y1053568D03*
X341343Y1063135D03*
X348744D03*
X341343Y1069513D03*
X343193Y1072702D03*
X348744Y1069513D03*
X346894Y1072702D03*
X345043Y1063135D03*
X350595Y1066324D03*
X345043Y1069513D03*
X350595Y1072702D03*
X346894Y1066324D03*
X337642Y1063135D03*
X339492Y1066324D03*
X337642Y1069513D03*
X339492Y1072702D03*
X343193Y1066324D03*
Y1079080D03*
X348744Y1075891D03*
X341343Y1082269D03*
X348744D03*
X341343Y1088647D03*
X348744D03*
X345043Y1075891D03*
X350595Y1079080D03*
X346894D03*
X345043Y1082269D03*
X350595Y1085458D03*
X345043Y1088647D03*
X346894Y1085458D03*
X337642Y1075891D03*
X339492Y1079080D03*
X337642Y1082269D03*
X339492Y1085458D03*
X337642Y1088647D03*
X343193Y1085458D03*
X341343Y1075891D03*
X348744Y1095025D03*
X343193Y1091836D03*
X348744Y1101403D03*
X341343D03*
X343193Y1098214D03*
X345043Y1101403D03*
X350595Y1104592D03*
X346894Y1091836D03*
X345043Y1095025D03*
X350595Y1098214D03*
X346894D03*
Y1104592D03*
X350595Y1091836D03*
X339492Y1104592D03*
X337642Y1095025D03*
X339492Y1098214D03*
X337642Y1101403D03*
X339492Y1091836D03*
X341343Y1095025D03*
X343193Y1104592D03*
X341343Y1107781D03*
X348744D03*
X343193Y1110970D03*
Y1117348D03*
X348744Y1114159D03*
X346894Y1110970D03*
X345043Y1114159D03*
X350595Y1117348D03*
X346894D03*
X345043Y1107781D03*
X350595Y1110970D03*
X337642Y1114159D03*
X339492Y1117348D03*
X337642Y1107781D03*
X339492Y1110970D03*
X341343Y1114159D03*
X348744Y1120537D03*
X341343D03*
Y1126915D03*
X348744D03*
Y1133293D03*
X343193Y1130103D03*
X345043Y1120537D03*
X350595Y1123726D03*
X346894Y1130103D03*
X345043Y1133293D03*
Y1126915D03*
X346894Y1123726D03*
X350595Y1130103D03*
X337642Y1120537D03*
X339492Y1123726D03*
X337642Y1133293D03*
Y1126915D03*
X339492Y1130103D03*
X343193Y1123726D03*
X341343Y1133293D03*
Y1139670D03*
X343193Y1136481D03*
X348744Y1139670D03*
X343193Y1149237D03*
X348744Y1146048D03*
X341343D03*
X350595Y1136481D03*
X346894D03*
X345043Y1139670D03*
X350595Y1142859D03*
X346894Y1149237D03*
X345043Y1146048D03*
X346894Y1142859D03*
X350595Y1149237D03*
X339492Y1136481D03*
X337642Y1139670D03*
X339492Y1142859D03*
X337642Y1146048D03*
X339492Y1149237D03*
X343193Y1142859D03*
X348744Y1152426D03*
X337642Y1158804D03*
X341343D03*
X348744D03*
X339492Y1155615D03*
X343193D03*
X346894D03*
X337642Y1165182D03*
X343193Y1161993D03*
X346894D03*
X348744Y1165182D03*
X345043Y1152426D03*
X350595Y1155615D03*
X337642Y1152426D03*
X339492Y1161993D03*
X341343Y1165182D03*
X350595Y1161993D03*
X341343Y1152426D03*
X345043Y1158804D03*
X339938Y1507295D03*
X344663D03*
X349387D03*
X347663Y1521453D03*
X342938D03*
X338214D03*
X338544Y1514243D03*
X343268D03*
X347993D03*
X339839Y1516970D03*
X344563D03*
X349288D03*
X336689Y1519698D03*
X341414D03*
X346138D03*
X350862D03*
X338264Y1536063D03*
X347713D03*
X348214Y1528853D03*
X343489D03*
X338765D03*
X342988Y1536063D03*
X339839Y1530608D03*
X344563D03*
X349288D03*
X336689Y1533336D03*
X341414D03*
X346138D03*
X350862D03*
X338765Y1526353D03*
X338214Y1523953D03*
X347663D03*
X348214Y1526353D03*
X343489D03*
X342938Y1523953D03*
X339938Y1542641D03*
X344663D03*
X349387D03*
X338486Y1592380D03*
X342746D03*
X350546D03*
X336726Y1602380D03*
X344506D03*
X348786D03*
X350546Y1624292D03*
X342746D03*
X338486D03*
X348786Y1614292D03*
X344506D03*
X336726D03*
X351265Y879568D03*
X360516Y876435D03*
X354965Y879624D03*
X356803Y872066D03*
X364217Y876435D03*
X358665Y879624D03*
X351264Y886002D03*
X362366D03*
X356815Y882813D03*
X360516D03*
X353114D03*
X354965Y886002D03*
Y892380D03*
X360516Y889191D03*
Y895569D03*
X353114Y889191D03*
Y895569D03*
X351264Y892380D03*
X358665Y886002D03*
X364217Y889191D03*
X356815D03*
X362366Y892380D03*
X356815Y895569D03*
X364217D03*
X358665Y892380D03*
X354965Y898758D03*
X360516Y901947D03*
X353114D03*
X354965Y911513D03*
Y905135D03*
X360516Y908325D03*
X353114Y908324D03*
X351264Y911513D03*
Y905135D03*
Y898758D03*
X356815Y908325D03*
X362366Y911513D03*
X358665Y898758D03*
X364217Y901947D03*
X356815D03*
X362366Y905135D03*
X358665D03*
X364217Y908325D03*
X358665Y911513D03*
X362366Y898758D03*
X354965Y917891D03*
X360516Y914702D03*
X353114D03*
X354965Y924269D03*
X360516Y921080D03*
X353114D03*
X351264Y924269D03*
Y917891D03*
X358665D03*
X364217Y921080D03*
X356815D03*
X362366Y924269D03*
X358665D03*
X356815Y914702D03*
X364217D03*
X362366Y917891D03*
X354965Y930647D03*
X360516Y927458D03*
Y933836D03*
X353114D03*
Y927458D03*
X354965Y937025D03*
X360516Y940214D03*
X353114D03*
X351264Y930647D03*
Y937025D03*
X364217Y927458D03*
X356815D03*
X362366Y930647D03*
X358665Y937025D03*
X364217Y940214D03*
X356815D03*
Y933836D03*
X364217D03*
X358665Y930647D03*
X362366Y937025D03*
X360516Y946592D03*
X353114D03*
X360516Y952970D03*
X353114D03*
X354965Y956159D03*
Y943403D03*
Y949781D03*
X351264Y943403D03*
Y949781D03*
Y956159D03*
X362366Y943403D03*
X358665D03*
X364217Y946592D03*
X356815D03*
X362366Y949781D03*
X358665Y956159D03*
X356815Y952970D03*
X364217D03*
X358665Y949781D03*
X362366Y956159D03*
X360516Y959348D03*
Y965726D03*
X353114Y959348D03*
Y965726D03*
X354965Y962537D03*
Y968915D03*
X351264D03*
Y962537D03*
X358665D03*
X364217Y965726D03*
X356815D03*
X362366Y968915D03*
X364217Y959348D03*
X356815D03*
X362366Y962537D03*
X358665Y968915D03*
X354965Y975293D03*
Y981671D03*
X360516Y972104D03*
Y978482D03*
X358665Y981671D03*
X353114Y972104D03*
Y978482D03*
X360516Y984860D03*
X356815D03*
X353114D03*
X351264Y981671D03*
Y975293D03*
X364217Y984860D03*
X358665Y975293D03*
X364217Y978482D03*
X356815D03*
X362366Y981671D03*
X356815Y972104D03*
X364217D03*
X362366Y975293D03*
X360516Y997616D03*
Y991238D03*
X353114D03*
Y997616D03*
X354965Y988049D03*
Y994427D03*
Y1000805D03*
X351264Y988049D03*
Y1000805D03*
Y994427D03*
X362366Y988049D03*
X358665Y994427D03*
X356815Y997616D03*
X364217D03*
X362366Y1000805D03*
X358665D03*
X356815Y991238D03*
X362366Y994427D03*
X364217Y991238D03*
X358666Y988049D03*
X354965Y1007183D03*
X360516Y1003994D03*
X353114D03*
X360516Y1010372D03*
X353114D03*
X351264Y1007183D03*
X356815Y1010372D03*
X358665Y1007183D03*
X356815Y1003994D03*
X364217D03*
X362366Y1007183D03*
X364217Y1010372D03*
X354295Y1028056D03*
X361697D03*
X365398D03*
X357996D03*
X361697Y1040812D03*
X356146Y1044001D03*
X354295Y1040812D03*
Y1034434D03*
X356146Y1031245D03*
Y1037623D03*
X361697Y1034434D03*
X352445Y1031245D03*
Y1037623D03*
X363547Y1031245D03*
X365398Y1034434D03*
X357996D03*
X359847Y1037623D03*
X363547D03*
X365398Y1040812D03*
X357996D03*
X359847Y1044001D03*
X363547D03*
X359847Y1031245D03*
X352445Y1044001D03*
X354295Y1047190D03*
X361697D03*
X354295Y1053568D03*
Y1059946D03*
X363547Y1056757D03*
X356146D03*
Y1050379D03*
X361697Y1053568D03*
X365398Y1059946D03*
X361697D03*
X352445Y1056757D03*
Y1050379D03*
X363547D03*
X357996Y1059946D03*
X365398Y1047190D03*
X359847Y1050379D03*
X357996Y1053568D03*
X359847Y1056757D03*
X357996Y1047190D03*
X365398Y1053568D03*
X356146Y1063135D03*
X354295Y1072702D03*
Y1066324D03*
X356146Y1069513D03*
X361697Y1066324D03*
Y1072702D03*
X352445Y1063135D03*
Y1069513D03*
X357996Y1072702D03*
X363547Y1063135D03*
X359847D03*
X365398Y1066324D03*
X363547Y1069513D03*
X359847D03*
X365398Y1072702D03*
X357996Y1066324D03*
X356146Y1075891D03*
X354295Y1079080D03*
X361697D03*
X354295Y1085458D03*
X356146Y1088647D03*
X361697Y1085458D03*
X356146Y1082269D03*
X352445Y1075891D03*
Y1082269D03*
Y1088647D03*
X363547Y1075891D03*
X359847D03*
X365398Y1079080D03*
X357996D03*
X363547Y1082269D03*
X359847D03*
X365398Y1085458D03*
X359847Y1088647D03*
X363547D03*
X357996Y1085458D03*
X354295Y1091836D03*
X361697D03*
X356146Y1095025D03*
X354295Y1104592D03*
Y1098214D03*
X361697Y1104592D03*
X356146Y1101403D03*
X361697Y1098214D03*
X352445Y1095025D03*
Y1101403D03*
X359847D03*
X365398Y1104592D03*
X357996Y1091836D03*
X363547Y1095025D03*
X359847D03*
X365398Y1098214D03*
X357996D03*
X363547Y1101403D03*
X357996Y1104592D03*
X365398Y1091836D03*
X356146Y1107781D03*
X354295Y1110970D03*
X361697D03*
Y1117348D03*
X356146Y1114159D03*
X354295Y1117348D03*
X352445Y1114159D03*
Y1107781D03*
X357996Y1110970D03*
X363547Y1114159D03*
X359847D03*
X365398Y1117348D03*
X357996D03*
X359847Y1107781D03*
X363547D03*
X365398Y1110970D03*
X354295Y1123726D03*
X356146Y1126915D03*
Y1120537D03*
X361697Y1123726D03*
X356146Y1133293D03*
X361697Y1130103D03*
X354296Y1130105D03*
X352445Y1120537D03*
Y1133293D03*
Y1126915D03*
X363547Y1120537D03*
X359847D03*
X365398Y1123726D03*
X357996Y1130103D03*
X363547Y1133293D03*
X359847D03*
Y1126915D03*
X363547D03*
X357996Y1123726D03*
X365398Y1130103D03*
X354295Y1136481D03*
X356146Y1139670D03*
X361697Y1136481D03*
X354295Y1142859D03*
X361697D03*
Y1149237D03*
X356146Y1146048D03*
X354295Y1149237D03*
X352445Y1139670D03*
Y1146048D03*
X365398Y1136481D03*
X357996D03*
X363547Y1139670D03*
X359847D03*
X365398Y1142859D03*
X357996Y1149237D03*
X359847Y1146048D03*
X363547D03*
X357996Y1142859D03*
X365398Y1149237D03*
X363547Y1165182D03*
X356146D03*
X361697Y1161993D03*
X363547Y1158804D03*
X356146D03*
X359847D03*
X352445D03*
X365398Y1155615D03*
X356146Y1152426D03*
X361697Y1155615D03*
X354295D03*
Y1161993D03*
X352445Y1152426D03*
X363547D03*
X359847D03*
X357996Y1155615D03*
X359847Y1165182D03*
X357996Y1161993D03*
X352445Y1165182D03*
X365398Y1161993D03*
X354111Y1507295D03*
X358836D03*
X363560D03*
X361836Y1521453D03*
X357111D03*
X352387D03*
X352717Y1514243D03*
X357442D03*
X362166D03*
X363461Y1516970D03*
X354012D03*
X358736D03*
X365036Y1519698D03*
X355587D03*
X360311D03*
X357162Y1536063D03*
X361886D03*
X362387Y1528853D03*
X357662D03*
X352938D03*
X352437Y1536063D03*
X363461Y1530608D03*
X354012D03*
X358736D03*
X365036Y1533336D03*
X355587D03*
X360311D03*
X362387Y1526353D03*
X361836Y1523953D03*
X352387D03*
X352938Y1526353D03*
X357662D03*
X357111Y1523953D03*
X354111Y1542641D03*
X358836D03*
X363560D03*
X362606Y1592380D03*
X354806D03*
X356566Y1602380D03*
X360846D03*
X354806Y1624292D03*
X360846Y1614292D03*
X356566D03*
X362606Y1624292D03*
X369768Y879624D03*
X373469D03*
X375319Y876435D03*
X377169Y879624D03*
X367917Y876435D03*
X371618D03*
X379020D03*
X369768Y873246D03*
X373469D03*
X377169D03*
X366067Y886002D03*
Y892380D03*
X367917Y889191D03*
X373469Y892380D03*
X367917Y882813D03*
X373469Y886002D03*
X379020Y882813D03*
X377169Y886002D03*
X379020Y895569D03*
X369768Y886002D03*
X375319Y889191D03*
X371618D03*
X377169Y892380D03*
X371618Y895569D03*
X375319D03*
X369768Y892380D03*
X371618Y882813D03*
X375319D03*
X379020Y889191D03*
X367917Y895569D03*
X366067Y898758D03*
Y911513D03*
X367917Y901947D03*
X373469Y898758D03*
X379020Y908325D03*
X373469Y911513D03*
Y905135D03*
X367917Y908324D03*
X371618Y908325D03*
X377169Y911513D03*
X369768Y898758D03*
X375319Y901947D03*
X371618D03*
X377169Y905135D03*
X369768D03*
X375319Y908325D03*
X369768Y911513D03*
X377169Y898758D03*
X366067Y905135D03*
X379020Y901947D03*
X366067Y917891D03*
X373469D03*
X367917Y921080D03*
X373469Y924269D03*
X379020Y921080D03*
X369768Y917891D03*
X375319Y921080D03*
X371618D03*
X377169Y924269D03*
X369768D03*
X371618Y914702D03*
X375319D03*
X377169Y917891D03*
X366067Y924269D03*
X367917Y914702D03*
X379020D03*
X366067Y930647D03*
Y937025D03*
X367917Y927458D03*
X379020Y933836D03*
X373469Y930647D03*
X367917Y940214D03*
X373469Y937025D03*
X379020Y940214D03*
X375319Y927458D03*
X371618D03*
X377169Y930647D03*
X369768Y937025D03*
X375319Y940214D03*
X371618D03*
Y933836D03*
X375319D03*
X369768Y930647D03*
X377169Y937025D03*
X367917Y933836D03*
X379020Y927458D03*
X366067Y949781D03*
Y956159D03*
X367917Y946592D03*
X373469Y943403D03*
Y949781D03*
Y956159D03*
X379020Y952970D03*
X377169Y943403D03*
X369768D03*
X375319Y946592D03*
X371618D03*
X377169Y949781D03*
X369768Y956159D03*
X371618Y952970D03*
X375319D03*
X369768Y949781D03*
X377169Y956159D03*
X366067Y943403D03*
X367917Y952970D03*
X379020Y946592D03*
X366067Y968915D03*
X367917Y959348D03*
Y965726D03*
X373469Y962537D03*
Y968915D03*
X379020Y965726D03*
X369768Y962537D03*
X375319Y965726D03*
X371618D03*
X377169Y968915D03*
X375319Y959348D03*
X371618D03*
X377169Y962537D03*
X369768Y968915D03*
X366067Y962537D03*
X379020Y959348D03*
X366067Y975293D03*
X369768Y981671D03*
X367917Y978482D03*
X373469Y975293D03*
Y981671D03*
X367917Y984860D03*
X379020D03*
X371618D03*
X379020Y978482D03*
X375319Y984860D03*
X369768Y975293D03*
X375319Y978482D03*
X371618D03*
X377169Y981671D03*
X371618Y972104D03*
X375319D03*
X377169Y975293D03*
X366067Y981671D03*
X367917Y972104D03*
X379020D03*
X366067Y994427D03*
Y988049D03*
X367917Y997616D03*
X379020Y991238D03*
X373469Y988049D03*
X379020Y997616D03*
X373469Y994427D03*
Y1000805D03*
X377169Y988049D03*
X369768Y994427D03*
X371618Y997616D03*
X375319D03*
X377169Y1000805D03*
X369768D03*
X371618Y991238D03*
X377169Y994427D03*
X366067Y1000805D03*
X367917Y991238D03*
X375319D03*
X369768Y988049D03*
X366067Y1007183D03*
X373469D03*
X367917Y1003994D03*
X379020D03*
X367917Y1010372D03*
X371618D03*
X369768Y1007183D03*
X371618Y1003994D03*
X375319D03*
X377169Y1007183D03*
X379020Y1010372D03*
X375319D03*
X380201Y1028056D03*
X369099D03*
X376500D03*
X372799D03*
X367248Y1031245D03*
Y1044001D03*
X369099Y1034434D03*
Y1040812D03*
X374650Y1031245D03*
X380201Y1040812D03*
Y1034434D03*
X374650Y1037623D03*
Y1044001D03*
X378351Y1031245D03*
X376500Y1034434D03*
X372799D03*
X370949Y1037623D03*
X378351D03*
X376500Y1040812D03*
X372799D03*
X370949Y1044001D03*
X367248Y1037623D03*
X378351Y1044001D03*
X370949Y1031245D03*
X367248Y1050379D03*
X380201Y1047190D03*
X369099Y1053568D03*
Y1059946D03*
X380201Y1053568D03*
X378351Y1056757D03*
X374650Y1050379D03*
Y1056757D03*
X380201Y1059946D03*
X376500D03*
X378351Y1050379D03*
X372799Y1059946D03*
X376500Y1047190D03*
X370949Y1050379D03*
X372799Y1053568D03*
X367248Y1056757D03*
X369099Y1047190D03*
X370949Y1056757D03*
X372799Y1047190D03*
X376500Y1053568D03*
X367248Y1063135D03*
Y1069513D03*
X374650Y1063135D03*
X369099Y1072702D03*
X380201D03*
X374650Y1069513D03*
X372799Y1072702D03*
X378351Y1063135D03*
X370949D03*
X376500Y1066324D03*
X378351Y1069513D03*
X370949D03*
X376500Y1072702D03*
X372799Y1066324D03*
X369099D03*
X380201D03*
X367248Y1088647D03*
Y1082269D03*
X374650Y1075891D03*
X369099Y1079080D03*
X380201Y1085458D03*
X374650Y1088647D03*
Y1082269D03*
X378351Y1075891D03*
X370949D03*
X376500Y1079080D03*
X372799D03*
X378351Y1082269D03*
X370949D03*
X376500Y1085458D03*
X370949Y1088647D03*
X378351D03*
X372799Y1085458D03*
X367248Y1075891D03*
X369099Y1085458D03*
X380201Y1079080D03*
X367248Y1101403D03*
X369099Y1091836D03*
X374650Y1095025D03*
X369099Y1098214D03*
X380201Y1104592D03*
Y1098214D03*
X374650Y1101403D03*
X370949D03*
X376500Y1104592D03*
X372799Y1091836D03*
X378351Y1095025D03*
X370949D03*
X376500Y1098214D03*
X372799D03*
X378351Y1101403D03*
X372799Y1104592D03*
X376500Y1091836D03*
X380201D03*
X367248Y1095025D03*
X369099Y1104592D03*
X367248Y1107781D03*
X374650D03*
X369099Y1110970D03*
Y1117348D03*
X380201D03*
X374650Y1114159D03*
X372799Y1110970D03*
X378351Y1114159D03*
X370949D03*
X376500Y1117348D03*
X372799D03*
X370949Y1107781D03*
X378351D03*
X376500Y1110970D03*
X367248Y1114159D03*
X380201Y1110970D03*
X367248Y1120537D03*
Y1126915D03*
X374650Y1120537D03*
Y1126915D03*
X380201Y1130103D03*
X374650Y1133293D03*
X369099Y1130103D03*
X378351Y1120537D03*
X370949D03*
X376500Y1123726D03*
X372799Y1130103D03*
X378351Y1133293D03*
X370949D03*
Y1126915D03*
X378351D03*
X372799Y1123726D03*
X376500Y1130103D03*
X369099Y1123726D03*
X367248Y1133293D03*
X380201Y1123726D03*
X367248Y1139670D03*
Y1146048D03*
X380201Y1142859D03*
X374650Y1139670D03*
X369099Y1136481D03*
Y1149237D03*
X374650Y1146048D03*
X376500Y1136481D03*
X372799D03*
X378351Y1139670D03*
X370949D03*
X376500Y1142859D03*
X372799Y1149237D03*
X370949Y1146048D03*
X378351D03*
X372799Y1142859D03*
X376500Y1149237D03*
X380201D03*
X369099Y1142859D03*
X380201Y1136481D03*
X378351Y1165182D03*
X374650D03*
X380201Y1155615D03*
X369099D03*
X372799D03*
X374650Y1152426D03*
X378351Y1158804D03*
X374650D03*
X376500Y1161993D03*
X378351Y1152426D03*
X370949D03*
X376500Y1155615D03*
X367248Y1158804D03*
X370949D03*
X369099Y1161993D03*
X372799D03*
X380201D03*
X367248Y1152426D03*
X377523Y1222274D03*
X372730Y1216782D03*
X367697Y1216624D03*
X377733Y1507295D03*
X368285D03*
X373009D03*
X376009Y1521453D03*
X380734D03*
X366560D03*
X371285D03*
X376339Y1514243D03*
X366890D03*
X371615D03*
X368185Y1516970D03*
X372910D03*
X377634D03*
X369760Y1519698D03*
X374484D03*
X379209D03*
X380784Y1536063D03*
X371335D03*
X376560Y1528853D03*
X367111D03*
X371836D03*
X376059Y1536063D03*
X366610D03*
X368185Y1530608D03*
X372910D03*
X377634D03*
X369760Y1533336D03*
X374484D03*
X379209D03*
X380734Y1523953D03*
X376560Y1526353D03*
X376009Y1523953D03*
X371285D03*
X371836Y1526353D03*
X367111D03*
X366560Y1523953D03*
X377733Y1542641D03*
X368285D03*
X373009D03*
X374666Y1592380D03*
X366866D03*
X380696Y1602380D03*
X368626Y1602286D03*
X372906Y1602380D03*
X374666Y1624292D03*
X380696Y1614292D03*
X372906D03*
X368626D03*
X366866Y1624292D03*
X386421Y876435D03*
X388272Y879624D03*
X384571Y873246D03*
X393823Y876435D03*
X382721D03*
X390122D03*
X380870Y879624D03*
X384571D03*
X380870Y873246D03*
X391973D03*
X395673D03*
Y879624D03*
X391973D03*
X388272Y892380D03*
X384571D03*
X395673D03*
X382721Y882813D03*
Y889191D03*
X380870Y892380D03*
X384571Y886002D03*
X386421Y882813D03*
X393823D03*
X388272Y886002D03*
X390122Y882813D03*
X391973Y892380D03*
X390122Y895569D03*
X386421Y889191D03*
X393823D03*
X391973Y886002D03*
X393823Y895569D03*
X380870Y886002D03*
X382721Y895569D03*
X390122Y889191D03*
X386421Y895569D03*
X395673Y886002D03*
X388272Y911513D03*
Y898758D03*
Y905135D03*
X384571Y911513D03*
Y898758D03*
Y905135D03*
X395673Y898758D03*
Y905135D03*
Y911513D03*
X382721Y901947D03*
X380870Y898758D03*
Y911513D03*
Y905135D03*
X393823Y901947D03*
X391973Y898758D03*
X390122Y901947D03*
X386421D03*
X391973Y905135D03*
Y911513D03*
X390122Y908325D03*
X393823D03*
X386421D03*
X382721D03*
X388272Y924269D03*
Y917891D03*
X384571Y924269D03*
Y917891D03*
X395673Y924269D03*
Y917891D03*
X382721Y914702D03*
X380870Y917891D03*
Y924269D03*
X386421Y914702D03*
X391973Y917891D03*
X393823Y914702D03*
X390122D03*
Y921080D03*
X391973Y924269D03*
X393823Y921080D03*
X382721D03*
X386421D03*
X388272Y930647D03*
X384571D03*
X395673D03*
X382721Y927458D03*
Y933836D03*
X380870Y930647D03*
X386421Y927458D03*
Y933836D03*
X393823Y927458D03*
X390122D03*
X393823Y933836D03*
X391973Y930647D03*
X390122Y933836D03*
Y940214D03*
X393823D03*
X382721D03*
X386421D03*
X380870Y937025D03*
X395673D03*
X388272D03*
X391973D03*
X384571D03*
Y949781D03*
Y943403D03*
Y956159D03*
X395673Y949781D03*
Y943403D03*
Y956159D03*
X388272Y949781D03*
Y943403D03*
Y956159D03*
X382721Y946592D03*
X380870Y943403D03*
Y949781D03*
Y956159D03*
X386421Y946592D03*
X391973Y943403D03*
Y949781D03*
X393823Y946592D03*
X390122D03*
X391973Y956159D03*
X390122Y952970D03*
X393823D03*
X382721D03*
X386421D03*
X382721Y959348D03*
X380870Y962537D03*
Y968915D03*
X393823Y959348D03*
X390122D03*
Y965726D03*
X386421Y959348D03*
X391973Y962537D03*
Y968915D03*
X393823Y965726D03*
X382721D03*
X386421D03*
X395673Y962537D03*
Y968915D03*
X384571Y962537D03*
Y968915D03*
X388272Y962537D03*
Y968915D03*
X386421Y984860D03*
X382721Y972104D03*
X380870Y975293D03*
X393823Y972104D03*
X390122D03*
Y978482D03*
X384571Y981671D03*
X391973D03*
Y975293D03*
X386421Y972104D03*
X393823Y984860D03*
X380870Y981671D03*
X382721Y984860D03*
X388272Y981671D03*
X390122Y984860D03*
X386421Y978482D03*
X393823D03*
X395673Y981671D03*
X382721Y978482D03*
X395673Y975293D03*
X384571D03*
X388272D03*
X391973Y988049D03*
X384571Y994427D03*
Y988049D03*
X391973Y994427D03*
X393823Y991238D03*
X386421D03*
Y997616D03*
X391973Y1000805D03*
X384571D03*
X393823Y997616D03*
X395673Y994427D03*
Y988049D03*
Y1000805D03*
X380870Y988049D03*
Y994427D03*
X382721Y997616D03*
Y991238D03*
X380870Y1000805D03*
X388272Y994427D03*
X390122Y997616D03*
X388272Y988049D03*
X390122Y991238D03*
X388272Y1000805D03*
X386421Y1003994D03*
X382721Y1010372D03*
X390122D03*
X391973Y1007183D03*
X393823Y1003994D03*
X395673Y1007183D03*
X384571D03*
X380870D03*
X382721Y1003994D03*
X388272Y1007183D03*
X390122Y1003994D03*
X393823Y1010372D03*
X386421D03*
X387603Y1028056D03*
X395004D03*
X391303D03*
X383902D03*
X393154Y1044001D03*
X385752Y1031245D03*
Y1037623D03*
Y1044001D03*
X395004Y1040812D03*
X387603Y1034434D03*
Y1040812D03*
X395004Y1034434D03*
X393154Y1031245D03*
Y1037623D03*
X382051Y1031245D03*
Y1037623D03*
Y1044001D03*
X391303Y1034434D03*
X389453Y1037623D03*
X391303Y1040812D03*
X389453Y1044001D03*
Y1031245D03*
X383902Y1040812D03*
Y1034434D03*
X395004Y1047190D03*
X387603D03*
Y1053568D03*
X391303Y1059946D03*
X395004Y1053568D03*
X385752Y1050379D03*
X393154Y1056757D03*
Y1050379D03*
X395004Y1059946D03*
X383902D03*
X387603D03*
X389453Y1056757D03*
X382051Y1050379D03*
X391303Y1047190D03*
X383902D03*
X391303Y1053568D03*
X389453Y1050379D03*
X383902Y1053568D03*
X385752Y1056757D03*
X382051D03*
Y1063135D03*
Y1069513D03*
X393154Y1063135D03*
X395004Y1066324D03*
X387603D03*
X383902D03*
X391303Y1072702D03*
Y1066324D03*
X393154Y1069513D03*
X385752D03*
Y1063135D03*
X389453Y1069513D03*
Y1063135D03*
X395004Y1072702D03*
X383902D03*
X387603D03*
X382051Y1075891D03*
Y1088647D03*
Y1082269D03*
X393154Y1075891D03*
X387603Y1079080D03*
X383902D03*
X391303D03*
X395004D03*
X393154Y1082269D03*
X391303Y1085458D03*
X393154Y1088647D03*
X385752Y1075891D03*
X389453D03*
X385752Y1088647D03*
Y1082269D03*
X389453Y1088647D03*
Y1082269D03*
X395004Y1085458D03*
X383902D03*
X387603D03*
X382051Y1095025D03*
X383902Y1091836D03*
X393154Y1095025D03*
X391303Y1091836D03*
X395004D03*
X387603D03*
X391303Y1098214D03*
Y1104592D03*
X395004D03*
X387603D03*
X383902D03*
X385752Y1095025D03*
X389453D03*
X395004Y1098214D03*
X383902D03*
X387603D03*
X382051Y1101403D03*
X393154D03*
X389453D03*
X385752D03*
X382051Y1107781D03*
Y1114159D03*
X383902Y1110970D03*
X387603D03*
X393154Y1107781D03*
X391303Y1110970D03*
X395004D03*
X391303Y1117348D03*
X393154Y1114159D03*
X389453D03*
Y1107781D03*
X385752Y1114159D03*
Y1107781D03*
X395004Y1117348D03*
X387603D03*
X383902D03*
X391304Y1130105D03*
X382051Y1126915D03*
Y1120537D03*
Y1133293D03*
X383902Y1123726D03*
X387603D03*
X393154Y1126915D03*
X391303Y1123726D03*
X395004D03*
X393154Y1120537D03*
Y1133293D03*
X389453Y1120537D03*
X385752D03*
X389453Y1126915D03*
Y1133293D03*
X385752Y1126915D03*
Y1133293D03*
X395004Y1130103D03*
X387603D03*
X383902D03*
X382051Y1139670D03*
Y1146048D03*
X393154Y1139670D03*
X395004Y1136481D03*
X391303D03*
X383902D03*
X387603D03*
X391303Y1142859D03*
X393154Y1146048D03*
X395004Y1149237D03*
X383902D03*
X387603D03*
X389453Y1139670D03*
Y1146048D03*
X385752Y1139670D03*
Y1146048D03*
X395004Y1142859D03*
X387603D03*
X383902D03*
X391303Y1149237D03*
X389453Y1158804D03*
X391303Y1155615D03*
X395004D03*
X383902D03*
X387603D03*
Y1161993D03*
X382051Y1152426D03*
X383902Y1161993D03*
X391303D03*
X395004D03*
X393154Y1152426D03*
X385752Y1158804D03*
X382051D03*
X393154D03*
X389453Y1152426D03*
X385752D03*
X388805Y1218420D03*
X388647Y1223453D03*
X386461Y1235718D03*
X386303Y1240751D03*
X382458Y1507295D03*
X387182D03*
X393483Y1507355D03*
X391383D03*
X381064Y1514243D03*
X390203Y1521453D03*
X385458D03*
X385788Y1514243D03*
X382359Y1516970D03*
X387083D03*
X383933Y1519698D03*
X388658D03*
X394890Y1514073D03*
X394834Y1516336D03*
X381285Y1528853D03*
X386009D03*
X385508Y1536063D03*
X390839D03*
X382359Y1530608D03*
X387083D03*
X383933Y1533336D03*
X388658D03*
X385458Y1523953D03*
X381285Y1526353D03*
X386009D03*
X395185Y1536640D03*
Y1534540D03*
X395186Y1531618D03*
X395097Y1528698D03*
X382458Y1542641D03*
X387182D03*
X394600Y1538658D03*
X410477Y873246D03*
X397524Y876435D03*
X399374Y873246D03*
Y879624D03*
X404925Y876435D03*
X401225D03*
X403075Y879624D03*
X406776D03*
X403075Y873246D03*
X399374Y892380D03*
X410477D03*
X406776D03*
X397524Y882813D03*
Y889191D03*
X401225Y882813D03*
X408626D03*
X404925D03*
X401225Y895569D03*
X408626Y889191D03*
X404925D03*
X403075Y892380D03*
X397524Y895569D03*
X403075Y886002D03*
X401225Y889191D03*
X408626Y895569D03*
X404925D03*
X406776Y886002D03*
X410477D03*
X399374D03*
Y898758D03*
Y905135D03*
X410477Y898758D03*
Y905135D03*
X406776Y898758D03*
Y905135D03*
X399374Y911513D03*
X410477D03*
X406776D03*
X397524Y901947D03*
X401225D03*
X408626D03*
X404925D03*
X403075Y898758D03*
Y905135D03*
Y911513D03*
X401225Y908324D03*
X397524Y908325D03*
X408626D03*
X404925Y908324D03*
X399374Y924269D03*
Y917891D03*
X410477D03*
Y924269D03*
X406776Y917891D03*
Y924269D03*
X397524Y914702D03*
X401225D03*
X408626D03*
X403075Y917891D03*
X404925Y914702D03*
X401225Y921080D03*
X403075Y924269D03*
X397524Y921080D03*
X408626D03*
X404925D03*
X399374Y930647D03*
X401225Y933836D03*
X408626Y927458D03*
X404925D03*
X403075Y930647D03*
X401225Y940214D03*
X397524Y927458D03*
Y933836D03*
X401225Y927458D03*
X397524Y940214D03*
X410477Y930647D03*
X406776D03*
X408626Y940214D03*
X404925D03*
X403075Y937025D03*
X404925Y933836D03*
X410477Y937025D03*
X408626Y933836D03*
X399374Y937025D03*
X406776D03*
Y949781D03*
Y943403D03*
Y956159D03*
X399374Y949781D03*
Y943403D03*
Y956159D03*
X410477Y949781D03*
Y943403D03*
Y956159D03*
X397524Y946592D03*
X401225D03*
X403075Y943403D03*
X408626Y946592D03*
X403075Y949781D03*
X404925Y946592D03*
X401225Y952970D03*
X403075Y956159D03*
X397524Y952970D03*
X408626D03*
X404925D03*
X397524Y959348D03*
X401225Y965726D03*
Y959348D03*
X408626D03*
X404925D03*
X403075Y962537D03*
Y968915D03*
X397524Y965726D03*
X408626D03*
X404925D03*
X406776Y962537D03*
Y968915D03*
X399374Y962537D03*
Y968915D03*
X410477Y962537D03*
Y968915D03*
X397524Y972104D03*
X401225D03*
X408626D03*
X404925D03*
X399374Y981671D03*
X406776D03*
X401225Y978482D03*
X403075Y975293D03*
X401225Y984860D03*
X408626D03*
X397524Y978482D03*
Y984860D03*
X404925Y978482D03*
X408626D03*
X410477Y981671D03*
X403075D03*
X404925Y984860D03*
X406776Y975293D03*
X399374D03*
X410477D03*
X408626Y991238D03*
X399374Y988049D03*
Y994427D03*
X406776Y988049D03*
X401225Y991238D03*
Y997616D03*
X399374Y1000805D03*
X408614Y997608D03*
X397524Y991238D03*
X410477Y988049D03*
X403075D03*
X404925Y991238D03*
X397524Y997616D03*
X403075Y994427D03*
Y1000805D03*
X397524Y1010372D03*
X399374Y1007183D03*
X401225Y1003994D03*
X410464Y1007175D03*
X404923Y1010366D03*
X401225Y1010372D03*
X397524Y1003994D03*
X406763Y1007175D03*
X403075Y1007183D03*
X398705Y1028056D03*
X409795Y1028064D03*
X406094D03*
X402406Y1028056D03*
X398705Y1034434D03*
X402406Y1040812D03*
X400555Y1031245D03*
Y1037623D03*
Y1044001D03*
X409795Y1034442D03*
Y1040820D03*
X406104D03*
X404256Y1044001D03*
X398705Y1040812D03*
X406094Y1034442D03*
X404256Y1037623D03*
Y1031245D03*
X402406Y1034434D03*
X396855Y1044001D03*
Y1031245D03*
Y1037623D03*
X402406Y1047190D03*
X409807D03*
X402406Y1053568D03*
X407957Y1056757D03*
X402406Y1059946D03*
X409807Y1053568D03*
X400555Y1056757D03*
Y1050379D03*
X407957D03*
X398705Y1047190D03*
X406107D03*
X404256Y1050379D03*
X398705Y1059946D03*
Y1053568D03*
X396855Y1050379D03*
Y1056757D03*
X409807Y1059946D03*
X406107D03*
Y1053568D03*
X404256Y1056757D03*
X398705Y1066324D03*
X404256Y1063135D03*
X402406Y1072702D03*
X404256Y1069513D03*
X406107Y1066324D03*
X409807D03*
X402406D03*
X396855Y1069513D03*
Y1063135D03*
X407957Y1069513D03*
Y1063135D03*
X400555Y1069513D03*
Y1063135D03*
X398705Y1072702D03*
X406107D03*
X409807D03*
X398705Y1079080D03*
X404256Y1075891D03*
X406107Y1079080D03*
X409807D03*
X402406D03*
X404256Y1088647D03*
X402406Y1085458D03*
X404256Y1082269D03*
X396855Y1075891D03*
X407957D03*
X400555D03*
X396855Y1088647D03*
Y1082269D03*
X407957Y1088647D03*
Y1082269D03*
X400555Y1088647D03*
Y1082269D03*
X398705Y1085458D03*
X406107D03*
X409807D03*
X398705Y1091836D03*
Y1104592D03*
X404256Y1095025D03*
X406107Y1091836D03*
X409807D03*
X402406D03*
Y1098214D03*
Y1104592D03*
X396855Y1095025D03*
X407957D03*
X400555D03*
X398705Y1098214D03*
X406107D03*
X409807D03*
Y1104592D03*
X407957Y1101403D03*
X404256D03*
X396855D03*
X406107Y1104592D03*
X400555Y1101403D03*
X398705Y1110970D03*
X404256Y1107781D03*
X406107Y1110970D03*
X409807D03*
X402406D03*
X404256Y1114159D03*
X402406Y1117348D03*
X400555Y1114159D03*
Y1107781D03*
X396855Y1114159D03*
Y1107781D03*
X407957Y1114159D03*
X398705Y1117348D03*
X407957Y1107781D03*
X406107Y1117348D03*
X409807D03*
X398705Y1123726D03*
X406107D03*
X409807D03*
X404256Y1120537D03*
X402406Y1123726D03*
X404256Y1126915D03*
Y1133293D03*
X402406Y1130103D03*
X400555Y1120537D03*
Y1126915D03*
X396855Y1120537D03*
Y1126915D03*
X407957Y1120537D03*
Y1126915D03*
X400555Y1133293D03*
X396855D03*
X407957D03*
X398705Y1130103D03*
X406107D03*
X409807D03*
X398705Y1136481D03*
Y1149237D03*
X402406Y1142859D03*
X404256Y1139670D03*
X406107Y1136481D03*
X409807D03*
X402406D03*
X404256Y1146048D03*
X406107Y1149237D03*
X409807D03*
X400555Y1139670D03*
Y1146048D03*
X396855Y1139670D03*
Y1146048D03*
X407957Y1139670D03*
Y1146048D03*
X398705Y1142859D03*
X406107D03*
X409807D03*
X402406Y1149237D03*
X398705Y1155615D03*
Y1161993D03*
X406107Y1155615D03*
X409807D03*
X402406D03*
X400555Y1158804D03*
X409807Y1161993D03*
X400555Y1165182D03*
X404256Y1152426D03*
X406107Y1161993D03*
X402406D03*
X396855Y1158804D03*
X407957D03*
X404256D03*
X400555Y1152426D03*
X396855D03*
X407957D03*
X421579Y873246D03*
X416028Y876435D03*
X412327D03*
X423429D03*
X414177Y873246D03*
X421579Y892380D03*
X417878D03*
X412327Y882813D03*
Y895569D03*
X414177Y892380D03*
X419729Y882813D03*
X416028D03*
X423429Y895569D03*
X425280Y892380D03*
X416028Y889191D03*
X419729D03*
X412327D03*
X425280Y886002D03*
X423429Y889191D03*
X419729Y895569D03*
X416028D03*
X414177Y886002D03*
X421579Y898758D03*
Y905135D03*
X417878Y898758D03*
Y905135D03*
X421579Y911513D03*
X417878D03*
X412327Y901947D03*
X414177Y898758D03*
Y905135D03*
Y911513D03*
X412327Y908325D03*
X423429Y901947D03*
X425280Y898758D03*
X419729Y901947D03*
X416028D03*
X425280Y905135D03*
Y911513D03*
X423429Y908324D03*
X419729Y908325D03*
X416028D03*
X421579Y917891D03*
Y924269D03*
X417878Y917891D03*
Y924269D03*
X414177Y917891D03*
X412327Y914702D03*
X414177Y924269D03*
X412327Y921080D03*
X423429Y914702D03*
X419729D03*
X416028D03*
X425280Y917891D03*
Y924269D03*
X423429Y921080D03*
X416028D03*
X419729D03*
X417878Y937025D03*
X421579D03*
X412327Y927458D03*
Y933836D03*
X414177Y930647D03*
X412327Y940214D03*
X414177Y937025D03*
X423429Y927458D03*
X419729D03*
X423429Y933836D03*
X425280Y930647D03*
X419729Y933836D03*
X416028Y927458D03*
Y933836D03*
X425280Y937025D03*
X423429Y940214D03*
X417878Y930647D03*
X421579D03*
X416028Y940214D03*
X419729D03*
X417878Y943403D03*
Y956159D03*
Y949781D03*
X421579Y943403D03*
Y956159D03*
Y949781D03*
X414177D03*
X412327Y946592D03*
X414177Y943403D03*
X412327Y952970D03*
X414177Y956159D03*
X416028Y946592D03*
X425280Y943403D03*
Y949781D03*
X423429Y946592D03*
X419729D03*
X423429Y952970D03*
X425280Y956159D03*
X416028Y952970D03*
X419729D03*
X412327Y965726D03*
Y959348D03*
X414177Y962537D03*
Y968915D03*
X423429Y965726D03*
X416028Y959348D03*
X423429D03*
X419729D03*
X425280Y962537D03*
Y968915D03*
X419729Y965726D03*
X416028D03*
X417878Y962537D03*
Y968915D03*
X421579Y962537D03*
Y968915D03*
X416028Y972104D03*
X423429D03*
X419729D03*
X416028Y984860D03*
X423429D03*
X412327Y978482D03*
X414177Y981671D03*
Y975293D03*
X412327Y972104D03*
X423429Y978482D03*
X421579Y981671D03*
X425280Y975293D03*
X412327Y984860D03*
X416028Y978482D03*
X419729D03*
X425280Y981671D03*
X417878D03*
X419729Y984860D03*
X417878Y975293D03*
X421579D03*
X414177Y988049D03*
X421579D03*
X423429Y991238D03*
X416028D03*
X423417Y997608D03*
X416015D03*
X417878Y988049D03*
X425280D03*
X412315Y997608D03*
X412327Y991238D03*
X419716Y997608D03*
X419729Y991238D03*
X424598Y1040820D03*
X417197D03*
X413496D03*
X420897D03*
X413508Y1059946D03*
X417209Y1047190D03*
X424610D03*
Y1053568D03*
X422760Y1056757D03*
X424610Y1059946D03*
X417209Y1053568D03*
X415358Y1056757D03*
Y1050379D03*
X422760D03*
X413508Y1047190D03*
X420910D03*
X419059Y1050379D03*
X411658D03*
X413508Y1053568D03*
X411658Y1056757D03*
X420910Y1053568D03*
X419059Y1056757D03*
X417209Y1059946D03*
X420910D03*
X413508Y1072702D03*
Y1066324D03*
X415358Y1063135D03*
X424610Y1072702D03*
Y1066324D03*
X420910D03*
X417209D03*
X415358Y1069513D03*
X419059Y1063135D03*
Y1069513D03*
X422760Y1063135D03*
X411658Y1069513D03*
Y1063135D03*
X422760Y1069513D03*
X417209Y1072702D03*
X420910D03*
X413508Y1079080D03*
Y1085458D03*
X415358Y1075891D03*
X420910Y1079080D03*
X424610D03*
X417209D03*
X424610Y1085458D03*
X415358Y1088647D03*
Y1082269D03*
X419059Y1075891D03*
X422760D03*
X411658D03*
X419059Y1082269D03*
Y1088647D03*
X422760Y1082269D03*
X411658Y1088647D03*
Y1082269D03*
X422760Y1088647D03*
X417209Y1085458D03*
X420910D03*
X413508Y1091836D03*
Y1098214D03*
Y1104592D03*
X415358Y1095025D03*
X420910Y1091836D03*
X424610D03*
X417209D03*
X420910Y1104592D03*
X424610D03*
Y1098214D03*
X417209Y1104592D03*
X415358Y1101403D03*
X419059Y1095025D03*
Y1101403D03*
X422760Y1095025D03*
Y1101403D03*
X411658Y1095025D03*
X420910Y1098214D03*
X417209D03*
X411658Y1101403D03*
X413508Y1110970D03*
Y1117348D03*
X415358Y1107781D03*
X424610Y1110970D03*
X420910D03*
X417209D03*
X424610Y1117348D03*
X415358Y1114159D03*
X422760D03*
X411658D03*
X419059D03*
X411658Y1107781D03*
X422760D03*
X419059D03*
X420910Y1117348D03*
X417209D03*
X415358Y1120537D03*
Y1126915D03*
X424610Y1123726D03*
X420910D03*
X417209D03*
X415358Y1133293D03*
X413508Y1123726D03*
Y1130103D03*
X424611Y1130105D03*
X422760Y1120537D03*
Y1126915D03*
X411658Y1120537D03*
Y1126915D03*
X419059Y1120537D03*
Y1126915D03*
X422760Y1133293D03*
X411658D03*
X419059D03*
X420910Y1130103D03*
X417209D03*
X413508Y1142859D03*
Y1136481D03*
X424610Y1142859D03*
Y1136481D03*
X420910D03*
X415358Y1139670D03*
X417209Y1136481D03*
X420910Y1149237D03*
X417209D03*
X415358Y1146048D03*
X422760Y1139670D03*
Y1146048D03*
X411658Y1139670D03*
Y1146048D03*
X419059Y1139670D03*
Y1146048D03*
X417209Y1142859D03*
X420910D03*
X413508Y1149237D03*
X424610D03*
X413508Y1155615D03*
X411658Y1158804D03*
X424610Y1155615D03*
X420910D03*
X417209D03*
X422760Y1158804D03*
Y1165182D03*
X420910Y1161993D03*
X424610D03*
X415358Y1152426D03*
X413508Y1161993D03*
X417209D03*
X419059Y1158804D03*
X415358D03*
X411658Y1152426D03*
X422760D03*
X419059D03*
X434532Y876435D03*
X432681Y879624D03*
X427130Y876435D03*
X430831Y895569D03*
X427130D03*
X430831Y882813D03*
X427130D03*
X430831Y889191D03*
X427130D03*
X434532Y895569D03*
Y889191D03*
X428981Y892380D03*
X432681D03*
X430831Y901947D03*
Y908325D03*
X427130Y901947D03*
Y908325D03*
X428981Y905135D03*
X434532Y901947D03*
X432681Y905135D03*
X434532Y908325D03*
X428981Y911513D03*
X432681D03*
X428981Y898758D03*
X432681D03*
X430831Y914702D03*
Y921080D03*
X427130Y914702D03*
Y921080D03*
X428981Y917891D03*
X432681D03*
X434532Y914702D03*
Y921080D03*
X428981Y924269D03*
X432681D03*
X430831Y927458D03*
X427130D03*
Y940214D03*
X430831D03*
X428981Y930647D03*
Y937025D03*
X432681Y930647D03*
X434532Y927458D03*
Y933836D03*
X432681Y937025D03*
X434532Y940214D03*
X427130Y933836D03*
X430831D03*
X427130Y946592D03*
Y952970D03*
X430831Y946592D03*
Y952970D03*
X428981Y949781D03*
X432681D03*
X434532Y946592D03*
Y952970D03*
X428981Y943403D03*
Y956159D03*
X432681Y943403D03*
Y956159D03*
X428981Y962537D03*
X432681D03*
X434532Y959348D03*
Y965726D03*
X428981Y968915D03*
X432681D03*
X427130Y959348D03*
Y965726D03*
X430831Y959348D03*
Y965726D03*
X428981Y981671D03*
Y975293D03*
X430831Y984860D03*
X434532Y972104D03*
X432681Y975293D03*
X434532Y978482D03*
X427130Y984860D03*
X432681Y981671D03*
X434532Y984860D03*
X427130Y978482D03*
Y972104D03*
X430831Y978482D03*
Y972104D03*
Y991238D03*
X428981Y988049D03*
X430819Y997608D03*
X432681Y988049D03*
X434532Y991238D03*
X427118Y997608D03*
X427130Y991238D03*
X434519Y997608D03*
X428299Y1040820D03*
X430162Y1056757D03*
Y1050379D03*
X432012Y1047190D03*
Y1053568D03*
X435713Y1059946D03*
X428311D03*
X432012D03*
X428311Y1047190D03*
X435713D03*
X433862Y1050379D03*
X426461D03*
Y1056757D03*
X428311Y1053568D03*
X433862Y1056757D03*
X435713Y1053568D03*
X426461Y1063135D03*
X430162D03*
X426461Y1069513D03*
X433862Y1063135D03*
X435713Y1072702D03*
Y1066324D03*
X428311Y1072702D03*
Y1066324D03*
X432012Y1072702D03*
Y1066324D03*
X430162Y1069513D03*
X433862D03*
X430162Y1075891D03*
X426461D03*
X430162Y1088647D03*
X426461D03*
Y1082269D03*
X433862Y1075891D03*
X435713Y1079080D03*
Y1085458D03*
X433862Y1088647D03*
X428311Y1079080D03*
X432012D03*
X428311Y1085458D03*
X432012D03*
X430162Y1082269D03*
X433862D03*
X426461Y1095025D03*
X430162Y1101403D03*
X426461D03*
X435713Y1091836D03*
Y1098214D03*
Y1104592D03*
X433862Y1101403D03*
X428311Y1098214D03*
Y1091836D03*
X432012Y1098214D03*
Y1091836D03*
X430162Y1095025D03*
X428311Y1104592D03*
X433862Y1095025D03*
X432012Y1104592D03*
X430162Y1107781D03*
X426461D03*
Y1114159D03*
X433862Y1107781D03*
X435713Y1110970D03*
Y1117348D03*
X432012D03*
Y1110970D03*
X428311Y1117348D03*
Y1110970D03*
X430162Y1114159D03*
X433862D03*
X426461Y1126915D03*
X430162Y1120537D03*
X426461D03*
X430162Y1133293D03*
X426461D03*
X435713Y1123726D03*
X433862Y1120537D03*
X435713Y1130103D03*
X433862Y1133293D03*
X432012Y1123726D03*
X428311D03*
X432012Y1130103D03*
X428311D03*
X430162Y1126915D03*
X433862D03*
X426461Y1139670D03*
Y1146048D03*
X428311Y1149237D03*
X435713Y1136481D03*
Y1142859D03*
Y1149237D03*
X432012D03*
Y1142859D03*
Y1136481D03*
X428311Y1142859D03*
Y1136481D03*
X430162Y1139670D03*
Y1146048D03*
X433862Y1139670D03*
Y1146048D03*
X430162Y1158804D03*
X435713Y1155615D03*
Y1161993D03*
X433862Y1158804D03*
X432012Y1161993D03*
X428311D03*
X426461Y1152426D03*
X430162D03*
X433862D03*
X432012Y1155615D03*
X426461Y1158804D03*
X428311Y1155615D03*
X445609Y876435D03*
X447460Y879624D03*
X454861Y873246D03*
X453011Y876435D03*
X449310D03*
X451160Y879624D03*
X454861D03*
X451160Y873246D03*
X449310Y895569D03*
X453011D03*
X445609Y882813D03*
Y889191D03*
Y895569D03*
X453011Y882813D03*
X449310Y889191D03*
X453011D03*
X454861Y892380D03*
X451160Y886002D03*
X454861D03*
X451160Y892380D03*
X447460D03*
Y886002D03*
X449310Y882813D03*
Y908325D03*
Y901947D03*
X453011Y908325D03*
Y901947D03*
X445609D03*
Y908325D03*
X454861Y898758D03*
X451160Y905135D03*
X454861D03*
Y911513D03*
X447460Y905135D03*
X451160Y911513D03*
X447460D03*
X451160Y898758D03*
X447460D03*
X449310Y921080D03*
Y914702D03*
X453011Y921080D03*
Y914702D03*
X445609D03*
Y921080D03*
X447460Y917891D03*
X451160D03*
X454861D03*
Y924269D03*
X451160D03*
X447460D03*
X453011Y940214D03*
X449310D03*
Y927458D03*
X453011D03*
X454861Y930647D03*
X447460Y937025D03*
X451160D03*
X454861D03*
X445609Y927458D03*
Y933836D03*
Y940214D03*
X447460Y930647D03*
X451160D03*
X449310Y933836D03*
X453011D03*
Y952970D03*
Y946592D03*
X449310Y952970D03*
Y946592D03*
X445609D03*
Y952970D03*
X447460Y949781D03*
X454861Y943403D03*
X451160Y949781D03*
X454861D03*
Y956159D03*
X451160Y943403D03*
Y956159D03*
X447460Y943403D03*
Y956159D03*
X453011Y959348D03*
Y965726D03*
X449310Y959348D03*
Y965726D03*
X445609Y959348D03*
Y965726D03*
X454861Y962537D03*
X451160D03*
X447460D03*
X454861Y968915D03*
X451160D03*
X447460D03*
X453011Y978482D03*
Y972104D03*
X449310Y978482D03*
Y972104D03*
X445609D03*
Y978482D03*
Y984860D03*
X447460Y981671D03*
X454861D03*
X451160Y975293D03*
X447460D03*
X454861D03*
X453011Y984860D03*
X451160Y981671D03*
X449310Y984860D03*
X445609Y991238D03*
X453011D03*
X454861Y988049D03*
X447460D03*
X445622Y997608D03*
X453023D03*
X449323D03*
X451160Y988049D03*
X449310Y991238D03*
X454204Y1040820D03*
X446790Y1047190D03*
Y1053568D03*
Y1059946D03*
X454192Y1047190D03*
X448641Y1056757D03*
X454192Y1053568D03*
X448641Y1050379D03*
X454192Y1059946D03*
X450491D03*
Y1047190D03*
X452341Y1056757D03*
X450491Y1053568D03*
X452341Y1050379D03*
X446790Y1066324D03*
Y1072702D03*
X452341Y1063135D03*
X448641D03*
X454192Y1066324D03*
Y1072702D03*
X450491Y1066324D03*
Y1072702D03*
X448641Y1069513D03*
X452341D03*
X446790Y1079080D03*
Y1085458D03*
X452341Y1075891D03*
X448641D03*
X452341Y1088647D03*
X448641D03*
X454192Y1079080D03*
X450491D03*
X454192Y1085458D03*
X450491D03*
X448641Y1082269D03*
X452341D03*
X446790Y1091836D03*
Y1098214D03*
Y1104592D03*
X452341Y1101403D03*
X448641D03*
X454192Y1091836D03*
Y1098214D03*
X450491Y1091836D03*
Y1098214D03*
X448641Y1095025D03*
X452341D03*
X450491Y1104592D03*
X454192D03*
X446790Y1110970D03*
Y1117348D03*
X452341Y1107781D03*
X448641D03*
X450491Y1110970D03*
Y1117348D03*
X454192Y1110970D03*
Y1117348D03*
X448641Y1114159D03*
X452341D03*
X446790Y1123726D03*
Y1130103D03*
X448641Y1120537D03*
X452341D03*
Y1133293D03*
X448641D03*
X450491Y1123726D03*
X454192D03*
X450491Y1130103D03*
X454192D03*
X448641Y1126915D03*
X452341D03*
X446790Y1136481D03*
Y1142859D03*
Y1149237D03*
X454192D03*
X450491D03*
Y1136481D03*
Y1142859D03*
X454192Y1136481D03*
Y1142859D03*
X448641Y1139670D03*
X452341D03*
X448641Y1146048D03*
X452341D03*
X450491Y1161993D03*
X446790Y1155615D03*
Y1161993D03*
X454192Y1155615D03*
X452341Y1165182D03*
X454192Y1161993D03*
X452341Y1152426D03*
X448640Y1165182D03*
X448641Y1158804D03*
X452341D03*
X450491Y1155615D03*
X447120Y1507512D03*
X452427Y1507295D03*
X444953Y1507509D03*
X442753D03*
X450703Y1521453D03*
X451033Y1514243D03*
X449861Y1519195D03*
X452328Y1516970D03*
X453903Y1519698D03*
X442918Y1513218D03*
X441660Y1521612D03*
X441259Y1518121D03*
X451254Y1528853D03*
X450752Y1536063D03*
X441752Y1523810D03*
Y1528725D03*
X452328Y1530608D03*
X453903Y1533336D03*
X441706Y1535698D03*
Y1537898D03*
X450703Y1523953D03*
X451254Y1526353D03*
X452427Y1542641D03*
X447224Y1542425D03*
X443153Y1540317D03*
X447224Y1544625D03*
X450139Y1592380D03*
Y1624292D03*
X460412Y876435D03*
X469664Y879624D03*
X462263D03*
X458562D03*
Y873246D03*
X462263D03*
X456712Y876435D03*
X467814D03*
X464113D03*
X465964Y879624D03*
Y873246D03*
X458562Y892380D03*
X469664D03*
X462263D03*
X460412Y889191D03*
X456712Y895569D03*
X467814Y882813D03*
X465964Y892380D03*
X467814Y895569D03*
X464113Y889191D03*
X460412Y882813D03*
X464113D03*
X469664Y886002D03*
X456712Y889191D03*
X460412Y895569D03*
X465964Y886002D03*
X467814Y889191D03*
X464113Y895569D03*
X462263Y886002D03*
X458562D03*
X456712Y882813D03*
X458562Y905135D03*
Y898758D03*
X469664Y905135D03*
Y898758D03*
X462263Y905135D03*
Y898758D03*
X458562Y911513D03*
X469664D03*
X462263D03*
X456712Y908324D03*
X465964Y911513D03*
X456712Y901947D03*
X460412D03*
X465964Y898758D03*
X467814Y901947D03*
X464113D03*
X467814Y908325D03*
X465964Y905135D03*
X460412Y908325D03*
X464113D03*
X458562Y924269D03*
Y917891D03*
X469664Y924269D03*
Y917891D03*
X462263Y924269D03*
Y917891D03*
X460412Y914702D03*
X456712D03*
Y921080D03*
X467814Y914702D03*
X464113D03*
X465964Y917891D03*
X467814Y921080D03*
X465964Y924269D03*
X460412Y921080D03*
X464113D03*
X462263Y937025D03*
X458562D03*
X460412Y927458D03*
X456712D03*
Y933836D03*
X460412D03*
X456712Y940214D03*
X467814Y927458D03*
Y933836D03*
X464113Y927458D03*
Y933836D03*
X467814Y940214D03*
X465964Y937025D03*
X462263Y930647D03*
X458562D03*
X460412Y940214D03*
X469664Y930647D03*
X464113Y940214D03*
X465964Y930647D03*
X469664Y937025D03*
X462263Y956159D03*
Y943403D03*
Y949781D03*
X458562Y956159D03*
Y943403D03*
Y949781D03*
X469664Y956159D03*
Y943403D03*
Y949781D03*
X460412Y946592D03*
X456712D03*
Y952970D03*
X467814Y946592D03*
X464113D03*
X465964Y943403D03*
Y949781D03*
X467814Y952970D03*
X465964Y956159D03*
X460412Y952970D03*
X464113D03*
X462263Y962537D03*
Y968915D03*
X458562Y962537D03*
Y968915D03*
X469664Y962537D03*
Y968915D03*
X456712Y965726D03*
X460412Y959348D03*
X456712D03*
X467814Y965726D03*
Y959348D03*
X465964Y962537D03*
X464113Y959348D03*
X465964Y968915D03*
X460412Y965726D03*
X464113D03*
X462263Y975293D03*
X458562D03*
X469664D03*
X456712Y972104D03*
Y978482D03*
X462263Y981671D03*
X460412Y972104D03*
Y984860D03*
X469664Y981671D03*
X467814Y978482D03*
Y972104D03*
X465964Y975293D03*
X464113Y972104D03*
X467814Y984860D03*
X460412Y978482D03*
X458562Y981671D03*
X456712Y984860D03*
X464113Y978482D03*
X465964Y981671D03*
X464113Y984860D03*
X460412Y991238D03*
X462263Y988049D03*
X469664D03*
X467814Y991238D03*
X467826Y997608D03*
X460425D03*
X458562Y988049D03*
X456724Y997608D03*
X456712Y991238D03*
X464126Y997608D03*
X465964Y988049D03*
X464113Y991238D03*
X469007Y1040820D03*
X461606D03*
X457905D03*
X465307D03*
X461593Y1047190D03*
Y1053568D03*
X456042Y1056757D03*
X457893Y1059946D03*
X456042Y1050379D03*
X468995Y1047190D03*
Y1053568D03*
Y1059946D03*
X463444Y1056757D03*
Y1050379D03*
X457893Y1047190D03*
X465294D03*
X459743Y1050379D03*
X465294Y1053568D03*
X467145Y1056757D03*
Y1050379D03*
X457893Y1053568D03*
X461593Y1059946D03*
X459743Y1056757D03*
X465294Y1059946D03*
X456042Y1063135D03*
Y1069513D03*
X457893Y1072702D03*
Y1066324D03*
X461593D03*
X467145Y1063135D03*
X468995Y1072702D03*
Y1066324D03*
X467145Y1069513D03*
X465294Y1066324D03*
X463444Y1063135D03*
Y1069513D03*
X459743Y1063135D03*
Y1069513D03*
X461593Y1072702D03*
X465294D03*
X456042Y1075891D03*
X461593Y1079080D03*
X457893D03*
X456042Y1088647D03*
X457893Y1085458D03*
X456042Y1082269D03*
X467145Y1075891D03*
X468995Y1079080D03*
X465294D03*
X468995Y1085458D03*
X467145Y1088647D03*
Y1082269D03*
X463444Y1075891D03*
X459743D03*
X463444Y1082269D03*
Y1088647D03*
X459743Y1082269D03*
Y1088647D03*
X461593Y1085458D03*
X465294D03*
X457893Y1091836D03*
X461593D03*
X456042Y1095025D03*
X457893Y1098214D03*
X456042Y1101403D03*
X457893Y1104592D03*
X461593D03*
X467145Y1095025D03*
X468995Y1091836D03*
X465294D03*
X468995Y1104592D03*
X465294D03*
X468995Y1098214D03*
X467145Y1101403D03*
X463444D03*
Y1095025D03*
X459743Y1101403D03*
Y1095025D03*
X461593Y1098214D03*
X465294D03*
X456042Y1107781D03*
X457893Y1110970D03*
X461593D03*
X457893Y1117348D03*
X456042Y1114159D03*
X468995Y1110970D03*
X465294D03*
X467145Y1107781D03*
Y1114159D03*
X468995Y1117348D03*
X459743Y1114159D03*
X463444D03*
X459743Y1107781D03*
X461593Y1117348D03*
X463444Y1107781D03*
X465294Y1117348D03*
X456042Y1126915D03*
X461593Y1123726D03*
X457893D03*
X456042Y1120537D03*
Y1133293D03*
X468995Y1123726D03*
X467145Y1120537D03*
X465294Y1123726D03*
X467145Y1126915D03*
X468995Y1130103D03*
X467145Y1133293D03*
X457893Y1130104D03*
X459743Y1126915D03*
Y1120537D03*
X463444Y1126915D03*
Y1120537D03*
X459743Y1133293D03*
X463444D03*
X461593Y1130103D03*
X465294D03*
X456042Y1139670D03*
X461593Y1136481D03*
X457893D03*
Y1142859D03*
X456042Y1146048D03*
X461593Y1149237D03*
X468995Y1142859D03*
X467145Y1139670D03*
X468995Y1136481D03*
X465294D03*
X467145Y1146048D03*
X465294Y1149237D03*
X459743Y1146048D03*
Y1139670D03*
X463444Y1146048D03*
Y1139670D03*
X461593Y1142859D03*
X457893Y1149237D03*
X465294Y1142859D03*
X468995Y1149237D03*
X467145Y1165182D03*
X459743Y1158804D03*
Y1152426D03*
X465294Y1155615D03*
X468995Y1161993D03*
X465294D03*
X467145Y1152426D03*
X457893Y1161993D03*
X456042Y1152426D03*
X459743Y1165182D03*
X456042Y1158804D03*
X457893Y1155615D03*
X456042Y1165182D03*
X461593Y1161993D03*
Y1155615D03*
X463444Y1152426D03*
Y1158804D03*
X467145D03*
X468995Y1155615D03*
X463444Y1165182D03*
X457152Y1507295D03*
X461876D03*
X466600D03*
X469600Y1521453D03*
X464876D03*
X460152D03*
X455427D03*
X455757Y1514243D03*
X460482D03*
X465206D03*
X469931D03*
X457052Y1516970D03*
X461777D03*
X466501D03*
X458627Y1519698D03*
X463351D03*
X468076D03*
X469651Y1536063D03*
X470151Y1528853D03*
X465427D03*
X460703D03*
X455978D03*
X464926Y1536063D03*
X460202D03*
X455477D03*
X457052Y1530608D03*
X461777D03*
X466501D03*
X458627Y1533336D03*
X463351D03*
X468076D03*
X464876Y1523953D03*
X460703Y1526353D03*
X455978D03*
X465427D03*
X455427Y1523953D03*
X460152D03*
X469600D03*
X470151Y1526353D03*
X466600Y1542641D03*
X457152D03*
X461876D03*
X469999Y1592380D03*
X457939D03*
X462199D03*
X463959Y1602380D03*
X456179D03*
X468239D03*
X457939Y1624292D03*
X463959Y1614292D03*
X456179D03*
X468239D03*
X469999Y1624292D03*
X462199D03*
X471515Y876435D03*
X480767Y873246D03*
Y879624D03*
X482617Y876435D03*
X484467Y873246D03*
X473365D03*
X477066D03*
X484467Y879624D03*
X477066D03*
X473365D03*
X475215Y876435D03*
X478916D03*
X480767Y892380D03*
X484467D03*
X473365D03*
X478916Y882813D03*
X475215D03*
X471515D03*
X478916Y895569D03*
X477066Y892380D03*
X475215Y889191D03*
X471515D03*
X482617Y882813D03*
Y889191D03*
X484467Y886002D03*
X480767D03*
X473365D03*
X477066D03*
X475215Y895569D03*
X471515D03*
X478916Y889191D03*
X482617Y895569D03*
X480767Y898758D03*
Y905135D03*
X484467Y898758D03*
X473365Y905135D03*
Y898758D03*
X484467Y905135D03*
X480767Y911513D03*
X484467D03*
X473365D03*
X478916Y901947D03*
X471515D03*
X475215D03*
X477066Y898758D03*
X478916Y908325D03*
X477066Y905135D03*
Y911513D03*
X482617Y901947D03*
X475215Y908325D03*
X471515D03*
X482617D03*
X480767Y917891D03*
Y924269D03*
X484467Y917891D03*
Y924269D03*
X473365D03*
Y917891D03*
X478916Y914702D03*
X477066Y917891D03*
X475215Y914702D03*
X471515D03*
X478916Y921080D03*
X477066Y924269D03*
X482617Y914702D03*
X475215Y921080D03*
X471515D03*
X482617D03*
X480767Y930647D03*
X484467D03*
X478916Y927458D03*
Y933836D03*
X475215Y927458D03*
X471515D03*
X477066Y930647D03*
X478916Y940214D03*
X482617Y927458D03*
Y933836D03*
X473365Y930647D03*
X471515Y940214D03*
X475215D03*
X482617D03*
X477066Y937025D03*
X480767D03*
X475215Y933836D03*
X471515D03*
X484467Y937025D03*
X473365D03*
X484467Y956159D03*
Y943403D03*
Y949781D03*
X473365Y956159D03*
Y943403D03*
Y949781D03*
X480767Y956159D03*
Y943403D03*
Y949781D03*
X478916Y946592D03*
X477066Y943403D03*
X475215Y946592D03*
X471515D03*
X477066Y949781D03*
X478916Y952970D03*
X477066Y956159D03*
X482617Y946592D03*
X475215Y952970D03*
X471515D03*
X482617D03*
X484467Y962537D03*
Y968915D03*
X473365Y962537D03*
Y968915D03*
X480767Y962537D03*
Y968915D03*
X478916Y965726D03*
Y959348D03*
X475215D03*
X471515D03*
X477066Y962537D03*
Y968915D03*
X482617Y959348D03*
X475215Y965726D03*
X471515D03*
X482617D03*
X484467Y975293D03*
X473365D03*
X480767D03*
X478916Y978482D03*
Y972104D03*
X477066Y981671D03*
Y975293D03*
X475215Y972104D03*
X471515D03*
X475215Y984860D03*
X484467Y981671D03*
X482617Y972104D03*
Y984860D03*
X475215Y978482D03*
X471515D03*
X473365Y981671D03*
X471515Y984860D03*
X478916D03*
X482617Y978482D03*
X480767Y981671D03*
X477066Y994427D03*
X475215Y991238D03*
X477066Y988049D03*
Y1000805D03*
X484467Y994427D03*
Y988049D03*
X482617Y991238D03*
Y997616D03*
X484467Y1000805D03*
X473365Y988049D03*
X471527Y997608D03*
X471515Y991238D03*
X478916Y997616D03*
Y991238D03*
X480767Y994427D03*
Y988049D03*
Y1000805D03*
X477066Y1007183D03*
X484467D03*
X482617Y1010372D03*
Y1003994D03*
X478916D03*
Y1010372D03*
X480767Y1007183D03*
X480097Y1028056D03*
X483798D03*
X478247Y1037623D03*
Y1044001D03*
X480097Y1034434D03*
X483798Y1040812D03*
X481948Y1031245D03*
X476400Y1040820D03*
X472708D03*
X481948Y1044001D03*
Y1037623D03*
X480097Y1040812D03*
X483798Y1034434D03*
X478247Y1031245D03*
X476397Y1047190D03*
Y1053568D03*
X470845Y1056757D03*
X478247D03*
X470845Y1050379D03*
X478247D03*
X483798Y1047190D03*
Y1053568D03*
X480097Y1059946D03*
X472696Y1047190D03*
X480097D03*
X474546Y1050379D03*
Y1056757D03*
X472696Y1053568D03*
Y1059946D03*
X476397D03*
X483798D03*
X481948Y1056757D03*
X480097Y1053568D03*
X481948Y1050379D03*
X478247Y1063135D03*
X472696Y1066324D03*
X476397D03*
X478247Y1069513D03*
X483798Y1066324D03*
X480097Y1072702D03*
Y1066324D03*
X474546Y1063135D03*
Y1069513D03*
X481948Y1063135D03*
Y1069513D03*
X470845Y1063135D03*
Y1069513D03*
X476397Y1072702D03*
X472696D03*
X483798D03*
X478247Y1075891D03*
X476397Y1079080D03*
X472696D03*
X478247Y1088647D03*
Y1082269D03*
X483798Y1079080D03*
X480097D03*
Y1085458D03*
X474546Y1075891D03*
X481948D03*
X470845D03*
X474546Y1082269D03*
Y1088647D03*
X481948Y1082269D03*
Y1088647D03*
X470845Y1082269D03*
Y1088647D03*
X472696Y1085458D03*
X476397D03*
X483798D03*
X480097Y1104592D03*
X483798D03*
X480097Y1098214D03*
X478247Y1095025D03*
X472696Y1091836D03*
X476397D03*
X480097D03*
X483798D03*
X474546Y1095025D03*
X481948D03*
X470845D03*
X472696Y1098214D03*
X476397D03*
X483798D03*
X478247Y1101403D03*
X472696Y1104592D03*
X481948Y1101403D03*
X476397Y1104592D03*
X470845Y1101403D03*
X474546D03*
X472696Y1110970D03*
X476397D03*
X478247Y1107781D03*
Y1114159D03*
X483798Y1110970D03*
X480097D03*
Y1117348D03*
X481948Y1114159D03*
X470845D03*
X481948Y1107781D03*
X474546Y1114159D03*
X470845Y1107781D03*
X474546D03*
X476397Y1117348D03*
X472696D03*
X483798D03*
X476397Y1123726D03*
X472696D03*
X478247Y1120537D03*
Y1126915D03*
Y1133293D03*
X483798Y1123726D03*
X480097D03*
Y1130103D03*
X481948Y1126915D03*
Y1120537D03*
X470845Y1126915D03*
Y1120537D03*
X474546Y1126915D03*
Y1120537D03*
X470845Y1133293D03*
X481948D03*
X474546D03*
X472696Y1130103D03*
X483798D03*
X476396D03*
X478247Y1139670D03*
X476397Y1136481D03*
X472696D03*
X476397Y1149237D03*
X472696D03*
X478247Y1146048D03*
X483798Y1136481D03*
X480097D03*
Y1142859D03*
X483798Y1149237D03*
X481948Y1146048D03*
Y1139670D03*
X470845Y1146048D03*
Y1139670D03*
X474546Y1146048D03*
Y1139670D03*
X472696Y1142859D03*
X476397D03*
X483798D03*
X480097Y1149237D03*
X476397Y1155615D03*
X474546Y1152426D03*
X470845Y1158804D03*
X481948D03*
X483798Y1155615D03*
X480097Y1161993D03*
X476397D03*
X478247Y1152426D03*
X470846Y1165182D03*
X481948D03*
X483798Y1161993D03*
X472696Y1155615D03*
X481948Y1152426D03*
X478247Y1158804D03*
X474546D03*
X478247Y1165182D03*
X480097Y1155615D03*
X474546Y1165182D03*
X470845Y1152426D03*
X472696Y1161993D03*
X471325Y1507295D03*
X476049D03*
X480774D03*
X483774Y1521453D03*
X479049D03*
X474325D03*
X474655Y1514243D03*
X479379D03*
X484104D03*
X471225Y1516970D03*
X475950D03*
X480674D03*
X472800Y1519698D03*
X477525D03*
X482249D03*
X483824Y1536063D03*
X474375D03*
X484325Y1528853D03*
X479600D03*
X474876D03*
X479099Y1536063D03*
X471225Y1530608D03*
X475950D03*
X480674D03*
X472800Y1533336D03*
X477525D03*
X482249D03*
X474325Y1523953D03*
X474876Y1526353D03*
X483774Y1523953D03*
X484325Y1526353D03*
X479049Y1523953D03*
X479600Y1526353D03*
X476049Y1542641D03*
X471325D03*
X480774D03*
X482059Y1592380D03*
X474259D03*
X476019Y1602380D03*
X480299D03*
X482059Y1624292D03*
X476019Y1614292D03*
X474259Y1624292D03*
X480299Y1614292D03*
X499271Y879624D03*
X493719Y876435D03*
X491869Y879624D03*
X488168Y873246D03*
Y879624D03*
X486318Y876435D03*
X490019D03*
X497420D03*
X495570Y879624D03*
X491869Y892380D03*
X495570D03*
X493719Y882813D03*
X490019D03*
X486318D03*
X493719Y889191D03*
X486318D03*
X490019Y895569D03*
X488168Y892380D03*
X497420Y889191D03*
X499271Y892380D03*
X495570Y886002D03*
X491869D03*
X488168D03*
X490019Y889191D03*
X493719Y895569D03*
X486318D03*
X499271Y886002D03*
X497420Y895569D03*
Y882813D03*
X491869Y905135D03*
Y898758D03*
Y911513D03*
X495570Y905135D03*
Y898758D03*
Y911513D03*
X493719Y901947D03*
X486318D03*
X490019D03*
X488168Y898758D03*
Y905135D03*
Y911513D03*
X497420Y901947D03*
X499271Y898758D03*
Y905135D03*
Y911513D03*
X490019Y908324D03*
X493719Y908325D03*
X486318D03*
X497420D03*
X491869Y917891D03*
Y924269D03*
X495570Y917891D03*
Y924269D03*
X493719Y914702D03*
X488168Y917891D03*
X490019Y914702D03*
X486318D03*
X490019Y921080D03*
X488168Y924269D03*
X499271Y917891D03*
X497420Y914702D03*
X499271Y924269D03*
X493719Y921080D03*
X486318D03*
X497420D03*
X491869Y930647D03*
X495570D03*
X493719Y927458D03*
X486318D03*
X490019D03*
X493719Y933836D03*
X490019D03*
X486318D03*
X488168Y930647D03*
X490019Y940214D03*
X497420Y927458D03*
Y933836D03*
X499271Y930647D03*
X493719Y940214D03*
X486318D03*
X497420D03*
X499271Y937025D03*
X488168D03*
X491869D03*
X495570D03*
Y956159D03*
Y943403D03*
Y949781D03*
X491869Y956159D03*
Y943403D03*
Y949781D03*
X488168Y943403D03*
X493719Y946592D03*
X490019D03*
X486318D03*
X488168Y949781D03*
X490019Y952970D03*
X488168Y956159D03*
X497420Y946592D03*
X499271Y943403D03*
Y949781D03*
Y956159D03*
X486318Y952970D03*
X493719D03*
X497420D03*
X495570Y962537D03*
Y968915D03*
X491869Y962537D03*
Y968915D03*
X490019Y965726D03*
X493719Y959348D03*
X490019D03*
X486318D03*
X488168Y962537D03*
Y968915D03*
X499271Y962537D03*
X497420Y959348D03*
X499271Y968915D03*
X493719Y965726D03*
X486318D03*
X497420D03*
X495570Y975293D03*
X491869D03*
Y981671D03*
X490019Y978482D03*
X493719Y972104D03*
X488168Y975293D03*
X490019Y972104D03*
X486318D03*
X490019Y984860D03*
X497420Y972104D03*
X499271Y975293D03*
Y981671D03*
X497420Y984860D03*
X493719Y978482D03*
X486318D03*
X488168Y981671D03*
X493719Y984860D03*
X486318D03*
X495570Y981671D03*
X497420Y978482D03*
X491869Y994427D03*
Y988049D03*
X490019Y997616D03*
Y991238D03*
X491869Y1000805D03*
X497420Y991238D03*
Y997616D03*
X499271Y988049D03*
Y994427D03*
Y1000805D03*
X488168Y988049D03*
Y994427D03*
X486318Y997616D03*
X493719D03*
X486318Y991238D03*
X493719D03*
X488168Y1000805D03*
X495570Y994427D03*
Y988049D03*
Y1000805D03*
X491869Y1007183D03*
X490019Y1010372D03*
Y1003994D03*
X497420Y1010372D03*
Y1003994D03*
X499271Y1007183D03*
X488168D03*
X486318Y1003994D03*
Y1010372D03*
X493719Y1003994D03*
Y1010372D03*
X495570Y1007183D03*
X494901Y1028056D03*
X487499D03*
X491200D03*
X498601D03*
X485649Y1044001D03*
X494901Y1034434D03*
X491200Y1040812D03*
X487499Y1034434D03*
X489349Y1031245D03*
X493050Y1037623D03*
X485649D03*
X493050Y1044001D03*
X496751Y1031245D03*
X498601Y1040812D03*
X494901D03*
X489349Y1044001D03*
X487499Y1040812D03*
X489349Y1037623D03*
X496751Y1044001D03*
Y1037623D03*
X485649Y1031245D03*
X493050D03*
X491200Y1034434D03*
X498601D03*
X496751Y1050379D03*
X491200Y1047190D03*
X493050Y1056757D03*
X491200Y1059946D03*
Y1053568D03*
X485649Y1056757D03*
X493050Y1050379D03*
X485649D03*
X498601Y1047190D03*
Y1053568D03*
X494901Y1047190D03*
X487499D03*
X489349Y1050379D03*
X494901Y1059946D03*
Y1053568D03*
X487499Y1059946D03*
X489349Y1056757D03*
X487499Y1053568D03*
X496751Y1056757D03*
X498601Y1059946D03*
X489349Y1063135D03*
X494901Y1066324D03*
X491200D03*
X487499D03*
X491200Y1072702D03*
X489349Y1069513D03*
X498601Y1066324D03*
X485649Y1063135D03*
Y1069513D03*
X496751Y1063135D03*
Y1069513D03*
X493050Y1063135D03*
Y1069513D03*
X494901Y1072702D03*
X487499D03*
X498601D03*
X489349Y1082269D03*
X498601Y1079080D03*
X494901D03*
X489349Y1075891D03*
X487499Y1079080D03*
X491200D03*
Y1085458D03*
X489349Y1088647D03*
X485649Y1075891D03*
X496751D03*
X493050D03*
X485649Y1082269D03*
Y1088647D03*
X496751Y1082269D03*
Y1088647D03*
X493050Y1082269D03*
Y1088647D03*
X494901Y1085458D03*
X487499D03*
X498601D03*
X494901Y1091836D03*
X487499D03*
X491200D03*
X489349Y1095025D03*
X494901Y1104592D03*
X491200Y1098214D03*
Y1104592D03*
X487499D03*
X498601Y1091836D03*
Y1104592D03*
X496751Y1101403D03*
X485649Y1095025D03*
X496751D03*
X493050D03*
X494901Y1098214D03*
X487499D03*
X498601D03*
X493050Y1101403D03*
X485649D03*
X489349D03*
X491200Y1110970D03*
X489349Y1114159D03*
X491200Y1117348D03*
X498601Y1110970D03*
X494901D03*
X489349Y1107781D03*
X487499Y1110970D03*
X493050Y1107781D03*
Y1114159D03*
X485649D03*
X496751Y1107781D03*
Y1114159D03*
X485649Y1107781D03*
X494901Y1117348D03*
X487499D03*
X498601D03*
X494901Y1123726D03*
X489349Y1126915D03*
X491200Y1123726D03*
X487499D03*
X489349Y1120537D03*
X491200Y1130103D03*
X489349Y1133293D03*
X498601Y1123726D03*
X493050Y1120537D03*
X485649Y1126915D03*
Y1120537D03*
X496751D03*
X493050Y1133293D03*
Y1126915D03*
X496751Y1133293D03*
Y1126915D03*
X485649Y1133293D03*
X487499Y1130103D03*
X494901D03*
X498601D03*
X494901Y1136481D03*
X489349Y1139670D03*
X491200Y1136481D03*
X487499D03*
X491200Y1142859D03*
X494901Y1149237D03*
X489349Y1146048D03*
X487499Y1149237D03*
X498601Y1136481D03*
Y1149237D03*
X493050Y1146048D03*
Y1139670D03*
X485649Y1146048D03*
Y1139670D03*
X496751Y1146048D03*
Y1139670D03*
X494901Y1142859D03*
X487499D03*
X491200Y1149237D03*
X498601Y1142859D03*
X487499Y1155615D03*
X485649Y1152426D03*
X493050Y1158804D03*
X498601Y1155615D03*
X496751Y1152426D03*
X498601Y1161993D03*
X487499D03*
X491200D03*
X489349Y1152426D03*
X493050Y1165182D03*
X485649Y1158804D03*
Y1165182D03*
X496751D03*
Y1158804D03*
X489349D03*
X491200Y1155615D03*
X493050Y1152426D03*
X494901Y1161993D03*
Y1155615D03*
X489349Y1165182D03*
X485498Y1507295D03*
X490222D03*
X499671D03*
X494947D03*
X497947Y1521453D03*
X493222D03*
X488498D03*
X488828Y1514243D03*
X493553D03*
X498277D03*
X499572Y1516970D03*
X485399D03*
X490123D03*
X494847D03*
X486973Y1519698D03*
X491698D03*
X496422D03*
X497997Y1536063D03*
X493273D03*
X498498Y1528853D03*
X493773D03*
X489049D03*
X488548Y1536063D03*
X499572Y1530608D03*
X485399D03*
X490123D03*
X494847D03*
X486973Y1533336D03*
X491698D03*
X496422D03*
X497947Y1523953D03*
X498498Y1526353D03*
X488498Y1523953D03*
X489049Y1526353D03*
X493222Y1523953D03*
X493773Y1526353D03*
X494947Y1542641D03*
X485498D03*
X490222D03*
X499671D03*
X498379Y1592380D03*
X486319D03*
X494119D03*
X488079Y1602380D03*
X492359D03*
X498379Y1624292D03*
X488079Y1614292D03*
X486319Y1624292D03*
X494119D03*
X492359Y1614292D03*
X510373Y879624D03*
X502971D03*
X501133Y872118D03*
X514074Y879624D03*
X508523Y876435D03*
X506672Y879624D03*
X512223Y876435D03*
X501121D03*
X508523Y882813D03*
X506672Y886002D03*
X502971D03*
X504822Y882813D03*
X506672Y892380D03*
X501121Y895569D03*
X512223Y882813D03*
X514074Y886002D03*
X512223Y889191D03*
X514074Y892380D03*
X510373Y886002D03*
X504822Y889191D03*
X508523D03*
X502971Y892380D03*
X508523Y895569D03*
X504822D03*
X510373Y892380D03*
X501121Y889191D03*
X512223Y895569D03*
X501121Y882813D03*
X506672Y898758D03*
Y905135D03*
Y911513D03*
X501121Y908325D03*
X512223Y901947D03*
X514074Y898758D03*
Y911513D03*
X512223Y908325D03*
X508523D03*
X502971Y911513D03*
X510373Y898758D03*
X504822Y901947D03*
X508523D03*
X502971Y905135D03*
X510373D03*
X504822Y908325D03*
X510373Y911513D03*
X502971Y898758D03*
X514074Y905135D03*
X501121Y901947D03*
X506672Y917891D03*
X501121Y921080D03*
X506672Y924269D03*
X514074Y917891D03*
X512223Y921080D03*
X510373Y917891D03*
X504822Y921080D03*
X508523D03*
X502971Y924269D03*
X510373D03*
X508523Y914702D03*
X504822D03*
X502971Y917891D03*
X512223Y914702D03*
X514074Y924269D03*
X501121Y914702D03*
X506672Y930647D03*
X501121Y933836D03*
X506672Y937025D03*
X501121Y940214D03*
X512223Y927458D03*
X514074Y930647D03*
X512223Y940214D03*
X514074Y937025D03*
X504822Y927458D03*
X508523D03*
X502971Y930647D03*
X510373Y937025D03*
X504822Y940214D03*
X508523D03*
Y933836D03*
X504822D03*
X510373Y930647D03*
X502971Y937025D03*
X512223Y933836D03*
X501121Y927458D03*
X506672Y943403D03*
Y949781D03*
X501121Y952970D03*
X506672Y956159D03*
X514074Y949781D03*
X512223Y946592D03*
X514074Y956159D03*
X502971Y943403D03*
X510373D03*
X504822Y946592D03*
X508523D03*
X502971Y949781D03*
X510373Y956159D03*
X508523Y952970D03*
X504822D03*
X510373Y949781D03*
X502971Y956159D03*
X514074Y943403D03*
X512223Y952970D03*
X501121Y946592D03*
X506672Y962537D03*
X501121Y965726D03*
X506672Y968915D03*
X512223Y959348D03*
Y965726D03*
X514074Y968915D03*
X510373Y962537D03*
X504822Y965726D03*
X508523D03*
X502971Y968915D03*
X504822Y959348D03*
X508523D03*
X502971Y962537D03*
X510373Y968915D03*
X514074Y962537D03*
X501121Y959348D03*
X510373Y981671D03*
X506672Y975293D03*
Y981671D03*
X501121Y978482D03*
X508523Y984860D03*
X514074Y975293D03*
X512223Y978482D03*
Y984860D03*
X504822D03*
X510373Y975293D03*
X504822Y978482D03*
X508523D03*
X502971Y981671D03*
X508523Y972104D03*
X504822D03*
X502971Y975293D03*
X514074Y981671D03*
X512223Y972104D03*
X501121D03*
Y984860D03*
X506672Y988049D03*
Y994427D03*
Y1000805D03*
X514074Y988049D03*
Y994427D03*
X512223Y997616D03*
X502971Y988049D03*
X510373Y994427D03*
X508523Y997616D03*
X504822D03*
X502971Y1000805D03*
X510373D03*
Y988049D03*
X504822Y991238D03*
X501121Y997616D03*
Y991238D03*
X512223D03*
X514074Y1000805D03*
X502971Y994427D03*
X508523Y991238D03*
X506672Y1007183D03*
X514074D03*
X512223Y1003994D03*
X508523Y1010372D03*
X510373Y1007183D03*
X508523Y1003994D03*
X504822D03*
X502971Y1007183D03*
X501121Y1010372D03*
X512223D03*
X501121Y1003994D03*
X504822Y1010372D03*
X502302Y1028056D03*
X513405D03*
X506003D03*
X509704D03*
X507853Y1037623D03*
X500452D03*
X502302Y1034434D03*
X507853Y1044001D03*
X500452D03*
X507853Y1031245D03*
X513405Y1034434D03*
Y1040812D03*
X504153Y1031245D03*
X506003Y1034434D03*
X509704D03*
X511554Y1037623D03*
X504153D03*
X506003Y1040812D03*
X509704D03*
X504153Y1044001D03*
X502302Y1040812D03*
X500452Y1031245D03*
X511554Y1044001D03*
Y1031245D03*
X507853Y1056757D03*
Y1050379D03*
X500452Y1056757D03*
X504153D03*
X500452Y1050379D03*
X502302Y1059946D03*
X506003D03*
X513405Y1053568D03*
Y1059946D03*
X504153Y1050379D03*
X509704Y1059946D03*
X506003Y1047190D03*
X511554Y1050379D03*
X509704Y1053568D03*
X502302Y1047190D03*
Y1053568D03*
X513405Y1047190D03*
X511554Y1056757D03*
X509704Y1047190D03*
X506003Y1053568D03*
X507853Y1063135D03*
X500452D03*
X507853Y1069513D03*
X500452D03*
X502302Y1072702D03*
X513405D03*
X509704D03*
X504153Y1063135D03*
X511554D03*
X506003Y1066324D03*
X504153Y1069513D03*
X511554D03*
X506003Y1072702D03*
X509704Y1066324D03*
X513405D03*
X502302D03*
X507853Y1075891D03*
X500452D03*
X507853Y1088647D03*
X500452D03*
X502302Y1085458D03*
X507853Y1082269D03*
X500452D03*
X513405Y1079080D03*
X504153Y1075891D03*
X511554D03*
X506003Y1079080D03*
X509704D03*
X504153Y1082269D03*
X511554D03*
X506003Y1085458D03*
X511554Y1088647D03*
X504153D03*
X509704Y1085458D03*
X513405D03*
X502302Y1079080D03*
X507853Y1095025D03*
X500452D03*
X502302Y1098214D03*
X507853Y1101403D03*
X502302Y1104592D03*
X513405Y1091836D03*
Y1098214D03*
X511554Y1101403D03*
X506003Y1104592D03*
X509704Y1091836D03*
X504153Y1095025D03*
X511554D03*
X506003Y1098214D03*
X509704D03*
X504153Y1101403D03*
X509704Y1104592D03*
X506003Y1091836D03*
X513405Y1104592D03*
X502302Y1091836D03*
X500452Y1101403D03*
X507853Y1107781D03*
X500452D03*
X507853Y1114159D03*
X502302Y1117348D03*
X500452Y1114159D03*
X513405Y1110970D03*
Y1117348D03*
X509704Y1110970D03*
X504153Y1114159D03*
X511554D03*
X506003Y1117348D03*
X509704D03*
X511554Y1107781D03*
X504153D03*
X506003Y1110970D03*
X502302D03*
X507853Y1120537D03*
X500452D03*
X507853Y1126915D03*
X500452D03*
X507853Y1133293D03*
X500452D03*
X502302Y1130103D03*
X513405Y1130104D03*
X504153Y1120537D03*
X511554D03*
X506003Y1123726D03*
X509704Y1130103D03*
X504153Y1133293D03*
X511554D03*
Y1126915D03*
X504153D03*
X509704Y1123726D03*
X506003Y1130103D03*
X513405Y1123726D03*
X502302D03*
X507853Y1139670D03*
X500452D03*
X502302Y1142859D03*
X507853Y1146048D03*
X500452D03*
X513405Y1136481D03*
Y1149237D03*
X506003Y1136481D03*
X509704D03*
X504153Y1139670D03*
X511554D03*
X506003Y1142859D03*
X509704Y1149237D03*
X511554Y1146048D03*
X504153D03*
X509704Y1142859D03*
X506003Y1149237D03*
X513405Y1142859D03*
X502302Y1136481D03*
Y1149237D03*
X511554Y1165182D03*
X509704Y1155615D03*
X507853Y1152426D03*
X502302Y1155615D03*
X507853Y1158804D03*
X504153D03*
X513405Y1155615D03*
X504153Y1152426D03*
X511554D03*
X506003Y1155615D03*
X513405Y1161993D03*
X511554Y1158804D03*
X509704Y1161993D03*
X502302D03*
X500452Y1152426D03*
X506003Y1161993D03*
X500452Y1158804D03*
Y1165182D03*
X507853D03*
X504153D03*
X504396Y1507295D03*
X509120D03*
X513844D03*
X512120Y1521453D03*
X507396D03*
X502671D03*
X503001Y1514243D03*
X507726D03*
X512450D03*
X504296Y1516970D03*
X509021D03*
X513745D03*
X501147Y1519698D03*
X505871D03*
X510595D03*
X507446Y1536063D03*
X512671Y1528853D03*
X507947D03*
X503222D03*
X512170Y1536063D03*
X502721D03*
X504296Y1530608D03*
X509021D03*
X513745D03*
X501147Y1533336D03*
X505871D03*
X510595D03*
X507947Y1526353D03*
X507396Y1523953D03*
X512120D03*
X512671Y1526353D03*
X503222D03*
X502671Y1523953D03*
X513844Y1542641D03*
X504396D03*
X509120D03*
X510439Y1592380D03*
X506179D03*
X512199Y1602380D03*
X500139D03*
X504419D03*
X512199Y1614292D03*
X500139D03*
X506179Y1624292D03*
X510439D03*
X504419Y1614292D03*
X525176Y879624D03*
X515924Y876435D03*
X525176Y873246D03*
X521475Y879624D03*
X519625Y876435D03*
X517775Y879624D03*
X521475Y873246D03*
X517775D03*
X527027Y876435D03*
X528877Y879624D03*
X525176Y886002D03*
X523326Y882813D03*
X517775Y886002D03*
X519625Y882813D03*
X527027Y895569D03*
Y889191D03*
X525176Y892380D03*
X519625Y889191D03*
Y895569D03*
X528877Y886002D03*
Y892380D03*
X521475Y886002D03*
X515924Y889191D03*
X523326D03*
X517775Y892380D03*
X523326Y895569D03*
X515924D03*
X521475Y892380D03*
X515924Y882813D03*
X527027D03*
Y901947D03*
X525176Y898758D03*
X519625Y901947D03*
X525176Y905135D03*
Y911513D03*
X519625Y908325D03*
X527027Y908324D03*
X528877Y911513D03*
Y905135D03*
Y898758D03*
X523326Y908325D03*
X517775Y911513D03*
X521475Y898758D03*
X515924Y901947D03*
X523326D03*
X517775Y905135D03*
X521475D03*
X515924Y908325D03*
X521475Y911513D03*
X517775Y898758D03*
X525176Y917891D03*
X519625Y914702D03*
X527027D03*
Y921080D03*
X525176Y924269D03*
X519625Y921080D03*
X528877Y924269D03*
Y917891D03*
X521475D03*
X515924Y921080D03*
X523326D03*
X517775Y924269D03*
X521475D03*
X523326Y914702D03*
X515924D03*
X517775Y917891D03*
X525176Y937025D03*
X527027Y927458D03*
Y933836D03*
X525176Y930647D03*
X519625Y927458D03*
Y933836D03*
X527027Y940214D03*
X519625D03*
X528877Y930647D03*
Y937025D03*
X515924Y927458D03*
X523326D03*
X517775Y930647D03*
X521475Y937025D03*
X515924Y940214D03*
X523326D03*
Y933836D03*
X515924D03*
X521475Y930647D03*
X517775Y937025D03*
X527027Y946592D03*
X519625D03*
X525176Y943403D03*
Y949781D03*
X527027Y952970D03*
X525176Y956159D03*
X519625Y952970D03*
X528877Y943403D03*
Y949781D03*
Y956159D03*
X517775Y943403D03*
X521475D03*
X515924Y946592D03*
X523326D03*
X517775Y949781D03*
X521475Y956159D03*
X523326Y952970D03*
X515924D03*
X521475Y949781D03*
X517775Y956159D03*
X527027Y959348D03*
Y965726D03*
X525176Y962537D03*
X519625Y959348D03*
Y965726D03*
X525176Y968915D03*
X528877D03*
Y962537D03*
X521475D03*
X515924Y965726D03*
X523326D03*
X517775Y968915D03*
X515924Y959348D03*
X523326D03*
X517775Y962537D03*
X521475Y968915D03*
Y981671D03*
X519625Y978482D03*
X527027Y984860D03*
X523326D03*
X519625D03*
X527027Y972104D03*
Y978482D03*
X525176Y975293D03*
Y981671D03*
X519625Y972104D03*
X528877Y981671D03*
Y975293D03*
X515924Y984860D03*
X521475Y975293D03*
X515924Y978482D03*
X523326D03*
X517775Y981671D03*
X523326Y972104D03*
X515924D03*
X517775Y975293D03*
X527027Y991238D03*
Y997616D03*
X525176Y988049D03*
Y994427D03*
X519625Y991238D03*
Y997616D03*
X525176Y1000805D03*
X528877Y988049D03*
Y1000805D03*
X517775Y988049D03*
X521475Y994427D03*
X523326Y997616D03*
X515924D03*
X517775Y1000805D03*
X521475D03*
Y988049D03*
X515924Y991238D03*
X517775Y994427D03*
X523326Y991238D03*
X528877Y994427D03*
X527027Y1010372D03*
Y1003994D03*
X525176Y1007183D03*
X519625Y1010372D03*
Y1003994D03*
X528877Y1007183D03*
X523326Y1010372D03*
X521475Y1007183D03*
X523326Y1003994D03*
X515924D03*
X517775Y1007183D03*
X515924Y1010372D03*
X520806Y1028056D03*
X528208D03*
X517105D03*
X524507D03*
X526357Y1037623D03*
Y1044001D03*
Y1031245D03*
X515255D03*
X520806Y1040812D03*
Y1034434D03*
X515255Y1044001D03*
X528208Y1040812D03*
Y1034434D03*
X518956Y1031245D03*
X517105Y1034434D03*
X524507D03*
X522657Y1037623D03*
X518956D03*
X517105Y1040812D03*
X524507D03*
X518956Y1044001D03*
X515255Y1037623D03*
X522656Y1044001D03*
Y1031245D03*
X520806Y1047190D03*
X526357Y1050379D03*
Y1056757D03*
X520806Y1053568D03*
X515255Y1050379D03*
X518956Y1056757D03*
X520806Y1059946D03*
X517105D03*
X528208Y1047190D03*
Y1053568D03*
Y1059946D03*
X518956Y1050379D03*
X524507Y1059946D03*
X517105Y1047190D03*
X522657Y1050379D03*
X524507Y1053568D03*
X515255Y1056757D03*
X522656D03*
X524507Y1047190D03*
X517105Y1053568D03*
X526357Y1063135D03*
X515255D03*
X526357Y1069513D03*
X520806Y1066324D03*
Y1072702D03*
X515255Y1069513D03*
X528208Y1066324D03*
Y1072702D03*
X524507D03*
X518956Y1063135D03*
X522657D03*
X517105Y1066324D03*
X518956Y1069513D03*
X522657D03*
X517105Y1072702D03*
X524507Y1066324D03*
X526357Y1075891D03*
X520806Y1079080D03*
X526357Y1088647D03*
Y1082269D03*
X520806Y1085458D03*
X515255Y1088647D03*
Y1082269D03*
X528208Y1079080D03*
Y1085458D03*
X518956Y1075891D03*
X522657D03*
X517105Y1079080D03*
X524507D03*
X518956Y1082269D03*
X522657D03*
X517105Y1085458D03*
X522657Y1088647D03*
X518956D03*
X524507Y1085458D03*
X515255Y1075891D03*
X526357Y1095025D03*
X520806Y1091836D03*
X526357Y1101403D03*
X520806Y1104592D03*
Y1098214D03*
X515255Y1101403D03*
X528208Y1091836D03*
Y1104592D03*
Y1098214D03*
X522657Y1101403D03*
X517105Y1104592D03*
X524507Y1091836D03*
X518956Y1095025D03*
X522657D03*
X517105Y1098214D03*
X524507D03*
X518956Y1101403D03*
X524507Y1104592D03*
X517105Y1091836D03*
X515255Y1095025D03*
X526357Y1107781D03*
X520806Y1110970D03*
X515255Y1107781D03*
X526357Y1114159D03*
X520806Y1117348D03*
X528208Y1110970D03*
Y1117348D03*
X524507Y1110970D03*
X518956Y1114159D03*
X522657D03*
X517105Y1117348D03*
X524507D03*
X522657Y1107781D03*
X518956D03*
X517105Y1110970D03*
X515255Y1114159D03*
X528208Y1130104D03*
X526357Y1120537D03*
Y1126915D03*
X520806Y1123726D03*
X515255Y1120537D03*
Y1126915D03*
X526357Y1133293D03*
X520806Y1130103D03*
X528208Y1123726D03*
X518956Y1120537D03*
X522657D03*
X517105Y1123726D03*
X524507Y1130103D03*
X518956Y1133293D03*
X522657D03*
Y1126915D03*
X518956D03*
X524507Y1123726D03*
X517105Y1130103D03*
X515255Y1133293D03*
Y1139670D03*
X520806Y1142859D03*
X526357Y1139670D03*
X520806Y1136481D03*
X526357Y1146048D03*
X520806Y1149237D03*
X515255Y1146048D03*
X528208Y1136481D03*
Y1142859D03*
Y1149237D03*
X517105Y1136481D03*
X524507D03*
X518956Y1139670D03*
X522657D03*
X517105Y1142859D03*
X524507Y1149237D03*
X522657Y1146048D03*
X518956D03*
X524507Y1142859D03*
X517105Y1149237D03*
X528208Y1161993D03*
X526357Y1152426D03*
Y1158804D03*
X520806Y1155615D03*
X517105D03*
X522657Y1158804D03*
X515255D03*
X517105Y1161993D03*
X528208Y1155615D03*
X518956Y1152426D03*
X522657D03*
X524507Y1155615D03*
X515255Y1152426D03*
X524507Y1161993D03*
X520806D03*
X518956Y1158804D03*
X526370Y1165290D03*
X515268D03*
X518969D03*
X522670D03*
X518569Y1507295D03*
X523293D03*
X529594Y1507355D03*
X527494D03*
X517175Y1514243D03*
X526314Y1521453D03*
X521569D03*
X516845D03*
X521899Y1514243D03*
X518470Y1516970D03*
X523194D03*
X515320Y1519698D03*
X520044D03*
X524769D03*
X516895Y1536063D03*
X522120Y1528853D03*
X517396D03*
X521619Y1536063D03*
X526950D03*
X518470Y1530608D03*
X523194D03*
X515320Y1533336D03*
X520044D03*
X524769D03*
X521569Y1523953D03*
X522120Y1526353D03*
X517396D03*
X516845Y1523953D03*
X523293Y1542641D03*
X518569D03*
X518239Y1592380D03*
X522499D03*
X524259Y1602380D03*
X528539D03*
X516479D03*
X524259Y1614292D03*
X518239Y1624292D03*
X522499D03*
X528539Y1614292D03*
X516479D03*
X534428Y876435D03*
X539979Y879624D03*
X532578D03*
X541830Y876435D03*
X543680Y879624D03*
X530727Y876435D03*
X532578Y873246D03*
X538129Y889191D03*
X539979Y892380D03*
X532578D03*
X543680Y886002D03*
X538129Y882813D03*
X532578Y886002D03*
X534428Y882813D03*
X536279Y886002D03*
X530727Y889191D03*
X534428D03*
Y895569D03*
X530727D03*
X536279Y892380D03*
X541830Y889191D03*
X543680Y892380D03*
X541830Y895569D03*
X538129D03*
X539979Y886002D03*
X530727Y882813D03*
X541830D03*
X538129Y901947D03*
X539979Y898758D03*
X532578D03*
X539979Y911513D03*
X538129Y908325D03*
X532578Y905135D03*
Y911513D03*
X534428Y908325D03*
X536279Y898758D03*
X530727Y901947D03*
X534428D03*
X536279Y905135D03*
X530727Y908325D03*
X536279Y911513D03*
X543680D03*
X541830Y901947D03*
X543680Y905135D03*
X541830Y908325D03*
X543680Y898758D03*
X539979Y905135D03*
Y917891D03*
X532578D03*
X538129Y921080D03*
X532578Y924269D03*
X536279Y917891D03*
X530727Y921080D03*
X534428D03*
X536279Y924269D03*
X534428Y914702D03*
X530727D03*
X541830Y921080D03*
X543680Y924269D03*
X541830Y914702D03*
X543680Y917891D03*
X539979Y924269D03*
X538129Y914702D03*
Y927458D03*
X539979Y930647D03*
X532578D03*
X539979Y937025D03*
X538129Y940214D03*
X532578Y937025D03*
X530727Y927458D03*
X534428D03*
X536279Y937025D03*
X530727Y940214D03*
X534428D03*
Y933836D03*
X530727D03*
X536279Y930647D03*
X541830Y927458D03*
X543680Y930647D03*
X541830Y940214D03*
Y933836D03*
X543680Y937025D03*
X538129Y933836D03*
X539979Y949781D03*
X538129Y946592D03*
X532578Y943403D03*
Y949781D03*
X539979Y956159D03*
X532578D03*
X536279Y943403D03*
X530727Y946592D03*
X534428D03*
X536279Y956159D03*
X534428Y952970D03*
X530727D03*
X536279Y949781D03*
X543680Y943403D03*
X541830Y946592D03*
X543680Y949781D03*
X541830Y952970D03*
X543680Y956159D03*
X538129Y952970D03*
X539979Y943403D03*
X538129Y959348D03*
Y965726D03*
X532578Y962537D03*
X539979Y968915D03*
X532578D03*
X536279Y962537D03*
X530727Y965726D03*
X534428D03*
X530727Y959348D03*
X534428D03*
X536279Y968915D03*
X541830Y965726D03*
X543680Y968915D03*
X541830Y959348D03*
X543680Y962537D03*
X539979D03*
Y975293D03*
X532578D03*
X538129Y978482D03*
X536279Y981671D03*
X532578D03*
X538129Y984860D03*
X534428D03*
X530727D03*
X536279Y975293D03*
X530727Y978482D03*
X534428D03*
Y972104D03*
X530727D03*
X541830Y984860D03*
Y978482D03*
X543680Y981671D03*
X541830Y972104D03*
X543680Y975293D03*
X538129Y972104D03*
X539979Y981671D03*
X532578Y994427D03*
X539979Y988049D03*
X532578D03*
X539979Y994427D03*
X538129Y997616D03*
X532578Y1000805D03*
X536279Y994427D03*
X534428Y997616D03*
X530727D03*
X536279Y1000805D03*
Y988049D03*
X530727Y991238D03*
X543680Y988049D03*
X541830Y997616D03*
X543680Y1000805D03*
X541830Y991238D03*
X539979Y1000805D03*
X538129Y991238D03*
X543680Y994427D03*
X534428Y991238D03*
X539978Y1007184D03*
X538129Y1003994D03*
X532578Y1007183D03*
X534428Y1010372D03*
X536279Y1007183D03*
X534428Y1003994D03*
X530727D03*
X541830D03*
X543680Y1007183D03*
X538129Y1010372D03*
X530727D03*
X541830D03*
X539310Y1028056D03*
X531908D03*
X543011D03*
X535609D03*
X541160Y1031245D03*
X533759D03*
X539310Y1034434D03*
Y1040812D03*
X533759Y1037623D03*
X541160Y1044001D03*
X533759D03*
X530058Y1031245D03*
X531908Y1034434D03*
X535609D03*
X537460Y1037623D03*
X530058D03*
X531908Y1040812D03*
X535609D03*
X530058Y1044001D03*
X543011Y1034434D03*
Y1040812D03*
X541160Y1037623D03*
X537460Y1044001D03*
Y1031245D03*
X543011Y1059946D03*
X530058Y1056757D03*
X541160Y1050379D03*
X539310Y1053568D03*
X533759Y1050379D03*
Y1056757D03*
X539310Y1059946D03*
X531908D03*
X530058Y1050379D03*
X535609Y1059946D03*
X531908Y1047190D03*
X537460Y1050379D03*
X535609Y1053568D03*
X543011Y1047190D03*
X541160Y1056757D03*
X539310Y1047190D03*
X543011Y1053568D03*
X537460Y1056757D03*
X535609Y1047190D03*
X531908Y1053568D03*
X541160Y1063135D03*
X533759D03*
X541160Y1069513D03*
X539310Y1072702D03*
X533759Y1069513D03*
X535609Y1072702D03*
X530058Y1063135D03*
X537460D03*
X531908Y1066324D03*
X530058Y1069513D03*
X537460D03*
X531908Y1072702D03*
X535609Y1066324D03*
X543011D03*
Y1072702D03*
X539310Y1066324D03*
X533759Y1075891D03*
X539310Y1079080D03*
X541160Y1088647D03*
X533759D03*
X541160Y1082269D03*
X533759D03*
X530058Y1075891D03*
X537460D03*
X531908Y1079080D03*
X535609D03*
X530058Y1082269D03*
X537460D03*
X531908Y1085458D03*
X537460Y1088647D03*
X530058D03*
X535609Y1085458D03*
X543011Y1079080D03*
Y1085458D03*
X539310D03*
X541160Y1075891D03*
X539310Y1091836D03*
X533759Y1095025D03*
X539310Y1098214D03*
X541160Y1101403D03*
X533759D03*
X537460D03*
X531908Y1104592D03*
X535609Y1091836D03*
X530058Y1095025D03*
X537460D03*
X531908Y1098214D03*
X535609D03*
X530058Y1101403D03*
X535609Y1104592D03*
X531908Y1091836D03*
X543011Y1104592D03*
Y1098214D03*
Y1091836D03*
X541160Y1095025D03*
X539310Y1104592D03*
X541160Y1107781D03*
X533759D03*
X539310Y1110970D03*
Y1117348D03*
X533759Y1114159D03*
X535609Y1110970D03*
X530058Y1114159D03*
X537460D03*
X531908Y1117348D03*
X535609D03*
X537460Y1107781D03*
X530058D03*
X531908Y1110970D03*
X543011Y1117348D03*
Y1110970D03*
X541160Y1114159D03*
Y1120537D03*
X533759D03*
X541160Y1126915D03*
X533759D03*
X539310Y1130103D03*
X533759Y1133293D03*
X530058Y1120537D03*
X537460D03*
X531908Y1123726D03*
X535609Y1130103D03*
X530058Y1133293D03*
X537460D03*
Y1126915D03*
X530058D03*
X535609Y1123726D03*
X531908Y1130103D03*
X543011Y1123726D03*
Y1130103D03*
X539310Y1123726D03*
X541160Y1133293D03*
Y1139670D03*
X539310Y1136481D03*
X533759Y1139670D03*
Y1146048D03*
X541160D03*
X539310Y1149237D03*
X531908Y1136481D03*
X535609D03*
X530058Y1139670D03*
X537460D03*
X531908Y1142859D03*
X535609Y1149237D03*
X537460Y1146048D03*
X530058D03*
X535609Y1142859D03*
X531908Y1149237D03*
X543011Y1136481D03*
Y1142859D03*
Y1149237D03*
X539310Y1142859D03*
X543011Y1155615D03*
X533759Y1158804D03*
X530058D03*
X539310Y1155615D03*
X535609D03*
X533759Y1152426D03*
X543011Y1161993D03*
X530058Y1152426D03*
X537460D03*
X531908Y1155615D03*
X541160Y1152426D03*
X531908Y1161993D03*
X535609D03*
X539310D03*
X537460Y1158804D03*
X541160D03*
X533772Y1165290D03*
X530071D03*
X531001Y1514073D03*
X530945Y1516336D03*
X532310Y1536640D03*
X531926Y1534540D03*
X531537Y1531618D03*
X531208Y1528698D03*
X530711Y1538658D03*
X542359Y1592380D03*
X530299D03*
X534559D03*
X536319Y1602380D03*
X540599D03*
X542359Y1624292D03*
X536319Y1614292D03*
X530299Y1624292D03*
X534559D03*
X540599Y1614292D03*
X545531Y876435D03*
X552932D03*
X556633D03*
X551082Y879624D03*
X545543Y872085D03*
X554783Y879624D03*
Y886002D03*
X549231Y882813D03*
X558483Y892380D03*
X545531Y889191D03*
Y895569D03*
X552932Y889191D03*
X551082Y892380D03*
X552932Y895569D03*
X558483Y886002D03*
X545531Y882813D03*
X551082Y886002D03*
X556633Y889191D03*
X554783Y892380D03*
X556633Y895569D03*
X547381Y886002D03*
X549231Y889191D03*
Y895569D03*
X547381Y892380D03*
X556633Y882813D03*
X552932D03*
X558483Y898758D03*
X545531Y901947D03*
X552932D03*
X551082Y898758D03*
X558483Y905135D03*
Y911513D03*
X551082Y905135D03*
Y911513D03*
X552932Y908325D03*
X545531Y908324D03*
X554783Y911513D03*
X556633Y901947D03*
X554783Y905135D03*
X556633Y908325D03*
X554783Y898758D03*
X549231Y908325D03*
X547381Y898758D03*
X549231Y901947D03*
X547381Y905135D03*
Y911513D03*
X558483Y917891D03*
X551082D03*
X552932Y914702D03*
X545531D03*
X558483Y924269D03*
X551082D03*
X552932Y921080D03*
X545531D03*
X556633D03*
X554783Y924269D03*
X556633Y914702D03*
X554783Y917891D03*
X547381D03*
X549231Y921080D03*
X547381Y924269D03*
X549231Y914702D03*
X558483Y930647D03*
X545531Y927458D03*
Y933836D03*
X552932Y927458D03*
Y933836D03*
X551082Y930647D03*
X558483Y937025D03*
X545531Y940214D03*
X551082Y937025D03*
X552932Y940214D03*
X556633Y927458D03*
X554783Y930647D03*
X556633Y940214D03*
Y933836D03*
X554783Y937025D03*
X549231Y927458D03*
X547381Y937025D03*
X549231Y940214D03*
Y933836D03*
X547381Y930647D03*
X558483Y943403D03*
Y949781D03*
X545531Y946592D03*
X551082Y943403D03*
Y949781D03*
X552932Y946592D03*
X558483Y956159D03*
X545531Y952970D03*
X552932D03*
X551082Y956159D03*
X554783Y943403D03*
X556633Y946592D03*
X554783Y949781D03*
X556633Y952970D03*
X554783Y956159D03*
X547381Y943403D03*
X549231Y946592D03*
X547381Y956159D03*
X549231Y952970D03*
X547381Y949781D03*
X558483Y962537D03*
X545531Y959348D03*
Y965726D03*
X552932Y959348D03*
X551082Y962537D03*
X552932Y965726D03*
X558483Y968915D03*
X551082D03*
X556633Y965726D03*
X554783Y968915D03*
X556633Y959348D03*
X554783Y962537D03*
X547381D03*
X549231Y965726D03*
Y959348D03*
X547381Y968915D03*
X558483Y975293D03*
Y981671D03*
X545531Y972104D03*
Y978482D03*
X547381Y981671D03*
X551082Y975293D03*
X552932Y972104D03*
X551082Y981671D03*
X552932Y978482D03*
Y984860D03*
X549231D03*
X545531D03*
X556633D03*
Y978482D03*
X554783Y981671D03*
X556633Y972104D03*
X554783Y975293D03*
X547381D03*
X549231Y978482D03*
Y972104D03*
X558483Y988049D03*
Y994427D03*
X552932Y991238D03*
X551082Y994427D03*
X552932Y997616D03*
X545531Y991238D03*
Y997616D03*
X551082Y988049D03*
X558483Y1000805D03*
X551082D03*
X554783Y988049D03*
X556633Y997616D03*
X554783Y1000805D03*
X556633Y991238D03*
X547381Y994427D03*
X549231Y997616D03*
X547381Y1000805D03*
Y988049D03*
X554782Y994427D03*
X549231Y991238D03*
X558483Y1007183D03*
X545531Y1010372D03*
Y1003994D03*
X552932Y1010372D03*
X551082Y1007183D03*
X552932Y1003994D03*
X556633D03*
X554783Y1007183D03*
X549231Y1010372D03*
X547381Y1007183D03*
X549231Y1003994D03*
X556633Y1010372D03*
X554113Y1028056D03*
X546712D03*
X557814D03*
X550412D03*
X546712Y1040812D03*
Y1034434D03*
X552263Y1031245D03*
X554113Y1040812D03*
X552263Y1037623D03*
X554113Y1034434D03*
X552263Y1044001D03*
X559664Y1031245D03*
Y1037623D03*
Y1044001D03*
X555964Y1031245D03*
X557814Y1034434D03*
X555964Y1037623D03*
X557814Y1040812D03*
X555964Y1044001D03*
X544861Y1031245D03*
X550412Y1034434D03*
X548562Y1037623D03*
X544861D03*
X550412Y1040812D03*
X544861Y1044001D03*
X548562D03*
Y1031245D03*
X546712Y1047190D03*
X554113D03*
X544861Y1056757D03*
X546712Y1053568D03*
Y1059946D03*
X552263Y1056757D03*
X555964D03*
X554113Y1053568D03*
X552263Y1050379D03*
X554113Y1059946D03*
X557814D03*
X559664Y1050379D03*
Y1056757D03*
X555964Y1050379D03*
X557814Y1047190D03*
X544861Y1050379D03*
X550412Y1059946D03*
X548562Y1050379D03*
X550412Y1053568D03*
X557814D03*
X548562Y1056757D03*
X550412Y1047190D03*
X552263Y1063135D03*
X546712Y1072702D03*
Y1066324D03*
X552263Y1069513D03*
X554113Y1066324D03*
Y1072702D03*
X559664Y1063135D03*
Y1069513D03*
X555964Y1063135D03*
X557814Y1066324D03*
X555964Y1069513D03*
X557814Y1072702D03*
X550412D03*
X544861Y1063135D03*
X548562D03*
X544861Y1069513D03*
X548562D03*
X550412Y1066324D03*
X552263Y1075891D03*
X546712Y1079080D03*
X554113D03*
X546712Y1085458D03*
X552263Y1088647D03*
X554113Y1085458D03*
X552263Y1082269D03*
X559664Y1075891D03*
Y1088647D03*
Y1082269D03*
X555964Y1075891D03*
X557814Y1079080D03*
X555964Y1082269D03*
X557814Y1085458D03*
X555964Y1088647D03*
X544861Y1075891D03*
X548562D03*
X550412Y1079080D03*
X544861Y1082269D03*
X548562D03*
Y1088647D03*
X544861D03*
X550412Y1085458D03*
X546712Y1091836D03*
X554113D03*
X552263Y1095025D03*
Y1101403D03*
X554113Y1098214D03*
X546712Y1104592D03*
Y1098214D03*
X554113Y1104592D03*
X559664Y1095025D03*
Y1101403D03*
X557814Y1104592D03*
X555964Y1095025D03*
X557814Y1098214D03*
X555964Y1101403D03*
X557814Y1091836D03*
X548562Y1101403D03*
X550412Y1091836D03*
X544861Y1095025D03*
X548562D03*
X550412Y1098214D03*
X544861Y1101403D03*
X550412Y1104592D03*
X552263Y1107781D03*
X554113Y1110970D03*
X546712D03*
X554113Y1117348D03*
X552263Y1114159D03*
X546712Y1117348D03*
X559664Y1107781D03*
Y1114159D03*
X555964D03*
X557814Y1117348D03*
X555964Y1107781D03*
X557814Y1110970D03*
X550412D03*
X544861Y1114159D03*
X548562D03*
X550412Y1117348D03*
X548562Y1107781D03*
X544861D03*
X546712Y1123726D03*
X554113D03*
X552263Y1120537D03*
Y1126915D03*
Y1133293D03*
X554113Y1130103D03*
X559664Y1120537D03*
Y1126915D03*
Y1133293D03*
X546712Y1130104D03*
X555964Y1120537D03*
X557814Y1123726D03*
X555964Y1133293D03*
Y1126915D03*
X557814Y1130103D03*
X544861Y1120537D03*
X548562D03*
X550412Y1130103D03*
X544861Y1133293D03*
X548562D03*
Y1126915D03*
X544861D03*
X550412Y1123726D03*
X552263Y1139670D03*
X554113Y1136481D03*
X546712D03*
X554113Y1142859D03*
X546712D03*
Y1149237D03*
X552263Y1146048D03*
X554113Y1149237D03*
X559664Y1139670D03*
Y1146048D03*
X557814Y1136481D03*
X555964Y1139670D03*
X557814Y1142859D03*
X555964Y1146048D03*
X557814Y1149237D03*
X550412Y1136481D03*
X544861Y1139670D03*
X548562D03*
X550412Y1149237D03*
X548562Y1146048D03*
X544861D03*
X550412Y1142859D03*
X546712Y1161993D03*
X555964Y1165182D03*
X554113Y1155615D03*
X552263Y1152426D03*
X555964Y1158804D03*
X552263D03*
X548562D03*
X546712Y1155615D03*
X554113Y1161993D03*
X559664Y1152426D03*
Y1158804D03*
X555964Y1152426D03*
X557814Y1155615D03*
X544861Y1152426D03*
X548562D03*
X550412Y1155615D03*
X557814Y1161993D03*
X544861Y1158804D03*
X558679Y1592380D03*
X546619D03*
X554419D03*
X548379Y1602380D03*
X552659D03*
X558679Y1624292D03*
X548379Y1614292D03*
X546619Y1624292D03*
X554419D03*
X552659Y1614292D03*
X562184Y879624D03*
X569586Y873246D03*
X562184D03*
X565885Y879624D03*
X564034Y876435D03*
X573286Y879624D03*
X571436Y876435D03*
X569586Y879624D03*
X560334Y882813D03*
X564034D03*
X569586Y886002D03*
X571436Y882813D03*
Y889191D03*
X564034D03*
X565885Y892380D03*
X571436Y895569D03*
X562184Y886002D03*
X560334Y889191D03*
Y895569D03*
X562184Y892380D03*
X564034Y895569D03*
X565885Y886002D03*
X567735Y882813D03*
X564034Y901947D03*
X571436D03*
X565885Y898758D03*
X564034Y908325D03*
X571436D03*
X565885Y911513D03*
X560334Y908325D03*
X562184Y898758D03*
X560334Y901947D03*
X562184Y905135D03*
Y911513D03*
X565885Y905135D03*
Y917891D03*
X571436Y914702D03*
X564034Y921080D03*
X571436D03*
X562184Y917891D03*
X560334Y921080D03*
X562184Y924269D03*
X560334Y914702D03*
X565885Y924269D03*
X564034Y914702D03*
Y927458D03*
X571436D03*
X565885Y930647D03*
X571436Y933836D03*
X565885Y937025D03*
X564034Y940214D03*
X571436D03*
X560334Y927458D03*
X562184Y937025D03*
X560334Y940214D03*
Y933836D03*
X562184Y930647D03*
X564034Y933836D03*
X565885Y949781D03*
X564034Y946592D03*
X571436D03*
Y952970D03*
X565885Y956159D03*
X562184Y943403D03*
X560334Y946592D03*
X562184Y956159D03*
X560334Y952970D03*
X562184Y949781D03*
X564034Y952970D03*
X565885Y943403D03*
X564034Y959348D03*
X571436D03*
X564034Y965726D03*
X571436D03*
X565885Y968915D03*
X562184Y962537D03*
X560334Y965726D03*
Y959348D03*
X562184Y968915D03*
X565885Y962537D03*
X562184Y981671D03*
X565885Y975293D03*
X571436Y972104D03*
X564034Y978482D03*
X571436D03*
X567735Y984860D03*
X560334D03*
X564034D03*
X571436D03*
X562184Y975293D03*
X560334Y978482D03*
Y972104D03*
X565885Y981671D03*
X564034Y972104D03*
X569586Y988049D03*
X571436Y991238D03*
X565885Y994427D03*
X564034Y997616D03*
X571436D03*
X565885Y988049D03*
X562184Y994427D03*
X560334Y997616D03*
X562184Y1000805D03*
Y988049D03*
X565885Y1000805D03*
X564034Y991238D03*
X560334D03*
X571436Y1010372D03*
X565885Y1007183D03*
X564034Y1003994D03*
X571436D03*
X560334Y1010372D03*
X562184Y1007183D03*
X560334Y1003994D03*
X564034Y1010372D03*
X567735D03*
X565216Y1028056D03*
X572617D03*
X568916D03*
X561515D03*
X567066Y1031245D03*
X565215Y1034434D03*
Y1040812D03*
X572617Y1034434D03*
Y1040812D03*
X567066Y1044001D03*
X561515Y1034434D03*
X563365Y1037623D03*
X561515Y1040812D03*
X567066Y1037623D03*
X563365Y1044001D03*
Y1031245D03*
X565215Y1059946D03*
X572617Y1047190D03*
X567066Y1050379D03*
X572617Y1053568D03*
X570767Y1056757D03*
X565215Y1053568D03*
X572617Y1059946D03*
X568916D03*
X561515D03*
X563365Y1050379D03*
X561515Y1053568D03*
X567066Y1056757D03*
X565215Y1047190D03*
X563365Y1056757D03*
X561515Y1047190D03*
X567066Y1063135D03*
X572617Y1066324D03*
Y1072702D03*
X567066Y1069513D03*
X565215Y1072702D03*
X561515D03*
X563365Y1063135D03*
Y1069513D03*
X561515Y1066324D03*
X565215D03*
Y1079080D03*
X572617D03*
X567066Y1088647D03*
X572617Y1085458D03*
X567066Y1082269D03*
X563365Y1075891D03*
X561515Y1079080D03*
X563365Y1082269D03*
Y1088647D03*
X561515Y1085458D03*
X565215D03*
X567066Y1075891D03*
X572617Y1091836D03*
X565215D03*
X572617Y1104592D03*
Y1098214D03*
X567066Y1101403D03*
X565215Y1098214D03*
X563365Y1101403D03*
X561515Y1091836D03*
X563365Y1095025D03*
X561515Y1098214D03*
Y1104592D03*
X565215D03*
X567066Y1095025D03*
Y1107781D03*
X572617Y1110970D03*
X565215D03*
X572617Y1117348D03*
X565215D03*
X561515Y1110970D03*
X563365Y1114159D03*
X561515Y1117348D03*
X563365Y1107781D03*
X567066Y1114159D03*
X572617Y1123726D03*
X567066Y1120537D03*
Y1126915D03*
X572617Y1130103D03*
X565215D03*
X563365Y1120537D03*
X561515Y1130103D03*
X563365Y1133293D03*
Y1126915D03*
X561515Y1123726D03*
X567066Y1133293D03*
X565215Y1123726D03*
X572617Y1136481D03*
X565215Y1149237D03*
X572617D03*
X567066Y1146048D03*
X572617Y1142859D03*
X567066Y1139670D03*
X565215Y1136481D03*
X561515D03*
X563365Y1139670D03*
X561515Y1149237D03*
X563365Y1146048D03*
X561515Y1142859D03*
X565215D03*
X567066Y1158804D03*
X574467D03*
X565215Y1155615D03*
X568916D03*
X572617D03*
X561515D03*
X565215Y1161993D03*
X563365Y1152426D03*
Y1158804D03*
X567066Y1152426D03*
X572617Y1161993D03*
X570767Y1165182D03*
X567066D03*
X568916Y1161993D03*
X570815Y1507509D03*
X573066Y1507460D03*
X570980Y1513218D03*
X569722Y1521612D03*
X569321Y1518121D03*
X569814Y1523810D03*
Y1528725D03*
X569768Y1535698D03*
Y1537898D03*
X571215Y1540317D03*
X570739Y1592380D03*
X566479D03*
X572499Y1602380D03*
X560439D03*
X564719D03*
X572499Y1614292D03*
X570739Y1624292D03*
X560439Y1614292D03*
X566479Y1624292D03*
X564719Y1614292D03*
X576987Y879624D03*
X575137Y882813D03*
X576987Y886002D03*
Y892380D03*
Y898758D03*
X577728Y906182D03*
Y912560D03*
Y918938D03*
Y925316D03*
Y931694D03*
Y938072D03*
Y944450D03*
Y950828D03*
Y957206D03*
Y963584D03*
Y969962D03*
Y976340D03*
Y982718D03*
Y989096D03*
Y995474D03*
Y1008230D03*
Y1001852D03*
X578909Y1030198D03*
Y1036576D03*
Y1042954D03*
Y1049332D03*
Y1055710D03*
Y1062088D03*
Y1074844D03*
Y1068466D03*
Y1087600D03*
Y1081222D03*
Y1093978D03*
Y1100356D03*
Y1106734D03*
Y1113112D03*
Y1119490D03*
Y1125868D03*
Y1132246D03*
Y1138623D03*
Y1145001D03*
Y1151379D03*
X578168Y1158804D03*
X575182Y1507514D03*
X580489Y1507295D03*
X585214D03*
X588214Y1521453D03*
X583489D03*
X578765D03*
X579095Y1514243D03*
X583819D03*
X588544D03*
X577923Y1519195D03*
X580390Y1516970D03*
X585114D03*
X581965Y1519698D03*
X586689D03*
X588765Y1528853D03*
X584040D03*
X579316D03*
X588264Y1536063D03*
X583539D03*
X578814D03*
X580390Y1530608D03*
X585114D03*
X581965Y1533336D03*
X586689D03*
X588765Y1526353D03*
X588214Y1523953D03*
X578765D03*
X583489D03*
X579316Y1526353D03*
X584040D03*
X585214Y1542641D03*
X580489D03*
X575286Y1542425D03*
Y1544625D03*
X578539Y1592380D03*
X582799D03*
X584559Y1602380D03*
X588839D03*
X576779D03*
X584559Y1614292D03*
X582799Y1624292D03*
X578539D03*
X588839Y1614292D03*
X576779D03*
X589938Y1507295D03*
X594662D03*
X599387D03*
X604111D03*
X602387Y1521453D03*
X597662D03*
X592938D03*
X593268Y1514243D03*
X597993D03*
X602717D03*
X589839Y1516970D03*
X594563D03*
X599287D03*
X604012D03*
X591413Y1519698D03*
X596138D03*
X600862D03*
X602437Y1536063D03*
X597713D03*
X602938Y1528853D03*
X598213D03*
X593489D03*
X592988Y1536063D03*
X589839Y1530608D03*
X594563D03*
X599287D03*
X604012D03*
X591413Y1533336D03*
X596138D03*
X600862D03*
X602387Y1523953D03*
X602938Y1526353D03*
X592938Y1523953D03*
X593489Y1526353D03*
X598213D03*
X597662Y1523953D03*
X589938Y1542641D03*
X604111D03*
X599387D03*
X594662D03*
X602659Y1592380D03*
X590599D03*
X594859D03*
X596619Y1602380D03*
X600899D03*
X602659Y1624292D03*
X596619Y1614292D03*
X594859Y1624292D03*
X590599D03*
X600899Y1614292D03*
X608836Y1507295D03*
X613560D03*
X618284D03*
X616560Y1521453D03*
X611836D03*
X607111D03*
X607441Y1514243D03*
X612166D03*
X616890D03*
X608736Y1516970D03*
X613461D03*
X618185D03*
X605587Y1519698D03*
X610311D03*
X615035D03*
X611886Y1536063D03*
X617111Y1528853D03*
X612387D03*
X607662D03*
X607161Y1536063D03*
X616610D03*
X608736Y1530608D03*
X613461D03*
X618185D03*
X605587Y1533336D03*
X610311D03*
X615035D03*
X616560Y1523953D03*
X617111Y1526353D03*
X607111Y1523953D03*
X607662Y1526353D03*
X612387D03*
X611836Y1523953D03*
X613560Y1542641D03*
X618284D03*
X608836D03*
X618979Y1592380D03*
X614719D03*
X606919D03*
X608679Y1602380D03*
X612959D03*
X618979Y1624292D03*
X608679Y1614292D03*
X606919Y1624292D03*
X614719D03*
X612959Y1614292D03*
X623009Y1507295D03*
X627733D03*
X632458D03*
X630733Y1521453D03*
X626009D03*
X621284D03*
X621615Y1514243D03*
X626339D03*
X631063D03*
X627634Y1516970D03*
X632358D03*
X622909D03*
X629209Y1519698D03*
X633933D03*
X619760D03*
X624484D03*
X626059Y1536063D03*
X621335D03*
X631284Y1528853D03*
X626560D03*
X621835D03*
X630783Y1536063D03*
X627634Y1530608D03*
X632358D03*
X622909D03*
X629209Y1533336D03*
X633933D03*
X619760D03*
X624484D03*
X626009Y1523953D03*
X626560Y1526353D03*
X631284D03*
X630733Y1523953D03*
X621835Y1526353D03*
X621284Y1523953D03*
X632458Y1542641D03*
X627733D03*
X623009D03*
X631039Y1592380D03*
X626779D03*
X632799Y1602286D03*
X620739Y1602380D03*
X625019D03*
X631039Y1624292D03*
X632799Y1614292D03*
X626779Y1624292D03*
X620739Y1614292D03*
X625019D03*
X637182Y1507295D03*
X641906D03*
X646631D03*
X645237Y1514243D03*
X644907Y1521453D03*
X640182D03*
X635458D03*
X635788Y1514243D03*
X640512D03*
X637083Y1516970D03*
X641807D03*
X646532D03*
X638657Y1519698D03*
X643382D03*
X648106D03*
X644957Y1536063D03*
X635508D03*
X645458Y1528853D03*
X640733D03*
X636009D03*
X640232Y1536063D03*
X637083Y1530608D03*
X641807D03*
X646532D03*
X638657Y1533336D03*
X643382D03*
X648106D03*
X644907Y1523953D03*
X640733Y1526353D03*
X640182Y1523953D03*
X635458D03*
X636009Y1526353D03*
X645458D03*
X646631Y1542641D03*
X641906D03*
X637182D03*
X638839Y1592380D03*
X644869Y1602380D03*
X637079D03*
X644869Y1614292D03*
X638839Y1624292D03*
X637079Y1614292D03*
X651355Y1507295D03*
X657656Y1507355D03*
X655556D03*
X654376Y1521453D03*
X649631D03*
X649961Y1514243D03*
X651256Y1516970D03*
X652831Y1519698D03*
X659063Y1514073D03*
X659007Y1516336D03*
X650182Y1528853D03*
X649681Y1536063D03*
X655012D03*
X651256Y1530608D03*
X652831Y1533336D03*
X650182Y1526353D03*
X649631Y1523953D03*
X659358Y1536640D03*
Y1534540D03*
X659359Y1531618D03*
X659270Y1528698D03*
X662353Y1534413D03*
X660877Y1530158D03*
X651355Y1542641D03*
X658773Y1538658D03*
X706780Y432492D03*
Y429342D03*
Y426192D03*
Y423043D03*
Y419893D03*
X703630Y432492D03*
Y429342D03*
Y426192D03*
Y423043D03*
Y419893D03*
X700481Y432492D03*
Y429342D03*
Y426192D03*
Y423043D03*
Y419893D03*
X697331Y432492D03*
Y429342D03*
Y426192D03*
Y423043D03*
Y419893D03*
X706780Y448240D03*
Y445090D03*
Y441940D03*
Y438791D03*
Y435641D03*
X703630Y448240D03*
Y445090D03*
Y441940D03*
Y438791D03*
Y435641D03*
X700481Y448240D03*
Y445090D03*
Y441940D03*
Y438791D03*
Y435641D03*
X697331Y448240D03*
Y445090D03*
Y441940D03*
Y438791D03*
Y435641D03*
X706780Y463988D03*
Y460838D03*
Y457688D03*
Y454539D03*
Y451389D03*
X703630Y463988D03*
Y460838D03*
Y457688D03*
Y454539D03*
Y451389D03*
X700481Y463988D03*
Y460838D03*
Y457688D03*
Y454539D03*
Y451389D03*
X697331Y463988D03*
Y460838D03*
Y457688D03*
Y454539D03*
Y451389D03*
X706780Y476586D03*
Y473436D03*
Y470287D03*
Y467137D03*
X703630Y476586D03*
Y473436D03*
Y470287D03*
Y467137D03*
X700481Y476586D03*
Y473436D03*
Y470287D03*
Y467137D03*
X697331Y476586D03*
Y473436D03*
Y470287D03*
Y467137D03*
X706780Y486035D03*
Y482885D03*
Y479736D03*
X703630Y486035D03*
Y482885D03*
Y479736D03*
X700481Y486035D03*
Y482885D03*
Y479736D03*
X697331Y486035D03*
Y482885D03*
Y479736D03*
X722528Y432492D03*
Y429342D03*
Y426192D03*
Y423043D03*
Y419893D03*
X719378Y432492D03*
Y429342D03*
Y426192D03*
Y423043D03*
Y419893D03*
X716229Y432492D03*
Y429342D03*
Y426192D03*
Y423043D03*
Y419893D03*
X713079Y432492D03*
Y429342D03*
Y426192D03*
Y423043D03*
Y419893D03*
X709930Y432492D03*
Y429342D03*
Y426192D03*
Y423043D03*
Y419893D03*
X722528Y448240D03*
Y445090D03*
Y441940D03*
Y438791D03*
Y435641D03*
X719378Y448240D03*
Y445090D03*
Y441940D03*
Y438791D03*
Y435641D03*
X716229Y448240D03*
Y445090D03*
Y441940D03*
Y438791D03*
Y435641D03*
X713079Y448240D03*
Y445090D03*
Y441940D03*
Y438791D03*
Y435641D03*
X709930Y448240D03*
Y445090D03*
Y441940D03*
Y438791D03*
Y435641D03*
X722528Y463988D03*
Y460838D03*
Y457688D03*
Y454539D03*
Y451389D03*
X719378Y463988D03*
Y460838D03*
Y457688D03*
Y454539D03*
Y451389D03*
X716229Y463988D03*
Y460838D03*
Y457688D03*
Y454539D03*
Y451389D03*
X713079Y463988D03*
Y460838D03*
Y457688D03*
Y454539D03*
Y451389D03*
X709930Y463988D03*
Y460838D03*
Y457688D03*
Y454539D03*
Y451389D03*
X722528Y476586D03*
Y473436D03*
Y470287D03*
Y467137D03*
X719378Y476586D03*
Y473436D03*
Y470287D03*
Y467137D03*
X716229Y476586D03*
Y473436D03*
Y470287D03*
Y467137D03*
X713079Y476586D03*
Y473436D03*
Y470287D03*
Y467137D03*
X709930Y476586D03*
Y473436D03*
Y470287D03*
Y467137D03*
X722528Y486035D03*
Y482885D03*
Y479736D03*
X719378Y486035D03*
Y482885D03*
Y479736D03*
X716229Y486035D03*
Y482885D03*
Y479736D03*
X713079Y486035D03*
Y482885D03*
Y479736D03*
X709930Y486035D03*
Y482885D03*
Y479736D03*
X738276Y432492D03*
Y429342D03*
Y426192D03*
Y423043D03*
Y419893D03*
X735126Y432492D03*
Y429342D03*
Y426192D03*
Y423043D03*
Y419893D03*
X731977Y432492D03*
Y429342D03*
Y426192D03*
Y423043D03*
Y419893D03*
X728827Y432492D03*
Y429342D03*
Y426192D03*
Y423043D03*
Y419893D03*
X725678Y432492D03*
Y429342D03*
Y426192D03*
Y423043D03*
Y419893D03*
X738276Y448240D03*
Y445090D03*
Y441940D03*
Y438791D03*
Y435641D03*
X735126Y448240D03*
Y445090D03*
Y441940D03*
Y438791D03*
Y435641D03*
X731977Y448240D03*
Y445090D03*
Y441940D03*
Y438791D03*
Y435641D03*
X728827Y448240D03*
Y445090D03*
Y441940D03*
Y438791D03*
Y435641D03*
X725678Y448240D03*
Y445090D03*
Y441940D03*
Y438791D03*
Y435641D03*
X738276Y463988D03*
Y460838D03*
Y457688D03*
Y454539D03*
Y451389D03*
X735126Y463988D03*
Y460838D03*
Y457688D03*
Y454539D03*
Y451389D03*
X731977Y463988D03*
Y460838D03*
Y457688D03*
Y454539D03*
Y451389D03*
X728827Y463988D03*
Y460838D03*
Y457688D03*
Y454539D03*
Y451389D03*
X725678Y463988D03*
Y460838D03*
Y457688D03*
Y454539D03*
Y451389D03*
X738276Y476586D03*
Y473436D03*
Y470287D03*
Y467137D03*
X735126Y476586D03*
Y473436D03*
Y470287D03*
Y467137D03*
X731977Y476586D03*
Y473436D03*
Y470287D03*
Y467137D03*
X728827Y476586D03*
Y473436D03*
Y470287D03*
Y467137D03*
X725678Y476586D03*
Y473436D03*
Y470287D03*
Y467137D03*
X738276Y486035D03*
Y482885D03*
Y479736D03*
X735126Y486035D03*
Y482885D03*
Y479736D03*
X731977Y486035D03*
Y482885D03*
Y479736D03*
X728827Y486035D03*
Y482885D03*
Y479736D03*
X725678Y486035D03*
Y482885D03*
Y479736D03*
X750874Y432492D03*
Y429342D03*
Y426192D03*
Y423043D03*
Y419893D03*
X747725Y432492D03*
Y429342D03*
Y426192D03*
Y423043D03*
Y419893D03*
X744575Y432492D03*
Y429342D03*
Y426192D03*
Y423043D03*
Y419893D03*
X741426Y432492D03*
Y429342D03*
Y426192D03*
Y423043D03*
Y419893D03*
X750874Y448240D03*
Y445090D03*
Y441940D03*
Y438791D03*
Y435641D03*
X747725Y448240D03*
Y445090D03*
Y441940D03*
Y438791D03*
Y435641D03*
X744575Y448240D03*
Y445090D03*
Y441940D03*
Y438791D03*
Y435641D03*
X741426Y448240D03*
Y445090D03*
Y441940D03*
Y438791D03*
Y435641D03*
X750874Y463988D03*
Y460838D03*
Y457688D03*
Y454539D03*
Y451389D03*
X747725Y463988D03*
Y460838D03*
Y457688D03*
Y454539D03*
Y451389D03*
X744575Y463988D03*
Y460838D03*
Y457688D03*
Y454539D03*
Y451389D03*
X741426Y463988D03*
Y460838D03*
Y457688D03*
Y454539D03*
Y451389D03*
X750874Y476586D03*
Y473436D03*
Y470287D03*
Y467137D03*
X747725Y476586D03*
Y473436D03*
Y470287D03*
Y467137D03*
X744575Y476586D03*
Y473436D03*
Y470287D03*
Y467137D03*
X741426Y476586D03*
Y473436D03*
Y470287D03*
Y467137D03*
X750874Y486035D03*
Y482885D03*
Y479736D03*
X747725Y486035D03*
Y482885D03*
Y479736D03*
X744575Y486035D03*
Y482885D03*
Y479736D03*
X741426Y486035D03*
Y482885D03*
Y479736D03*
X763473Y432492D03*
Y429342D03*
Y426192D03*
Y423043D03*
Y419893D03*
X760323Y432492D03*
Y429342D03*
Y426192D03*
Y423043D03*
Y419893D03*
X757174Y432492D03*
Y429342D03*
Y426192D03*
Y423043D03*
Y419893D03*
X754024Y432492D03*
Y429342D03*
Y426192D03*
Y423043D03*
Y419893D03*
X763473Y448240D03*
Y445090D03*
Y441940D03*
Y438791D03*
Y435641D03*
X760323Y448240D03*
Y445090D03*
Y441940D03*
Y438791D03*
Y435641D03*
X757174Y448240D03*
Y445090D03*
Y441940D03*
Y438791D03*
Y435641D03*
X754024Y448240D03*
Y445090D03*
Y441940D03*
Y438791D03*
Y435641D03*
X763473Y463988D03*
Y460838D03*
Y457688D03*
Y454539D03*
Y451389D03*
X760323Y463988D03*
Y460838D03*
Y457688D03*
Y454539D03*
Y451389D03*
X757174Y463988D03*
Y460838D03*
Y457688D03*
Y454539D03*
Y451389D03*
X754024Y463988D03*
Y460838D03*
Y457688D03*
Y454539D03*
Y451389D03*
X763473Y476586D03*
Y473436D03*
Y470287D03*
Y467137D03*
X760323Y476586D03*
Y473436D03*
Y470287D03*
Y467137D03*
X757174Y476586D03*
Y473436D03*
Y470287D03*
Y467137D03*
X754024Y476586D03*
Y473436D03*
Y470287D03*
Y467137D03*
X763473Y486035D03*
Y482885D03*
Y479736D03*
X760323Y486035D03*
Y482885D03*
Y479736D03*
X757174Y486035D03*
Y482885D03*
Y479736D03*
X754024Y486035D03*
Y482885D03*
Y479736D03*
X1184959Y1551121D03*
X1185452Y1556810D03*
Y1561725D03*
X1185360Y1554612D03*
X1185406Y1568698D03*
Y1570898D03*
X1190820Y1540512D03*
X1194733Y1547243D03*
X1196127Y1540295D03*
X1199457Y1547243D03*
X1193561Y1552195D03*
X1196028Y1549970D03*
X1197603Y1552698D03*
X1188653Y1540509D03*
X1186453D03*
X1186618Y1546218D03*
X1199127Y1554453D03*
X1194403D03*
X1199678Y1561853D03*
X1194954D03*
X1196028Y1563608D03*
X1197603Y1566336D03*
X1194403Y1556953D03*
X1199678Y1559353D03*
X1194954D03*
X1199127Y1556953D03*
X1199177Y1569063D03*
X1196127Y1575641D03*
X1194452Y1569063D03*
X1190924Y1575425D03*
X1186853Y1573317D03*
X1190924Y1577625D03*
X1193839Y1625380D03*
X1199879Y1635380D03*
Y1647292D03*
X1193839Y1657292D03*
X1200852Y1540295D03*
X1204182Y1547243D03*
X1205576Y1540295D03*
X1208906Y1547243D03*
X1210300Y1540295D03*
X1213631Y1547243D03*
X1215025Y1540295D03*
X1200752Y1549970D03*
X1205477D03*
X1210201D03*
X1214925D03*
X1202327Y1552698D03*
X1207051D03*
X1211776D03*
X1213300Y1554453D03*
X1208576D03*
X1203852D03*
X1213851Y1561853D03*
X1209127D03*
X1204403D03*
X1200752Y1563608D03*
X1205477D03*
X1210201D03*
X1214925D03*
X1202327Y1566336D03*
X1207051D03*
X1211776D03*
X1208576Y1556953D03*
X1204403Y1559353D03*
X1209127D03*
X1203852Y1556953D03*
X1213300D03*
X1213851Y1559353D03*
X1213351Y1569063D03*
X1210300Y1575641D03*
X1208626Y1569063D03*
X1203902D03*
X1200852Y1575641D03*
X1205576D03*
X1215025D03*
X1205899Y1625380D03*
X1201639D03*
X1213699D03*
X1207659Y1635380D03*
X1211939D03*
X1207659Y1647292D03*
X1211939D03*
X1201639Y1657292D03*
X1205899D03*
X1213699D03*
X1218355Y1547243D03*
X1219749Y1540295D03*
X1223079Y1547243D03*
X1227804D03*
X1229198Y1540295D03*
X1224474D03*
X1219650Y1549970D03*
X1224374D03*
X1229099D03*
X1216500Y1552698D03*
X1221225D03*
X1225949D03*
X1227474Y1554453D03*
X1222749D03*
X1218025D03*
X1228025Y1561853D03*
X1223300D03*
X1218576D03*
X1219650Y1563608D03*
X1224374D03*
X1229099D03*
X1216500Y1566336D03*
X1221225D03*
X1225949D03*
X1218025Y1556953D03*
X1218576Y1559353D03*
X1227474Y1556953D03*
X1228025Y1559353D03*
X1222749Y1556953D03*
X1223300Y1559353D03*
X1227524Y1569063D03*
X1218075D03*
X1222799D03*
X1219749Y1575641D03*
X1224474D03*
X1229198D03*
X1217959Y1625380D03*
X1225759D03*
X1230019D03*
X1223999Y1635380D03*
X1219719D03*
X1223999Y1647292D03*
X1219719D03*
X1217959Y1657292D03*
X1230019D03*
X1225759D03*
X1232528Y1547243D03*
X1233922Y1540295D03*
X1237253Y1547243D03*
X1241977D03*
X1243371Y1540295D03*
X1238647D03*
X1243272Y1549970D03*
X1233823D03*
X1238547D03*
X1244847Y1552698D03*
X1230673D03*
X1235398D03*
X1240122D03*
X1241647Y1554453D03*
X1236922D03*
X1232198D03*
X1242198Y1561853D03*
X1237473D03*
X1232749D03*
X1243272Y1563608D03*
X1233823D03*
X1238547D03*
X1244847Y1566336D03*
X1230673D03*
X1235398D03*
X1240122D03*
X1241647Y1556953D03*
X1242198Y1559353D03*
X1232198Y1556953D03*
X1232749Y1559353D03*
X1236922Y1556953D03*
X1237473Y1559353D03*
X1241697Y1569063D03*
X1236973D03*
X1238647Y1575641D03*
X1232248Y1569063D03*
X1233922Y1575641D03*
X1243371D03*
X1237819Y1625380D03*
X1242079D03*
X1231779Y1635380D03*
X1236059D03*
X1243839D03*
X1236059Y1647292D03*
X1231779D03*
X1243839D03*
X1237819Y1657292D03*
X1242079D03*
X1246701Y1547243D03*
X1248096Y1540295D03*
X1251426Y1547243D03*
X1252820Y1540295D03*
X1256150Y1547243D03*
X1257544Y1540295D03*
X1247996Y1549970D03*
X1252721D03*
X1257445D03*
X1249571Y1552698D03*
X1254295D03*
X1259020D03*
X1255820Y1554453D03*
X1251096D03*
X1246371D03*
X1256371Y1561853D03*
X1251647D03*
X1246922D03*
X1247996Y1563608D03*
X1252721D03*
X1257445D03*
X1249571Y1566336D03*
X1254295D03*
X1259020D03*
X1251647Y1559353D03*
X1251096Y1556953D03*
X1255820D03*
X1256371Y1559353D03*
X1246371Y1556953D03*
X1246922Y1559353D03*
X1251146Y1569063D03*
X1257544Y1575641D03*
X1255870Y1569063D03*
X1246421D03*
X1248096Y1575641D03*
X1252820D03*
X1249879Y1625380D03*
X1254139D03*
X1248119Y1635380D03*
X1255899D03*
X1260179D03*
X1248119Y1647292D03*
X1255899D03*
X1260179D03*
X1254139Y1657292D03*
X1249879D03*
X1260875Y1547243D03*
X1262269Y1540295D03*
X1265599Y1547243D03*
X1266993Y1540295D03*
X1262170Y1549970D03*
X1266894D03*
X1263744Y1552698D03*
X1268469D03*
X1273294Y1540355D03*
X1271194D03*
X1274701Y1547073D03*
X1274645Y1549336D03*
X1270014Y1554453D03*
X1265269D03*
X1260545D03*
X1265820Y1561853D03*
X1261096D03*
X1262170Y1563608D03*
X1266894D03*
X1263744Y1566336D03*
X1268469D03*
X1265269Y1556953D03*
X1265820Y1559353D03*
X1261096D03*
X1260545Y1556953D03*
X1274996Y1567540D03*
X1274997Y1564618D03*
X1274908Y1561698D03*
X1260595Y1569063D03*
X1270650D03*
X1266993Y1575641D03*
X1265319Y1569063D03*
X1262269Y1575641D03*
X1274411Y1571658D03*
X1274996Y1569640D03*
X1266199Y1625380D03*
X1261939D03*
X1273999D03*
X1267959Y1635380D03*
X1272239D03*
X1267959Y1647292D03*
X1272239D03*
X1266199Y1657292D03*
X1261939D03*
X1273999D03*
X1286697Y873245D03*
Y879623D03*
X1279296D03*
X1288549Y876434D03*
X1284847Y895568D03*
Y882812D03*
X1286697Y886001D03*
X1281146Y882812D03*
X1279296Y886001D03*
X1284847Y889190D03*
X1279296Y892379D03*
X1284847Y901946D03*
X1279296Y898757D03*
X1284847Y908324D03*
X1278555Y906181D03*
Y912559D03*
X1284847Y914701D03*
X1278555Y918937D03*
X1284847Y921079D03*
X1278555Y925315D03*
X1284847Y927457D03*
Y933835D03*
X1278555Y931693D03*
Y938071D03*
X1284847Y940213D03*
Y946591D03*
X1278555Y950827D03*
X1284847Y952969D03*
X1278555Y944449D03*
X1284847Y959347D03*
X1278555Y957205D03*
X1284847Y965725D03*
X1278555Y963583D03*
Y969961D03*
X1284847Y972103D03*
X1278555Y976339D03*
X1284847Y978481D03*
X1278555Y982717D03*
X1284847Y984859D03*
X1288548D03*
X1278555Y995473D03*
X1284847Y991237D03*
X1286697Y988048D03*
X1278555Y989095D03*
X1284847Y997615D03*
Y1010371D03*
Y1003993D03*
X1278555Y1008229D03*
Y1001851D03*
X1288548Y1010371D03*
X1279736Y1030197D03*
X1286028Y1028055D03*
X1289729D03*
X1286028Y1034433D03*
Y1040811D03*
X1279736Y1042953D03*
Y1036575D03*
X1286028Y1047189D03*
Y1053567D03*
X1287878Y1056756D03*
X1289729Y1059945D03*
X1286028D03*
X1279736Y1055709D03*
Y1049331D03*
Y1062087D03*
Y1068465D03*
Y1074843D03*
X1286028Y1066323D03*
Y1072701D03*
Y1079079D03*
X1279736Y1081221D03*
Y1087599D03*
X1286028Y1085457D03*
X1279736Y1093977D03*
X1286028Y1091835D03*
X1279736Y1100355D03*
X1286028Y1098213D03*
Y1104591D03*
X1279736Y1106733D03*
X1286028Y1110969D03*
X1279736Y1113111D03*
Y1119489D03*
X1286028Y1117347D03*
X1279736Y1125867D03*
X1286028Y1123725D03*
Y1130102D03*
X1279736Y1132245D03*
Y1138622D03*
X1286028Y1136480D03*
Y1142858D03*
X1279736Y1145000D03*
X1286028Y1149236D03*
X1279736Y1151378D03*
Y1157756D03*
X1289729Y1155614D03*
X1286028D03*
X1284178Y1158803D03*
X1287878Y1165181D03*
X1278259Y1625380D03*
X1286059D03*
X1280019Y1635380D03*
X1284299D03*
X1280019Y1647292D03*
X1284299D03*
X1278259Y1657292D03*
X1286059D03*
X1297800Y879623D03*
X1299650Y876434D03*
X1290398Y873245D03*
X1301500Y879623D03*
X1303351Y876434D03*
X1294099Y879623D03*
X1295949Y876434D03*
X1290399Y879623D03*
X1303351Y882812D03*
Y895568D03*
X1290398Y886001D03*
Y892379D03*
X1292249Y882812D03*
X1297800Y886001D03*
X1301500D03*
X1295949Y882812D03*
X1292249Y889190D03*
X1303351D03*
X1297800Y892379D03*
X1294099Y886001D03*
X1299650Y889190D03*
X1295949D03*
X1301500Y892379D03*
X1295949Y895568D03*
X1299650D03*
X1294099Y892379D03*
X1292249Y895568D03*
X1299650Y882812D03*
X1290398Y898757D03*
Y911512D03*
X1292249Y901946D03*
X1297800Y898757D03*
X1303351Y901946D03*
X1292249Y908324D03*
X1297800Y905134D03*
Y911512D03*
X1303351Y908324D03*
X1295949D03*
X1301500Y911512D03*
X1294099Y898757D03*
X1299650Y901946D03*
X1295949D03*
X1301500Y905134D03*
X1294099D03*
X1299650Y908324D03*
X1294099Y911512D03*
X1301500Y898757D03*
X1290398Y905134D03*
Y917890D03*
X1297800D03*
X1303351Y914701D03*
Y921079D03*
X1297800Y924268D03*
X1292249Y921079D03*
X1294099Y917890D03*
X1299650Y921079D03*
X1295949D03*
X1301500Y924268D03*
X1294099D03*
X1295949Y914701D03*
X1299650D03*
X1301500Y917890D03*
X1292249Y914701D03*
X1290398Y924268D03*
X1297800Y930646D03*
X1303351Y927457D03*
Y933835D03*
X1292249Y927457D03*
X1303351Y940213D03*
X1297800Y937024D03*
X1292249Y940213D03*
X1290398Y930646D03*
Y937024D03*
X1299650Y927457D03*
X1295949D03*
X1301500Y930646D03*
X1294099Y937024D03*
X1299650Y940213D03*
X1295949D03*
Y933835D03*
X1299650D03*
X1294099Y930646D03*
X1301500Y937024D03*
X1292249Y933835D03*
X1290398Y949780D03*
Y956158D03*
X1297800Y949780D03*
X1303351Y946591D03*
X1292249D03*
X1297800Y943402D03*
X1303351Y952969D03*
X1297800Y956158D03*
X1301500Y943402D03*
X1294099D03*
X1299650Y946591D03*
X1295949D03*
X1301500Y949780D03*
X1294099Y956158D03*
X1295949Y952969D03*
X1299650D03*
X1294099Y949780D03*
X1301500Y956158D03*
X1292249Y952969D03*
X1290398Y943402D03*
Y968914D03*
X1297800Y962536D03*
X1303351Y959347D03*
Y965725D03*
X1292249Y959347D03*
Y965725D03*
X1297800Y968914D03*
X1294099Y962536D03*
X1299650Y965725D03*
X1295949D03*
X1301500Y968914D03*
X1299650Y959347D03*
X1295949D03*
X1301500Y962536D03*
X1294099Y968914D03*
X1290398Y962536D03*
Y975292D03*
X1297800Y981670D03*
Y975292D03*
X1303351Y972103D03*
Y978481D03*
X1294099Y981670D03*
X1292249Y978481D03*
X1303351Y984859D03*
X1295949D03*
X1292249D03*
X1299650D03*
X1294099Y975292D03*
X1299650Y978481D03*
X1295949D03*
X1301500Y981670D03*
X1295949Y972103D03*
X1299650D03*
X1301500Y975292D03*
X1292249Y972103D03*
X1290398Y981670D03*
Y988048D03*
Y994426D03*
X1297800D03*
Y988048D03*
X1303351Y991237D03*
Y997615D03*
X1292249D03*
X1297800Y1000804D03*
X1301500Y988048D03*
X1294099Y994426D03*
X1295949Y997615D03*
X1299650D03*
X1301500Y1000804D03*
X1294099D03*
X1295949Y991237D03*
X1301500Y994426D03*
X1292249Y991237D03*
X1290398Y1000804D03*
X1299650Y991237D03*
X1294099Y988048D03*
X1290398Y1007182D03*
X1292249Y1010371D03*
X1297800Y1007182D03*
X1303351Y1010371D03*
Y1003993D03*
X1292249D03*
X1295949Y1010371D03*
X1294099Y1007182D03*
X1295949Y1003993D03*
X1299650D03*
X1301500Y1007182D03*
X1299650Y1010371D03*
X1304532Y1028055D03*
X1293430D03*
X1300831D03*
X1297130D03*
X1293430Y1034433D03*
Y1040811D03*
X1298981Y1044000D03*
Y1037622D03*
X1304532Y1034433D03*
Y1040811D03*
X1298981Y1031244D03*
X1291579D03*
Y1044000D03*
X1302681Y1031244D03*
X1300831Y1034433D03*
X1297130D03*
X1295280Y1037622D03*
X1302681D03*
X1300831Y1040811D03*
X1297130D03*
X1295280Y1044000D03*
X1291579Y1037622D03*
X1302682Y1044000D03*
X1295280Y1031244D03*
X1304532Y1047189D03*
X1291579Y1050378D03*
X1293430Y1053567D03*
Y1059945D03*
X1304532Y1053567D03*
X1298981Y1050378D03*
X1302681Y1056756D03*
X1298981D03*
X1300831Y1059945D03*
X1304532D03*
X1302681Y1050378D03*
X1297130Y1059945D03*
X1300831Y1047189D03*
X1295280Y1050378D03*
X1297130Y1053567D03*
X1291579Y1056756D03*
X1293430Y1047189D03*
X1295280Y1056756D03*
X1297130Y1047189D03*
X1300831Y1053567D03*
X1298981Y1063134D03*
X1291579D03*
Y1069512D03*
X1293430Y1072701D03*
X1304532D03*
Y1066323D03*
X1298981Y1069512D03*
X1297130Y1072701D03*
X1302681Y1063134D03*
X1295280D03*
X1300831Y1066323D03*
X1302681Y1069512D03*
X1295280D03*
X1300831Y1072701D03*
X1297130Y1066323D03*
X1293430D03*
X1298981Y1075890D03*
X1293430Y1079079D03*
X1304532D03*
Y1085457D03*
X1298981Y1088646D03*
X1291579Y1082268D03*
X1298981D03*
X1291579Y1088646D03*
X1302681Y1075890D03*
X1295280D03*
X1300831Y1079079D03*
X1297130D03*
X1302681Y1082268D03*
X1295280D03*
X1300831Y1085457D03*
X1295280Y1088646D03*
X1302681D03*
X1297130Y1085457D03*
X1293430D03*
X1291579Y1075890D03*
X1293430Y1091835D03*
X1304532D03*
X1298981Y1095024D03*
X1293430Y1098213D03*
X1298981Y1101402D03*
X1304532Y1098213D03*
Y1104591D03*
X1291579Y1101402D03*
X1295280D03*
X1300831Y1104591D03*
X1297130Y1091835D03*
X1302681Y1095024D03*
X1295280D03*
X1300831Y1098213D03*
X1297130D03*
X1302681Y1101402D03*
X1297130Y1104591D03*
X1300831Y1091835D03*
X1293430Y1104591D03*
X1291579Y1095024D03*
X1298981Y1107780D03*
X1291579D03*
X1293430Y1110969D03*
X1304532D03*
X1293430Y1117347D03*
X1298981Y1114158D03*
X1304532Y1117347D03*
X1297130Y1110969D03*
X1302681Y1114158D03*
X1295280D03*
X1300831Y1117347D03*
X1297130D03*
X1295280Y1107780D03*
X1302681D03*
X1300831Y1110969D03*
X1291579Y1114158D03*
Y1120536D03*
X1298981D03*
X1304532Y1123725D03*
X1291579Y1126914D03*
X1298981D03*
X1304532Y1130102D03*
X1298981Y1133292D03*
X1293430Y1130102D03*
X1302681Y1120536D03*
X1295280D03*
X1300831Y1123725D03*
X1297130Y1130102D03*
X1302681Y1133292D03*
X1295280D03*
Y1126914D03*
X1302681D03*
X1297130Y1123725D03*
X1300831Y1130102D03*
X1291579Y1133292D03*
X1293430Y1123725D03*
X1304532Y1136480D03*
X1298981Y1139669D03*
X1291579D03*
X1293430Y1136480D03*
X1304532Y1142858D03*
X1291579Y1146047D03*
X1293430Y1149236D03*
X1298981Y1146047D03*
X1304532Y1149236D03*
X1300831Y1136480D03*
X1297130D03*
X1302681Y1139669D03*
X1295280D03*
X1300831Y1142858D03*
X1297130Y1149236D03*
X1295280Y1146047D03*
X1302681D03*
X1297130Y1142858D03*
X1300831Y1149236D03*
X1293430Y1142858D03*
X1291579Y1158803D03*
X1293430Y1155614D03*
X1304532D03*
X1298981Y1152425D03*
X1297130Y1155614D03*
X1302681Y1158803D03*
X1298981D03*
X1304532Y1161992D03*
X1297130D03*
X1302681Y1152425D03*
X1295280D03*
X1300831Y1155614D03*
X1295280Y1158803D03*
X1291579Y1152425D03*
X1300831Y1161992D03*
X1302682Y1165181D03*
X1298119Y1625380D03*
X1290319D03*
X1302379D03*
X1292079Y1635380D03*
X1296359D03*
X1304139D03*
X1296359Y1647292D03*
X1292079D03*
X1304139D03*
X1298119Y1657292D03*
X1290319D03*
X1302379D03*
X1318154Y876434D03*
X1305201Y879623D03*
X1312603D03*
X1316304D03*
X1314453Y876434D03*
X1308902Y873245D03*
Y879623D03*
X1307052Y876434D03*
X1310752Y895568D03*
X1307052Y882812D03*
X1305201Y886001D03*
Y892379D03*
X1310752Y882812D03*
X1312603Y886001D03*
X1316304D03*
X1318154Y882812D03*
X1310752Y889190D03*
X1318154D03*
X1316304Y892379D03*
X1308902Y886001D03*
X1314453Y889190D03*
X1307052D03*
X1312603Y892379D03*
X1307052Y895568D03*
X1314453D03*
X1308902Y892379D03*
X1318154Y895568D03*
X1305201Y898757D03*
Y905134D03*
Y911512D03*
X1310752Y901946D03*
X1318154D03*
X1316304Y898757D03*
Y911512D03*
X1318154Y908324D03*
X1310752Y908323D03*
X1307052Y908324D03*
X1312603Y911512D03*
X1308902Y898757D03*
X1314453Y901946D03*
X1307052D03*
X1312603Y905134D03*
X1308902D03*
X1314453Y908324D03*
X1308902Y911512D03*
X1312603Y898757D03*
X1316304Y905134D03*
X1305201Y917890D03*
Y924268D03*
X1310752Y914701D03*
X1316304Y917890D03*
X1318154Y921079D03*
X1310752D03*
X1308902Y917890D03*
X1314453Y921079D03*
X1307052D03*
X1312603Y924268D03*
X1308902D03*
X1307052Y914701D03*
X1314453D03*
X1312603Y917890D03*
X1316304Y924268D03*
X1318154Y914701D03*
X1305201Y930646D03*
Y937024D03*
X1310752Y927457D03*
Y933835D03*
X1318154Y927457D03*
X1316304Y930646D03*
Y937024D03*
X1310752Y940213D03*
X1318154D03*
X1314453Y927457D03*
X1307052D03*
X1312603Y930646D03*
X1308902Y937024D03*
X1314453Y940213D03*
X1307052D03*
Y933835D03*
X1314453D03*
X1308902Y930646D03*
X1312603Y937024D03*
X1318154Y933835D03*
X1305201Y943402D03*
Y949780D03*
Y956158D03*
X1310752Y946591D03*
X1316304Y949780D03*
X1318154Y946591D03*
X1310752Y952969D03*
X1316304Y956158D03*
X1312603Y943402D03*
X1308902D03*
X1314453Y946591D03*
X1307052D03*
X1312603Y949780D03*
X1308902Y956158D03*
X1307052Y952969D03*
X1314453D03*
X1308902Y949780D03*
X1312603Y956158D03*
X1318154Y952969D03*
X1316304Y943402D03*
X1318154Y959347D03*
Y965725D03*
X1316304Y968914D03*
X1305201Y962536D03*
Y968914D03*
X1310752Y959347D03*
Y965725D03*
X1308902Y962536D03*
X1314453Y965725D03*
X1307052D03*
X1312603Y968914D03*
X1314453Y959347D03*
X1307052D03*
X1312603Y962536D03*
X1308902Y968914D03*
X1316304Y962536D03*
X1305201Y975292D03*
Y981670D03*
X1307052Y984859D03*
X1310752Y972103D03*
Y978481D03*
X1316304Y975292D03*
X1318154Y978481D03*
X1308902Y981670D03*
X1310752Y984859D03*
X1318154D03*
X1314453D03*
X1308902Y975292D03*
X1314453Y978481D03*
X1307052D03*
X1312603Y981670D03*
X1307052Y972103D03*
X1314453D03*
X1312603Y975292D03*
X1316304Y981670D03*
X1318154Y972103D03*
X1305201Y988048D03*
Y994426D03*
Y1000804D03*
X1310752Y991237D03*
Y997615D03*
X1316304Y988048D03*
X1318154Y997615D03*
X1316304Y994426D03*
X1312603Y988048D03*
X1308902Y994426D03*
X1307052Y997615D03*
X1314453D03*
X1312603Y1000804D03*
X1308902D03*
X1307052Y991237D03*
X1312603Y994426D03*
X1316304Y1000804D03*
X1318154Y991237D03*
X1314453D03*
X1308902Y988048D03*
X1305201Y1007182D03*
X1310752Y1003993D03*
Y1010371D03*
X1318154D03*
X1316304Y1007182D03*
X1318154Y1003993D03*
X1307052Y1010371D03*
X1308902Y1007182D03*
X1307052Y1003993D03*
X1314453D03*
X1312603Y1007182D03*
X1314453Y1010371D03*
X1311933Y1028055D03*
X1319335D03*
X1315634D03*
X1308233D03*
X1306382Y1044000D03*
Y1037622D03*
Y1031244D03*
X1319335Y1034433D03*
X1311933Y1040811D03*
X1319335D03*
X1317485Y1031244D03*
Y1044000D03*
X1311933Y1034433D03*
X1313784Y1031244D03*
X1315634Y1034433D03*
X1308233D03*
X1310083Y1037622D03*
X1313784D03*
X1315634Y1040811D03*
X1308233D03*
X1310083Y1044000D03*
X1317485Y1037622D03*
X1313784Y1044000D03*
X1310083Y1031244D03*
X1306382Y1050378D03*
Y1056756D03*
X1311933Y1047189D03*
X1313784Y1056756D03*
X1311933Y1059945D03*
X1315634D03*
X1319335D03*
X1317485Y1050378D03*
X1319335Y1053567D03*
X1311933D03*
X1313784Y1050378D03*
X1308233Y1059945D03*
X1315634Y1047189D03*
X1310083Y1050378D03*
X1308233Y1053567D03*
X1317485Y1056756D03*
X1319335Y1047189D03*
X1310083Y1056756D03*
X1308233Y1047189D03*
X1315634Y1053567D03*
X1306382Y1063134D03*
Y1069512D03*
X1317485Y1063134D03*
X1319335Y1072701D03*
X1317485Y1069512D03*
X1311933Y1066323D03*
Y1072701D03*
X1308233D03*
X1313784Y1063134D03*
X1310083D03*
X1315634Y1066323D03*
X1313784Y1069512D03*
X1310083D03*
X1315634Y1072701D03*
X1308233Y1066323D03*
X1319335D03*
X1306382Y1075890D03*
Y1088646D03*
Y1082268D03*
X1319335Y1079079D03*
X1311933D03*
Y1085457D03*
X1317485Y1088646D03*
Y1082268D03*
X1313784Y1075890D03*
X1310083D03*
X1315634Y1079079D03*
X1308233D03*
X1313784Y1082268D03*
X1310083D03*
X1315634Y1085457D03*
X1310083Y1088646D03*
X1313784D03*
X1308233Y1085457D03*
X1319335D03*
X1317485Y1075890D03*
X1306382Y1095024D03*
Y1101402D03*
X1319335Y1091835D03*
X1311933D03*
Y1098213D03*
X1319335D03*
X1317485Y1101402D03*
X1311933Y1104591D03*
X1310083Y1101402D03*
X1315634Y1104591D03*
X1308233Y1091835D03*
X1313784Y1095024D03*
X1310083D03*
X1315634Y1098213D03*
X1308233D03*
X1313784Y1101402D03*
X1308233Y1104591D03*
X1315634Y1091835D03*
X1319335Y1104591D03*
X1317485Y1095024D03*
X1306382Y1107780D03*
Y1114158D03*
X1317485Y1107780D03*
X1319335Y1110969D03*
X1311933D03*
Y1117347D03*
X1319335D03*
X1308233Y1110969D03*
X1313784Y1114158D03*
X1310083D03*
X1315634Y1117347D03*
X1308233D03*
X1310083Y1107780D03*
X1313784D03*
X1315634Y1110969D03*
X1317485Y1114158D03*
X1306382Y1120536D03*
Y1126914D03*
Y1133292D03*
X1317485Y1120536D03*
X1311933Y1123725D03*
X1317485Y1126914D03*
X1319335Y1130102D03*
X1311933Y1130103D03*
X1313784Y1120536D03*
X1310083D03*
X1315634Y1123725D03*
X1308233Y1130102D03*
X1313784Y1133292D03*
X1310083D03*
Y1126914D03*
X1313784D03*
X1308233Y1123725D03*
X1315634Y1130102D03*
X1317485Y1133292D03*
X1319335Y1123725D03*
X1306382Y1139669D03*
Y1146047D03*
X1319335Y1136480D03*
X1317485Y1139669D03*
X1311933Y1136480D03*
Y1142858D03*
X1317485Y1146047D03*
X1319335Y1149236D03*
X1311933D03*
X1315634Y1136480D03*
X1308233D03*
X1313784Y1139669D03*
X1310083D03*
X1315634Y1142858D03*
X1308233Y1149236D03*
X1310083Y1146047D03*
X1313784D03*
X1308233Y1142858D03*
X1315634Y1149236D03*
X1319335Y1142858D03*
X1317485Y1158803D03*
X1313784D03*
X1319335Y1161992D03*
X1311933D03*
X1306382Y1165181D03*
X1313784D03*
X1306382Y1152425D03*
Y1158803D03*
X1319335Y1155614D03*
X1315634D03*
X1311933D03*
X1310083Y1158803D03*
X1313784Y1152425D03*
X1310083D03*
X1308233Y1155614D03*
X1317485Y1152425D03*
X1308233Y1161992D03*
X1310083Y1165181D03*
X1317485D03*
X1315634Y1161992D03*
X1318882Y1540514D03*
X1316766Y1540460D03*
X1314515Y1540509D03*
X1314680Y1546218D03*
X1313021Y1551121D03*
X1313514Y1556810D03*
Y1561725D03*
X1313422Y1554612D03*
X1318986Y1575425D03*
X1313468Y1568698D03*
Y1570898D03*
X1318986Y1577625D03*
X1314915Y1573317D03*
X1310179Y1625380D03*
X1314439D03*
X1308419Y1635380D03*
X1316199D03*
X1308419Y1647292D03*
X1316199D03*
X1310179Y1657292D03*
X1314439D03*
X1323705Y879623D03*
X1327406D03*
X1321855Y876434D03*
X1320004Y879623D03*
X1331107Y873245D03*
X1325556Y876434D03*
X1331107Y879623D03*
X1332957Y876434D03*
X1329256D03*
X1334807Y879623D03*
X1321855Y882812D03*
X1323705Y886001D03*
X1329256Y882812D03*
X1332957D03*
X1331107Y886001D03*
X1327406D03*
X1323705Y892379D03*
X1329256Y889190D03*
X1331107Y892379D03*
X1329256Y895568D03*
X1320004Y886001D03*
X1325556Y889190D03*
X1321855D03*
X1327406Y892379D03*
X1321855Y895568D03*
X1325556D03*
X1320004Y892379D03*
X1334807Y886001D03*
X1332957Y889190D03*
Y895568D03*
X1334807Y892379D03*
X1323705Y898757D03*
X1331107D03*
X1329256Y901946D03*
X1331107Y911512D03*
X1323705D03*
Y905134D03*
X1331107D03*
X1329256Y908323D03*
X1321855Y908324D03*
X1327406Y911512D03*
X1320004Y898757D03*
X1325556Y901946D03*
X1321855D03*
X1327406Y905134D03*
X1320004D03*
X1325556Y908324D03*
X1320004Y911512D03*
X1327406Y898757D03*
X1332957Y908324D03*
X1334807Y898757D03*
X1332957Y901946D03*
X1334807Y905134D03*
Y911512D03*
X1329256Y914701D03*
X1323705Y917890D03*
X1331107D03*
X1323705Y924268D03*
X1329256Y921079D03*
X1331107Y924268D03*
X1320004Y917890D03*
X1325556Y921079D03*
X1321855D03*
X1327406Y924268D03*
X1320004D03*
X1321855Y914701D03*
X1325556D03*
X1327406Y917890D03*
X1334807D03*
X1332957Y921079D03*
X1334807Y924268D03*
X1332957Y914701D03*
X1331107Y930646D03*
X1329256Y933835D03*
X1323705Y930646D03*
X1329256Y927457D03*
X1331107Y937024D03*
X1329256Y940213D03*
X1323705Y937024D03*
X1325556Y927457D03*
X1321855D03*
X1327406Y930646D03*
X1320004Y937024D03*
X1325556Y940213D03*
X1321855D03*
Y933835D03*
X1325556D03*
X1320004Y930646D03*
X1327406Y937024D03*
X1332957Y927457D03*
X1334807Y937024D03*
X1332957Y940213D03*
Y933835D03*
X1334807Y930646D03*
X1331107Y943402D03*
X1329256Y946591D03*
X1331107Y949780D03*
X1323705Y943402D03*
Y949780D03*
X1329256Y952969D03*
X1331107Y956158D03*
X1323705D03*
X1327406Y943402D03*
X1320004D03*
X1325556Y946591D03*
X1321855D03*
X1327406Y949780D03*
X1320004Y956158D03*
X1321855Y952969D03*
X1325556D03*
X1320004Y949780D03*
X1327406Y956158D03*
X1334807Y943402D03*
X1332957Y946591D03*
X1334807Y956158D03*
X1332957Y952969D03*
X1334807Y949780D03*
X1329256Y959347D03*
X1331107Y962536D03*
X1329256Y965725D03*
X1323705Y962536D03*
X1331107Y968914D03*
X1323705D03*
X1320004Y962536D03*
X1325556Y965725D03*
X1321855D03*
X1327406Y968914D03*
X1325556Y959347D03*
X1321855D03*
X1327406Y962536D03*
X1320004Y968914D03*
X1334807Y962536D03*
X1332957Y965725D03*
Y959347D03*
X1334807Y968914D03*
X1320004Y981670D03*
X1321855Y984859D03*
X1323705Y975292D03*
Y981670D03*
X1329256Y972103D03*
X1331107Y975292D03*
X1329256Y978481D03*
X1331107Y981670D03*
X1334807D03*
X1329256Y984859D03*
X1332957D03*
X1325556D03*
X1320004Y975292D03*
X1325556Y978481D03*
X1321855D03*
X1327406Y981670D03*
X1321855Y972103D03*
X1325556D03*
X1327406Y975292D03*
X1334807D03*
X1332957Y978481D03*
Y972103D03*
X1323705Y1000804D03*
Y988048D03*
Y994426D03*
X1329256Y997615D03*
X1331107Y988048D03*
X1329256Y991237D03*
X1331107Y994426D03*
Y1000804D03*
X1327406Y988048D03*
X1320004Y994426D03*
X1321855Y997615D03*
X1325556D03*
X1327406Y1000804D03*
X1320004D03*
X1321855Y991237D03*
X1327406Y994426D03*
X1334807D03*
X1332957Y997615D03*
X1334807Y1000804D03*
X1332957Y991237D03*
X1334808Y988048D03*
X1325556Y991237D03*
X1320004Y988048D03*
X1323705Y1007182D03*
X1329256Y1003993D03*
X1331107Y1007182D03*
X1329256Y1010371D03*
X1321855D03*
X1320004Y1007182D03*
X1321855Y1003993D03*
X1325556D03*
X1327406Y1007182D03*
X1332957Y1010371D03*
X1334807Y1007182D03*
X1332957Y1003993D03*
X1325556Y1010371D03*
X1330437Y1028055D03*
X1326737D03*
X1334138D03*
X1323036D03*
X1324886Y1031244D03*
X1332288D03*
X1324886Y1044000D03*
Y1037622D03*
X1332288Y1044000D03*
X1330437Y1034433D03*
X1332288Y1037622D03*
X1330437Y1040811D03*
X1328587Y1031244D03*
X1326737Y1034433D03*
X1323036D03*
X1321185Y1037622D03*
X1328587D03*
X1326737Y1040811D03*
X1323036D03*
X1321185Y1044000D03*
X1334138Y1034433D03*
Y1040811D03*
X1328587Y1044000D03*
X1321185Y1031244D03*
X1330437Y1047189D03*
X1324886Y1050378D03*
Y1056756D03*
X1332288Y1050378D03*
X1330437Y1053567D03*
X1328587Y1056756D03*
X1332288D03*
X1326737Y1059945D03*
X1330437D03*
X1328587Y1050378D03*
X1323036Y1059945D03*
X1326737Y1047189D03*
X1321185Y1050378D03*
X1323036Y1053567D03*
X1334138Y1059945D03*
Y1053567D03*
Y1047189D03*
X1321185Y1056756D03*
X1323036Y1047189D03*
X1326737Y1053567D03*
X1332288Y1063134D03*
X1324886D03*
Y1069512D03*
X1330437Y1066323D03*
X1332288Y1069512D03*
X1330437Y1072701D03*
X1323036D03*
X1328587Y1063134D03*
X1321185D03*
X1326737Y1066323D03*
X1328587Y1069512D03*
X1321185D03*
X1326737Y1072701D03*
X1323036Y1066323D03*
X1334138Y1072701D03*
Y1066323D03*
X1324886Y1075890D03*
X1332288D03*
X1330437Y1079079D03*
X1324886Y1088646D03*
X1330437Y1085457D03*
X1332288Y1088646D03*
X1324886Y1082268D03*
X1332288D03*
X1328587Y1075890D03*
X1321185D03*
X1326737Y1079079D03*
X1323036D03*
X1328587Y1082268D03*
X1321185D03*
X1326737Y1085457D03*
X1321185Y1088646D03*
X1328587D03*
X1323036Y1085457D03*
X1334138Y1079079D03*
Y1085457D03*
X1330437Y1091835D03*
X1324886Y1095024D03*
X1332288D03*
X1324886Y1101402D03*
X1330437Y1098213D03*
X1332288Y1101402D03*
X1330437Y1104591D03*
X1321185Y1101402D03*
X1326737Y1104591D03*
X1323036Y1091835D03*
X1328587Y1095024D03*
X1321185D03*
X1326737Y1098213D03*
X1323036D03*
X1328587Y1101402D03*
X1323036Y1104591D03*
X1326737Y1091835D03*
X1334138D03*
Y1098213D03*
Y1104591D03*
X1324886Y1107780D03*
X1332288D03*
X1330437Y1110969D03*
X1324886Y1114158D03*
X1332288D03*
X1330437Y1117347D03*
X1323036Y1110969D03*
X1328587Y1114158D03*
X1321185D03*
X1326737Y1117347D03*
X1323036D03*
X1321185Y1107780D03*
X1328587D03*
X1326737Y1110969D03*
X1334138D03*
Y1117347D03*
X1324886Y1120536D03*
X1332288D03*
X1330437Y1123725D03*
X1324886Y1126914D03*
X1332288D03*
X1324886Y1133292D03*
X1332288D03*
X1330439Y1130102D03*
X1328587Y1120536D03*
X1321185D03*
X1326737Y1123725D03*
X1323036Y1130102D03*
X1328587Y1133292D03*
X1321185D03*
Y1126914D03*
X1328587D03*
X1323036Y1123725D03*
X1326737Y1130102D03*
X1334138D03*
Y1123725D03*
X1324886Y1139669D03*
X1330437Y1136480D03*
X1332288Y1139669D03*
X1330437Y1142858D03*
X1332288Y1146047D03*
X1330437Y1149236D03*
X1324886Y1146047D03*
X1326737Y1136480D03*
X1323036D03*
X1328587Y1139669D03*
X1321185D03*
X1326737Y1142858D03*
X1323036Y1149236D03*
X1321185Y1146047D03*
X1328587D03*
X1323036Y1142858D03*
X1326737Y1149236D03*
X1334138Y1136480D03*
Y1149236D03*
Y1142858D03*
X1332288Y1165181D03*
X1323036Y1155614D03*
Y1161992D03*
X1332288Y1152425D03*
X1330437Y1155614D03*
X1324886Y1152425D03*
X1332288Y1158803D03*
X1328587D03*
X1324886D03*
X1330437Y1161992D03*
X1324886Y1165181D03*
X1328587Y1152425D03*
X1321185D03*
X1326737Y1155614D03*
X1334138D03*
X1321185Y1158803D03*
X1334138Y1161992D03*
X1322795Y1547243D03*
X1324189Y1540295D03*
X1327519Y1547243D03*
X1328914Y1540295D03*
X1332244Y1547243D03*
X1333638Y1540295D03*
X1321623Y1552195D03*
X1324090Y1549970D03*
X1328814D03*
X1333539D03*
X1325665Y1552698D03*
X1330389D03*
X1331914Y1554453D03*
X1327189D03*
X1322465D03*
X1332465Y1561853D03*
X1327740D03*
X1323016D03*
X1324090Y1563608D03*
X1328814D03*
X1333539D03*
X1325665Y1566336D03*
X1330389D03*
X1332465Y1559353D03*
X1331914Y1556953D03*
X1322465D03*
X1327189D03*
X1323016Y1559353D03*
X1327740D03*
X1333638Y1575641D03*
X1331964Y1569063D03*
X1328914Y1575641D03*
X1327239Y1569063D03*
X1324189Y1575641D03*
X1322514Y1569063D03*
X1326499Y1625380D03*
X1322239D03*
X1334299D03*
X1320479Y1635380D03*
X1328259D03*
X1332539D03*
X1328259Y1647292D03*
X1320479D03*
X1332539D03*
X1322239Y1657292D03*
X1326499D03*
X1334299D03*
X1336658Y876434D03*
X1345910Y879623D03*
X1349611D03*
X1344059Y876434D03*
X1347760D03*
X1340359D03*
X1338508Y886001D03*
X1336658Y882812D03*
Y889190D03*
Y895568D03*
X1342209Y886001D03*
X1349611D03*
X1344059Y882812D03*
Y889190D03*
X1342209Y892379D03*
X1349611D03*
X1345910Y886001D03*
X1347760Y889190D03*
Y895568D03*
X1345910Y892379D03*
X1340359Y889190D03*
X1338508Y892379D03*
X1340359Y895568D03*
X1347760Y882812D03*
X1344059Y895568D03*
X1336658Y901946D03*
Y908324D03*
X1342209Y898757D03*
X1349611D03*
X1344059Y901946D03*
X1349611Y905134D03*
X1342209Y911512D03*
X1349611D03*
X1344059Y908323D03*
X1347760Y908324D03*
X1345910Y898757D03*
X1347760Y901946D03*
X1345910Y905134D03*
Y911512D03*
X1338508D03*
X1340359Y901946D03*
X1338508Y905134D03*
X1340359Y908324D03*
X1338508Y898757D03*
X1342209Y905134D03*
X1336658Y914701D03*
Y921079D03*
X1342209Y917890D03*
X1349611D03*
X1344059Y921079D03*
X1349611Y924268D03*
X1345910Y917890D03*
X1347760Y921079D03*
X1345910Y924268D03*
X1347760Y914701D03*
X1340359Y921079D03*
X1338508Y924268D03*
X1340359Y914701D03*
X1338508Y917890D03*
X1344059Y914701D03*
X1342209Y924268D03*
X1336658Y933835D03*
Y927457D03*
Y940213D03*
X1344059Y927457D03*
X1342209Y930646D03*
X1349611D03*
X1344059Y940213D03*
X1342209Y937024D03*
X1349611D03*
X1347760Y927457D03*
X1345910Y937024D03*
X1347760Y940213D03*
Y933835D03*
X1345910Y930646D03*
X1340359Y927457D03*
X1338508Y930646D03*
X1340359Y940213D03*
Y933835D03*
X1338508Y937024D03*
X1344059Y933835D03*
X1349611Y943402D03*
X1344059Y946591D03*
X1349611Y949780D03*
X1342209D03*
X1349611Y956158D03*
X1342209D03*
X1336658Y946591D03*
Y952969D03*
X1345910Y943402D03*
X1347760Y946591D03*
X1345910Y956158D03*
X1347760Y952969D03*
X1345910Y949780D03*
X1338508Y943402D03*
X1340359Y946591D03*
X1338508Y949780D03*
X1340359Y952969D03*
X1338508Y956158D03*
X1342209Y943402D03*
X1344059Y952969D03*
X1336658Y965725D03*
Y959347D03*
X1344059D03*
X1349611Y962536D03*
X1344059Y965725D03*
X1349611Y968914D03*
X1342209D03*
X1345910Y962536D03*
X1347760Y965725D03*
Y959347D03*
X1345910Y968914D03*
X1340359Y965725D03*
X1338508Y968914D03*
X1340359Y959347D03*
X1338508Y962536D03*
X1342209D03*
X1336658Y972103D03*
Y978481D03*
Y984859D03*
X1349611Y975292D03*
X1342209D03*
X1344059Y978481D03*
X1349611Y981670D03*
X1345910D03*
X1344059Y984859D03*
X1347760D03*
X1345910Y975292D03*
X1347760Y978481D03*
Y972103D03*
X1340359Y984859D03*
Y978481D03*
X1338508Y981670D03*
X1340359Y972103D03*
X1338508Y975292D03*
X1342209Y981670D03*
X1344059Y972103D03*
X1336658Y997615D03*
Y991237D03*
X1349611Y988048D03*
Y994426D03*
X1342209D03*
X1344059Y997615D03*
X1342209Y988048D03*
X1349611Y1000804D03*
X1345910Y994426D03*
X1347760Y997615D03*
X1345910Y1000804D03*
X1347760Y991237D03*
X1338508Y988048D03*
X1340359Y997615D03*
X1338508Y1000804D03*
Y994426D03*
X1344059Y991237D03*
X1342209Y1000804D03*
X1340359Y991237D03*
X1345910Y988048D03*
X1336658Y1010371D03*
X1344059D03*
X1336658Y1003993D03*
X1344059D03*
X1342209Y1007182D03*
X1349611D03*
X1347760Y1010371D03*
X1345910Y1007182D03*
X1347760Y1003993D03*
X1340359D03*
X1338508Y1007182D03*
X1340359Y1010371D03*
X1337839Y1028055D03*
X1345241D03*
X1341540D03*
X1348941D03*
X1337839Y1040811D03*
Y1034433D03*
X1343390Y1031244D03*
Y1044000D03*
X1345241Y1040811D03*
Y1034433D03*
X1348941D03*
X1347091Y1037622D03*
X1348941Y1040811D03*
X1347091Y1044000D03*
X1339689Y1031244D03*
X1341540Y1034433D03*
X1335989Y1037622D03*
X1339689D03*
X1341540Y1040811D03*
X1335989Y1044000D03*
X1343390Y1037622D03*
X1339689Y1044000D03*
X1335989Y1031244D03*
X1347091D03*
X1337839Y1047189D03*
Y1053567D03*
Y1059945D03*
X1339689Y1056756D03*
X1343390Y1050378D03*
X1345241Y1053567D03*
X1341540Y1059945D03*
X1345241D03*
X1348941D03*
X1347091Y1050378D03*
X1348941Y1053567D03*
X1339689Y1050378D03*
X1341540Y1047189D03*
X1335989Y1050378D03*
X1345241Y1047189D03*
X1343390Y1056756D03*
X1335989D03*
X1341540Y1053567D03*
X1347091Y1056756D03*
X1348941Y1047189D03*
X1337839Y1072701D03*
Y1066323D03*
X1343390Y1063134D03*
Y1069512D03*
X1345241Y1072701D03*
X1348941D03*
X1347091Y1063134D03*
Y1069512D03*
X1348941Y1066323D03*
X1339689Y1063134D03*
X1335989D03*
X1341540Y1066323D03*
X1339689Y1069512D03*
X1335989D03*
X1341540Y1072701D03*
X1345241Y1066323D03*
X1337839Y1079079D03*
Y1085457D03*
X1345241Y1079079D03*
X1343390Y1088646D03*
Y1082268D03*
X1347091Y1075890D03*
X1348941Y1079079D03*
X1347091Y1082268D03*
Y1088646D03*
X1348941Y1085457D03*
X1339689Y1075890D03*
X1335989D03*
X1341540Y1079079D03*
X1339689Y1082268D03*
X1335989D03*
X1341540Y1085457D03*
X1335989Y1088646D03*
X1339689D03*
X1343390Y1075890D03*
X1345241Y1085457D03*
X1337839Y1091835D03*
Y1098213D03*
Y1104591D03*
X1345241Y1091835D03*
X1343390Y1101402D03*
X1345241Y1098213D03*
X1347091Y1101402D03*
X1348941Y1091835D03*
X1347091Y1095024D03*
X1348941Y1098213D03*
Y1104591D03*
X1335989Y1101402D03*
X1341540Y1104591D03*
X1339689Y1095024D03*
X1335989D03*
X1341540Y1098213D03*
X1339689Y1101402D03*
X1341540Y1091835D03*
X1343390Y1095024D03*
X1345241Y1104591D03*
X1337839Y1110969D03*
Y1117347D03*
X1343390Y1107780D03*
X1345241Y1110969D03*
Y1117347D03*
X1348941Y1110969D03*
X1347091Y1114158D03*
X1348941Y1117347D03*
X1347091Y1107780D03*
X1339689Y1114158D03*
X1335989D03*
X1341540Y1117347D03*
X1335989Y1107780D03*
X1339689D03*
X1341540Y1110969D03*
X1343390Y1114158D03*
X1337839Y1123725D03*
Y1130102D03*
X1343390Y1120536D03*
Y1126914D03*
X1345241Y1130102D03*
X1347091Y1120536D03*
X1348941Y1130102D03*
X1347091Y1133292D03*
Y1126914D03*
X1348941Y1123725D03*
X1339689Y1120536D03*
X1335989D03*
X1341540Y1123725D03*
X1339689Y1133292D03*
X1335989D03*
Y1126914D03*
X1339689D03*
X1341540Y1130102D03*
X1343390Y1133292D03*
X1345241Y1123725D03*
X1337839Y1136480D03*
Y1142858D03*
Y1149236D03*
X1343390Y1139669D03*
X1345241Y1136480D03*
Y1149236D03*
X1343390Y1146047D03*
X1348941Y1136480D03*
X1347091Y1139669D03*
X1348941Y1149236D03*
X1347091Y1146047D03*
X1348941Y1142858D03*
X1341540Y1136480D03*
X1339689Y1139669D03*
X1335989D03*
X1341540Y1142858D03*
X1335989Y1146047D03*
X1339689D03*
X1341540Y1149236D03*
X1345241Y1142858D03*
X1337839Y1155614D03*
X1335989Y1158803D03*
X1337839Y1161992D03*
X1341540Y1155614D03*
X1339689Y1158803D03*
X1348941Y1155614D03*
X1345241D03*
X1339689Y1165181D03*
X1347091Y1152425D03*
X1339689D03*
X1335989D03*
X1347091Y1158803D03*
X1348941Y1161992D03*
X1345241D03*
X1343390Y1152425D03*
X1335989Y1165181D03*
X1343390Y1158803D03*
X1341540Y1161992D03*
X1336968Y1547243D03*
X1338362Y1540295D03*
X1341693Y1547243D03*
X1343087Y1540295D03*
X1346417Y1547243D03*
X1347811Y1540295D03*
X1338263Y1549970D03*
X1342987D03*
X1347712D03*
X1335113Y1552698D03*
X1339838D03*
X1344562D03*
X1349287D03*
X1346087Y1554453D03*
X1341362D03*
X1336638D03*
X1346638Y1561853D03*
X1341913D03*
X1337189D03*
X1338263Y1563608D03*
X1342987D03*
X1347712D03*
X1335113Y1566336D03*
X1339838D03*
X1344562D03*
X1349287D03*
X1346087Y1556953D03*
X1346638Y1559353D03*
X1336638Y1556953D03*
X1337189Y1559353D03*
X1341913D03*
X1341362Y1556953D03*
X1346137Y1569063D03*
X1341413D03*
X1347811Y1575641D03*
X1343087D03*
X1338362D03*
X1336688Y1569063D03*
X1338559Y1625380D03*
X1346359D03*
X1340319Y1635380D03*
X1344599D03*
X1340319Y1647292D03*
X1344599D03*
X1338559Y1657292D03*
X1346359D03*
X1351461Y876434D03*
X1353311Y879623D03*
X1364414D03*
X1360713Y873245D03*
X1362563Y876434D03*
X1358863D03*
X1355162D03*
X1364414Y892379D03*
X1360713D03*
X1353311Y886001D03*
X1362563Y882812D03*
X1358863D03*
X1364414Y886001D03*
X1360713D03*
X1355162Y882812D03*
X1357012Y892379D03*
X1355162Y895568D03*
X1362563Y889190D03*
X1358863D03*
X1351461D03*
X1353311Y892379D03*
X1351461Y895568D03*
Y882812D03*
X1357012Y886001D03*
X1362563Y895568D03*
X1358863D03*
X1355162Y889190D03*
X1364414Y905134D03*
Y898757D03*
Y911512D03*
X1360713Y905134D03*
Y898757D03*
Y911512D03*
X1357012Y898757D03*
X1362563Y901946D03*
X1358863D03*
X1357012Y905134D03*
Y911512D03*
X1355162Y908324D03*
X1353311Y911512D03*
X1351461Y901946D03*
X1353311Y905134D03*
X1351461Y908324D03*
X1353311Y898757D03*
X1362563Y908324D03*
X1358863D03*
X1355162Y901946D03*
X1364414Y917890D03*
Y924268D03*
X1360713Y917890D03*
Y924268D03*
X1358863Y914701D03*
X1362563D03*
X1357012Y917890D03*
X1355162Y921079D03*
X1357012Y924268D03*
X1351461Y921079D03*
X1353311Y924268D03*
X1351461Y914701D03*
X1353311Y917890D03*
X1358863Y921079D03*
X1362563D03*
X1355162Y914701D03*
X1364414Y930646D03*
X1360713D03*
X1362563Y933835D03*
X1358863D03*
X1355162D03*
X1362563Y927457D03*
X1358863D03*
X1357012Y930646D03*
X1355162Y940213D03*
X1351461Y927457D03*
X1353311Y930646D03*
X1351461Y940213D03*
Y933835D03*
X1353311Y937024D03*
X1362563Y940213D03*
X1358863D03*
X1357012Y937024D03*
X1355162Y927457D03*
X1364414Y937024D03*
X1360713D03*
Y956158D03*
Y943402D03*
Y949780D03*
X1364414Y956158D03*
Y943402D03*
Y949780D03*
X1357012Y943402D03*
X1358863Y946591D03*
X1362563D03*
X1357012Y949780D03*
Y956158D03*
X1355162Y952969D03*
X1353311Y943402D03*
X1351461Y946591D03*
X1353311Y949780D03*
X1351461Y952969D03*
X1353311Y956158D03*
X1362563Y952969D03*
X1358863D03*
X1355162Y946591D03*
X1360713Y962536D03*
Y968914D03*
X1364414Y962536D03*
Y968914D03*
X1358863Y959347D03*
X1362563D03*
X1357012Y962536D03*
X1355162Y965725D03*
X1357012Y968914D03*
X1351461Y965725D03*
X1353311Y968914D03*
X1351461Y959347D03*
X1353311Y962536D03*
X1362563Y965725D03*
X1358863D03*
X1355162Y959347D03*
X1360713Y975292D03*
X1364414D03*
X1358863Y972103D03*
X1362563D03*
X1357012Y975292D03*
X1360713Y981670D03*
X1355162Y978481D03*
X1362563Y984859D03*
X1355162D03*
X1351461D03*
Y978481D03*
X1353311Y981670D03*
X1351461Y972103D03*
X1353311Y975292D03*
X1357012Y981670D03*
X1364414D03*
X1358863Y984859D03*
X1362563Y978481D03*
X1358863D03*
X1355162Y972103D03*
Y991237D03*
Y997615D03*
X1362563Y991237D03*
Y997615D03*
X1360713Y994426D03*
Y988048D03*
Y1000804D03*
X1353311Y988048D03*
X1351461Y997615D03*
X1353311Y1000804D03*
Y994426D03*
X1357012Y988048D03*
X1358863Y997615D03*
X1357012Y994426D03*
X1358863Y991237D03*
X1364414Y988048D03*
Y994426D03*
X1357012Y1000804D03*
X1364414D03*
X1351461Y991237D03*
X1358863Y1010371D03*
X1360713Y1007182D03*
X1362563Y1003993D03*
X1355162D03*
X1351461D03*
X1353311Y1007182D03*
X1357012D03*
X1358863Y1003993D03*
X1364414Y1007182D03*
X1355162Y1010371D03*
X1362563D03*
X1351461D03*
X1356343Y1028055D03*
X1363745D03*
X1360044D03*
X1352642D03*
X1350792Y1031244D03*
Y1044000D03*
Y1037622D03*
X1356343Y1034433D03*
Y1040811D03*
X1363745Y1034433D03*
Y1040811D03*
X1361894Y1044000D03*
Y1037622D03*
Y1031244D03*
X1354493D03*
X1352642Y1034433D03*
X1354493Y1037622D03*
X1352642Y1040811D03*
X1358193Y1031244D03*
X1360044Y1040811D03*
Y1034433D03*
X1358193Y1037622D03*
Y1044000D03*
X1354493D03*
Y1056756D03*
X1350792D03*
Y1050378D03*
X1352642Y1059945D03*
X1356343Y1047189D03*
X1363745D03*
X1356343Y1053567D03*
X1361894Y1050378D03*
X1356343Y1059945D03*
X1363745Y1053567D03*
X1354493Y1050378D03*
X1352642Y1047189D03*
X1363745Y1059945D03*
X1360044D03*
Y1047189D03*
X1358193Y1050378D03*
X1360044Y1053567D03*
X1361894Y1056756D03*
X1358193D03*
X1352642Y1053567D03*
X1350792Y1063134D03*
Y1069512D03*
X1358193Y1063134D03*
X1356343Y1072701D03*
X1363745Y1066323D03*
X1358193Y1069512D03*
X1360044Y1066323D03*
X1354493Y1063134D03*
X1352642Y1066323D03*
X1354493Y1069512D03*
X1352642Y1072701D03*
X1361894Y1069512D03*
Y1063134D03*
X1363745Y1072701D03*
X1360044D03*
X1356343Y1066323D03*
X1350792Y1075890D03*
Y1082268D03*
Y1088646D03*
X1358193Y1075890D03*
X1363745Y1079079D03*
X1360044D03*
X1356343Y1085457D03*
X1358193Y1088646D03*
Y1082268D03*
X1354493Y1075890D03*
X1352642Y1079079D03*
X1354493Y1082268D03*
X1352642Y1085457D03*
X1354493Y1088646D03*
X1361894Y1075890D03*
Y1088646D03*
Y1082268D03*
X1363745Y1085457D03*
X1360044D03*
X1356343Y1079079D03*
X1350792Y1095024D03*
Y1101402D03*
X1356343Y1104591D03*
X1363745Y1091835D03*
X1360044D03*
X1358193Y1095024D03*
X1356343Y1098213D03*
X1363745Y1104591D03*
X1360044D03*
X1352642D03*
X1354493Y1095024D03*
X1352642Y1098213D03*
X1354493Y1101402D03*
X1352642Y1091835D03*
X1361894Y1095024D03*
X1363745Y1098213D03*
X1360044D03*
X1356343Y1091835D03*
X1358193Y1101402D03*
X1361894D03*
X1350792Y1107780D03*
Y1114158D03*
X1358193Y1107780D03*
X1360044Y1110969D03*
X1363745D03*
X1356343Y1117347D03*
X1358193Y1114158D03*
X1354493D03*
X1352642Y1117347D03*
X1354493Y1107780D03*
X1352642Y1110969D03*
X1361894Y1114158D03*
Y1107780D03*
X1363745Y1117347D03*
X1360044D03*
X1356343Y1110969D03*
X1350792Y1120536D03*
Y1126914D03*
Y1133292D03*
X1358193Y1126914D03*
X1363745Y1123725D03*
X1360044D03*
X1358193Y1120536D03*
X1356343Y1130102D03*
X1358193Y1133292D03*
X1354493Y1120536D03*
X1352642Y1123725D03*
X1354493Y1133292D03*
Y1126914D03*
X1352642Y1130102D03*
X1361894Y1120536D03*
Y1126914D03*
Y1133292D03*
X1363745Y1130102D03*
X1360044D03*
X1356343Y1123725D03*
X1350792Y1139669D03*
Y1146047D03*
X1358193Y1139669D03*
X1363745Y1136480D03*
X1360044D03*
X1356343Y1142858D03*
X1363745Y1149236D03*
X1360044D03*
X1358193Y1146047D03*
X1352642Y1136480D03*
X1354493Y1139669D03*
X1352642Y1142858D03*
X1354493Y1146047D03*
X1352642Y1149236D03*
X1361894Y1139669D03*
Y1146047D03*
X1360044Y1142858D03*
X1363745D03*
X1356343Y1149236D03*
Y1136480D03*
X1354493Y1158803D03*
X1350792Y1152425D03*
Y1158803D03*
X1352642Y1161992D03*
X1356343Y1155614D03*
X1363745D03*
X1360044D03*
X1363745Y1161992D03*
X1354493Y1152425D03*
X1352642Y1155614D03*
X1358193Y1152425D03*
X1356343Y1161992D03*
X1360044D03*
X1361894Y1158803D03*
X1358193D03*
X1361894Y1152425D03*
X1351141Y1547243D03*
X1352536Y1540295D03*
X1355866Y1547243D03*
X1357260Y1540295D03*
X1360590Y1547243D03*
X1361984Y1540295D03*
X1352436Y1549970D03*
X1357161D03*
X1361885D03*
X1354011Y1552698D03*
X1358735D03*
X1363460D03*
X1360260Y1554453D03*
X1355536D03*
X1350811D03*
X1360811Y1561853D03*
X1356087D03*
X1351362D03*
X1352436Y1563608D03*
X1357161D03*
X1361885D03*
X1354011Y1566336D03*
X1358735D03*
X1363460D03*
X1360260Y1556953D03*
X1360811Y1559353D03*
X1350811Y1556953D03*
X1351362Y1559353D03*
X1356087D03*
X1355536Y1556953D03*
X1355586Y1569063D03*
X1361984Y1575641D03*
X1360310Y1569063D03*
X1352536Y1575641D03*
X1350861Y1569063D03*
X1357260Y1575641D03*
X1350619Y1625380D03*
X1358419D03*
X1362679D03*
X1352379Y1635380D03*
X1356659D03*
X1364439D03*
X1356659Y1647292D03*
X1352379D03*
X1364439D03*
X1358419Y1657292D03*
X1350619D03*
X1362679D03*
X1373666Y876434D03*
X1375516Y873245D03*
Y879623D03*
X1369965Y876434D03*
X1366264D03*
X1377367D03*
X1368115Y879623D03*
X1371815D03*
X1375516Y892379D03*
X1371815D03*
X1369965Y882812D03*
X1366264D03*
X1369965Y889190D03*
X1368115Y892379D03*
X1366264Y895568D03*
X1373666Y882812D03*
X1377367D03*
X1379217Y892379D03*
X1377367Y895568D03*
X1373666Y889190D03*
X1368115Y886001D03*
X1369965Y895568D03*
X1373666D03*
X1366264Y889190D03*
X1377366D03*
X1379216Y886001D03*
X1371815D03*
X1375516D03*
Y898757D03*
Y905134D03*
X1371815Y898757D03*
Y905134D03*
X1375516Y911512D03*
X1371815D03*
X1368115Y898757D03*
X1369965Y901946D03*
X1366264D03*
X1368115Y905134D03*
Y911512D03*
X1366264Y908324D03*
X1379217Y898757D03*
X1377367Y901946D03*
X1373666D03*
X1379217Y905134D03*
X1377367Y908324D03*
X1379217Y911512D03*
X1369965Y908324D03*
X1373666D03*
X1375516Y917890D03*
Y924268D03*
X1371815Y917890D03*
Y924268D03*
X1369965Y914701D03*
X1368115Y917890D03*
X1366264Y914701D03*
X1368115Y924268D03*
X1366264Y921079D03*
X1377367Y914701D03*
X1373666D03*
X1379217Y917890D03*
X1377367Y921079D03*
X1379217Y924268D03*
X1369965Y921079D03*
X1373666D03*
X1375516Y930646D03*
X1371815D03*
X1366264Y933835D03*
X1369965Y927457D03*
X1368115Y930646D03*
X1369965Y933835D03*
X1366264Y927457D03*
Y940213D03*
X1377367Y927457D03*
X1373666D03*
X1379217Y930646D03*
X1377367Y933835D03*
X1373666D03*
X1377367Y940213D03*
X1369965D03*
X1373666D03*
X1371815Y937024D03*
X1379217D03*
X1368115D03*
X1375516D03*
X1371815Y956158D03*
Y943402D03*
Y949780D03*
X1375516Y956158D03*
Y943402D03*
Y949780D03*
X1368115Y943402D03*
X1369965Y946591D03*
X1368115Y949780D03*
X1366264Y946591D03*
X1368115Y956158D03*
X1366264Y952969D03*
X1379217Y943402D03*
X1373666Y946591D03*
X1377367D03*
X1379217Y949780D03*
X1377367Y952969D03*
X1379217Y956158D03*
X1369965Y952969D03*
X1373666D03*
X1371815Y962536D03*
Y968914D03*
X1375516Y962536D03*
Y968914D03*
X1366264Y959347D03*
X1369965D03*
X1368115Y962536D03*
X1366264Y965725D03*
X1368115Y968914D03*
X1373666Y959347D03*
X1377367Y965725D03*
Y959347D03*
X1379217Y962536D03*
Y968914D03*
X1369965Y965725D03*
X1373666D03*
X1371815Y975292D03*
X1375516D03*
X1369965Y972103D03*
X1368115Y975292D03*
Y981670D03*
X1366264Y972103D03*
Y978481D03*
X1369965Y984859D03*
X1373666Y972103D03*
X1377367D03*
X1379217Y975292D03*
X1375516Y981670D03*
X1377367Y978481D03*
Y984859D03*
X1366264D03*
X1369965Y978481D03*
X1373666D03*
X1371815Y981670D03*
X1379217D03*
X1373666Y984859D03*
X1369965Y991237D03*
Y997615D03*
X1368115Y994426D03*
Y988048D03*
Y1000804D03*
X1375516Y994426D03*
X1377367Y991237D03*
Y997615D03*
X1375516Y988048D03*
Y1000804D03*
X1373666Y991237D03*
X1371815Y988048D03*
Y994426D03*
Y1000804D03*
X1366264Y997615D03*
Y991237D03*
X1379217Y988048D03*
Y994426D03*
X1373666Y997615D03*
X1379217Y1000804D03*
X1369965Y1003993D03*
X1368115Y1007182D03*
X1366264Y1010371D03*
X1373666D03*
X1375516Y1007182D03*
X1371815D03*
X1377367Y1003993D03*
X1366264D03*
X1379217Y1007182D03*
X1377367Y1010371D03*
X1373666Y1003993D03*
X1369965Y1010371D03*
X1371146Y1028055D03*
X1374847D03*
X1378548D03*
X1367445D03*
X1369296Y1044000D03*
Y1037622D03*
Y1031244D03*
X1371146Y1034433D03*
X1376697Y1037622D03*
X1378548Y1040811D03*
X1371146D03*
X1374847Y1034433D03*
X1376697Y1031244D03*
Y1044000D03*
X1374847Y1040811D03*
X1378548Y1034433D03*
X1372997Y1037622D03*
Y1044000D03*
X1367445Y1040811D03*
Y1034433D03*
X1365595Y1031244D03*
Y1037622D03*
Y1044000D03*
X1372997Y1031244D03*
X1378548Y1053567D03*
X1376697Y1050378D03*
X1367445Y1059945D03*
X1369296Y1056756D03*
Y1050378D03*
X1371146Y1047189D03*
X1378548D03*
X1376697Y1056756D03*
X1371146Y1053567D03*
X1378548Y1059945D03*
X1374847Y1047189D03*
Y1053567D03*
X1371146Y1059945D03*
X1372997Y1056756D03*
Y1050378D03*
X1374847Y1059945D03*
X1365595Y1056756D03*
X1367445Y1047189D03*
Y1053567D03*
X1365595Y1050378D03*
X1369296Y1063134D03*
Y1069512D03*
X1367445Y1066323D03*
Y1072701D03*
X1371146Y1066323D03*
X1378548D03*
X1374847D03*
X1378548Y1072701D03*
X1372997Y1069512D03*
Y1063134D03*
X1365595Y1069512D03*
Y1063134D03*
X1376697Y1069512D03*
Y1063134D03*
X1371146Y1072701D03*
X1374847D03*
X1369296Y1075890D03*
X1367445Y1079079D03*
X1369296Y1088646D03*
X1367445Y1085457D03*
X1369296Y1082268D03*
X1371146Y1079079D03*
X1378548D03*
X1374847D03*
X1378548Y1085457D03*
X1372997Y1075890D03*
X1365595D03*
X1376697D03*
X1372997Y1088646D03*
Y1082268D03*
X1365595Y1088646D03*
Y1082268D03*
X1376697Y1088646D03*
Y1082268D03*
X1374847Y1085457D03*
X1371146D03*
X1367445Y1091835D03*
X1369296Y1095024D03*
X1367445Y1104591D03*
Y1098213D03*
X1371146Y1091835D03*
X1378548D03*
X1374847D03*
X1371146Y1104591D03*
X1374847D03*
X1378548Y1098213D03*
Y1104591D03*
X1372997Y1095024D03*
X1365595D03*
X1376697D03*
X1374847Y1098213D03*
X1371146D03*
X1372997Y1101402D03*
X1376697D03*
X1369296D03*
X1365595D03*
X1369296Y1107780D03*
X1367445Y1110969D03*
X1369296Y1114158D03*
X1367445Y1117347D03*
X1371146Y1110969D03*
X1378548D03*
X1374847D03*
X1378548Y1117347D03*
X1365595Y1114158D03*
Y1107780D03*
X1376697Y1114158D03*
Y1107780D03*
X1372997Y1114158D03*
Y1107780D03*
X1374847Y1117347D03*
X1371146D03*
X1367445Y1130103D03*
X1369296Y1126914D03*
Y1120536D03*
X1367445Y1123725D03*
X1369296Y1133292D03*
X1374847Y1123725D03*
X1371146D03*
X1378548D03*
Y1130102D03*
X1365595Y1120536D03*
X1376697D03*
Y1126914D03*
X1372997Y1120536D03*
Y1126914D03*
X1365595D03*
Y1133292D03*
X1376697D03*
X1372997D03*
X1371146Y1130102D03*
X1374847D03*
X1369296Y1139669D03*
X1367445Y1136480D03*
Y1142858D03*
X1369296Y1146047D03*
X1374847Y1136480D03*
X1371146D03*
X1378548D03*
Y1142858D03*
X1371146Y1149236D03*
X1374847D03*
X1365595Y1139669D03*
Y1146047D03*
X1376697Y1139669D03*
Y1146047D03*
X1372997Y1139669D03*
Y1146047D03*
X1374847Y1142858D03*
X1371146D03*
X1378548Y1149236D03*
X1367445D03*
Y1155614D03*
X1365595Y1158803D03*
X1371146Y1155614D03*
X1378548D03*
X1374847D03*
X1376697Y1158803D03*
Y1165181D03*
X1374847Y1161992D03*
X1369296Y1152425D03*
X1371146Y1161992D03*
X1378548D03*
X1367445D03*
X1372997Y1158803D03*
X1369296D03*
X1365595Y1152425D03*
X1376697D03*
X1372997D03*
X1365315Y1547243D03*
X1366709Y1540295D03*
X1370039Y1547243D03*
X1371433Y1540295D03*
X1374763Y1547243D03*
X1376158Y1540295D03*
X1379488Y1547243D03*
X1371334Y1549970D03*
X1376058D03*
X1366609D03*
X1372909Y1552698D03*
X1377633D03*
X1368184D03*
X1379158Y1554453D03*
X1374433D03*
X1369709D03*
X1364984D03*
X1374984Y1561853D03*
X1370260D03*
X1365535D03*
X1371334Y1563608D03*
X1376058D03*
X1366609D03*
X1372909Y1566336D03*
X1377633D03*
X1368184D03*
X1369709Y1556953D03*
X1370260Y1559353D03*
X1379158Y1556953D03*
X1374984Y1559353D03*
X1374433Y1556953D03*
X1365535Y1559353D03*
X1364984Y1556953D03*
X1379208Y1569063D03*
X1369759D03*
X1365035D03*
X1371433Y1575641D03*
X1366709D03*
X1376158D03*
X1374483Y1569063D03*
X1370479Y1625380D03*
X1374740D03*
X1368719Y1635380D03*
X1376499Y1635286D03*
X1368719Y1647292D03*
X1376499D03*
X1370479Y1657292D03*
X1374739D03*
X1386619Y879623D03*
X1382918Y873245D03*
X1384768Y876434D03*
X1394020Y873245D03*
X1388469Y876434D03*
X1392170D03*
X1381067D03*
X1390320Y879623D03*
X1394021D03*
X1386619Y892379D03*
X1394020D03*
X1382918D03*
X1384768Y882812D03*
X1381067D03*
Y889190D03*
X1384768D03*
X1392170Y882812D03*
X1388469D03*
Y895568D03*
X1392170Y889190D03*
X1390319Y892379D03*
X1381067Y895568D03*
X1384768D03*
X1390319Y886001D03*
X1392170Y895568D03*
X1388469Y889190D03*
X1394021Y886001D03*
X1386619Y905134D03*
Y898757D03*
X1394020Y905134D03*
Y898757D03*
X1382918Y905134D03*
Y898757D03*
X1386619Y911512D03*
X1394020D03*
X1382918D03*
X1381067Y901946D03*
X1384768D03*
X1388469D03*
X1390319Y898757D03*
X1392170Y901946D03*
X1388469Y908324D03*
X1390319Y911512D03*
Y905134D03*
X1384768Y908324D03*
X1392170D03*
X1381067Y908323D03*
X1386619Y924268D03*
Y917890D03*
X1394020Y924268D03*
Y917890D03*
X1382918Y924268D03*
Y917890D03*
X1381067Y914701D03*
X1384768D03*
X1390319Y917890D03*
X1388469Y914701D03*
X1392170D03*
X1388469Y921079D03*
X1390319Y924268D03*
X1384768Y921079D03*
X1381067D03*
X1392170D03*
X1394020Y937024D03*
X1381067Y927457D03*
X1384768D03*
X1388469D03*
Y933835D03*
X1392170Y927457D03*
X1390319Y930646D03*
X1392170Y933835D03*
X1388469Y940213D03*
X1390319Y937024D03*
X1382918Y930646D03*
X1386619D03*
X1384768Y940213D03*
X1381067D03*
X1394020Y930646D03*
X1392170Y940213D03*
X1381067Y933835D03*
X1386619Y937024D03*
X1384768Y933835D03*
X1382918Y937024D03*
X1394020Y956158D03*
Y943402D03*
Y949780D03*
X1382918Y956158D03*
Y943402D03*
Y949780D03*
X1386619Y956158D03*
Y943402D03*
Y949780D03*
X1381067Y946591D03*
X1384768D03*
X1388469D03*
X1390319Y943402D03*
X1392170Y946591D03*
X1390319Y949780D03*
X1388469Y952969D03*
X1390319Y956158D03*
X1384768Y952969D03*
X1381067D03*
X1392170D03*
X1394020Y962536D03*
Y968914D03*
X1382918Y962536D03*
Y968914D03*
X1386619Y962536D03*
Y968914D03*
X1381067Y959347D03*
X1384768D03*
X1388469Y965725D03*
Y959347D03*
X1392170D03*
X1390319Y962536D03*
Y968914D03*
X1384768Y965725D03*
X1381067D03*
X1392170D03*
X1394020Y975292D03*
X1382918D03*
X1386619D03*
X1388469Y978481D03*
X1381067Y972103D03*
X1384768D03*
X1382918Y981670D03*
X1384768Y984859D03*
X1388469Y972103D03*
X1392170D03*
X1390319Y981670D03*
Y975292D03*
X1392170Y984859D03*
X1381067Y978481D03*
X1384768D03*
X1386619Y981670D03*
X1381067Y984859D03*
X1392170Y978481D03*
X1394020Y981670D03*
X1388469Y984859D03*
X1384768Y991237D03*
X1382918Y988048D03*
X1392170Y991237D03*
X1390319Y988048D03*
X1384756Y997607D03*
X1392157D03*
X1386619Y988048D03*
X1394020D03*
X1381067Y991237D03*
X1388457Y997607D03*
X1388469Y991237D03*
X1386606Y1007174D03*
X1381065Y1010365D03*
X1382905Y1007174D03*
X1385937Y1028063D03*
X1382236D03*
X1385937Y1034441D03*
X1393339Y1040819D03*
X1385937D03*
X1380398Y1044000D03*
X1382246Y1040819D03*
X1389638D03*
X1382236Y1034441D03*
X1380398Y1037622D03*
Y1031244D03*
X1385949Y1047189D03*
Y1053567D03*
X1384099Y1056756D03*
Y1050378D03*
X1393351Y1047189D03*
Y1053567D03*
X1389650Y1059945D03*
X1391500Y1056756D03*
Y1050378D03*
X1382249Y1047189D03*
X1389650D03*
X1380398Y1050378D03*
X1382249Y1059945D03*
Y1053567D03*
X1385949Y1059945D03*
X1380398Y1056756D03*
X1387800D03*
X1393351Y1059945D03*
X1387800Y1050378D03*
X1389650Y1053567D03*
Y1066323D03*
X1391500Y1069512D03*
X1389650Y1072701D03*
X1380398Y1063134D03*
X1385949Y1066323D03*
X1382249D03*
X1380398Y1069512D03*
X1391500Y1063134D03*
X1393351Y1066323D03*
X1384099Y1069512D03*
Y1063134D03*
X1387800Y1069512D03*
Y1063134D03*
X1382249Y1072701D03*
X1385949D03*
X1393351D03*
X1380398Y1075890D03*
X1385949Y1079079D03*
X1382249D03*
X1380398Y1088646D03*
Y1082268D03*
X1391500Y1075890D03*
X1393351Y1079079D03*
X1389650D03*
X1391500Y1088646D03*
X1389650Y1085457D03*
X1391500Y1082268D03*
X1384099Y1075890D03*
X1387800D03*
X1384099Y1088646D03*
Y1082268D03*
X1387800Y1088646D03*
Y1082268D03*
X1382249Y1085457D03*
X1385949D03*
X1393351D03*
X1385949Y1091835D03*
X1382249D03*
X1380398Y1095024D03*
X1393351Y1091835D03*
X1389650D03*
X1391500Y1095024D03*
Y1101402D03*
X1389650Y1098213D03*
X1393351Y1104591D03*
X1389650D03*
X1384099Y1095024D03*
X1387800D03*
X1382249Y1098213D03*
X1385949D03*
X1393351D03*
X1385949Y1104591D03*
X1384099Y1101402D03*
X1380398D03*
X1382249Y1104591D03*
X1387800Y1101402D03*
X1385949Y1110969D03*
X1382249D03*
X1380398Y1107780D03*
Y1114158D03*
X1393351Y1110969D03*
X1389650D03*
X1391500Y1107780D03*
X1389650Y1117347D03*
X1391500Y1114158D03*
X1387800D03*
X1384099D03*
Y1107780D03*
X1382249Y1117347D03*
X1385949D03*
X1387800Y1107780D03*
X1393351Y1117347D03*
X1385949Y1123725D03*
X1382249D03*
X1380398Y1120536D03*
Y1126914D03*
Y1133292D03*
X1393351Y1123725D03*
X1389650D03*
X1391500Y1120536D03*
Y1126914D03*
Y1133292D03*
X1389650Y1130102D03*
X1387800Y1120536D03*
Y1126914D03*
X1384099Y1120536D03*
Y1126914D03*
X1387800Y1133292D03*
X1384099D03*
X1385949Y1130102D03*
X1382249D03*
X1393351D03*
X1380398Y1139669D03*
X1385949Y1136480D03*
X1382249D03*
X1385949Y1149236D03*
X1382249D03*
X1380398Y1146047D03*
X1391500Y1139669D03*
X1393351Y1136480D03*
X1389650D03*
Y1142858D03*
X1393351Y1149236D03*
X1391500Y1146047D03*
X1387800Y1139669D03*
Y1146047D03*
X1384099Y1139669D03*
Y1146047D03*
X1382249Y1142858D03*
X1385949D03*
X1393351D03*
X1389650Y1149236D03*
X1385949Y1155614D03*
X1382249D03*
X1385949Y1161992D03*
X1387800Y1158803D03*
X1393351Y1155614D03*
X1389650D03*
X1380398Y1152425D03*
X1382249Y1161992D03*
X1391500Y1152425D03*
X1393351Y1161992D03*
X1389650D03*
X1384099Y1158803D03*
X1380398D03*
X1391500D03*
X1387800Y1152425D03*
X1384099D03*
X1388937Y1547243D03*
X1380882Y1540295D03*
X1384212Y1547243D03*
X1385606Y1540295D03*
X1390331D03*
X1393661Y1547243D03*
X1380783Y1549970D03*
X1385507D03*
X1390232D03*
X1382357Y1552698D03*
X1387082D03*
X1391806D03*
X1393331Y1554453D03*
X1388607D03*
X1383882D03*
X1393882Y1561853D03*
X1389158D03*
X1384433D03*
X1379709D03*
X1380783Y1563608D03*
X1385507D03*
X1390232D03*
X1382357Y1566336D03*
X1387082D03*
X1391806D03*
X1388607Y1556953D03*
X1384433Y1559353D03*
X1383882Y1556953D03*
X1379709Y1559353D03*
X1393882D03*
X1389158D03*
X1393331Y1556953D03*
X1388657Y1569063D03*
X1385606Y1575641D03*
X1383932Y1569063D03*
X1380882Y1575641D03*
X1390331D03*
X1393381Y1569063D03*
X1382539Y1625380D03*
X1388569Y1635380D03*
X1380779D03*
Y1647292D03*
X1388569D03*
X1382539Y1657292D03*
X1397721Y873245D03*
Y879623D03*
X1395871Y876434D03*
X1408823Y879623D03*
X1399571Y876434D03*
X1403272D03*
X1405123Y879623D03*
X1401423D03*
X1406973Y895568D03*
X1397721Y892379D03*
X1403272Y895568D03*
X1399571Y882812D03*
X1395871D03*
X1401422Y892379D03*
X1399571Y895568D03*
X1395871Y889190D03*
X1403272Y882812D03*
X1406973D03*
X1403272Y889190D03*
X1406973D03*
X1401422Y886001D03*
X1395871Y895568D03*
X1399571Y889190D03*
X1408823Y892379D03*
X1405123D03*
X1397722Y886001D03*
X1408824D03*
X1405123D03*
X1406973Y908324D03*
Y901946D03*
X1397721Y905134D03*
Y898757D03*
X1403272Y908324D03*
Y901946D03*
X1397721Y911512D03*
X1399571Y901946D03*
X1395871D03*
X1401422Y905134D03*
Y911512D03*
X1405123Y905134D03*
X1408823D03*
X1401422Y898757D03*
X1399571Y908323D03*
X1395871Y908324D03*
X1408823Y911512D03*
X1405123D03*
X1408823Y898757D03*
X1405123D03*
X1406973Y921079D03*
Y914701D03*
X1397721Y924268D03*
Y917890D03*
X1403272Y921079D03*
Y914701D03*
X1399571D03*
X1401422Y917890D03*
X1395871Y914701D03*
X1399571Y921079D03*
X1401422Y924268D03*
X1405123Y917890D03*
X1408823D03*
X1395871Y921079D03*
X1408823Y924268D03*
X1405123D03*
X1403272Y940213D03*
X1406973D03*
X1397721Y937024D03*
X1406973Y927457D03*
X1403272D03*
X1395871D03*
Y933835D03*
X1399571Y927457D03*
X1401422Y930646D03*
X1399571Y933835D03*
Y940213D03*
X1401422Y937024D03*
X1405123Y930646D03*
X1408823D03*
X1405123Y937024D03*
X1408823D03*
X1397721Y930646D03*
X1395871Y940213D03*
X1406973Y933835D03*
X1403272D03*
Y952969D03*
Y946591D03*
X1406973Y952969D03*
Y946591D03*
X1397721Y956158D03*
Y943402D03*
Y949780D03*
X1401422Y943402D03*
X1399571Y946591D03*
X1401422Y949780D03*
X1399571Y952969D03*
X1401422Y956158D03*
X1408823Y949780D03*
X1405123D03*
X1395871Y946591D03*
Y952969D03*
X1405123Y943402D03*
X1408823D03*
X1405123Y956158D03*
X1408823D03*
X1403272Y959347D03*
Y965725D03*
X1406973Y959347D03*
Y965725D03*
X1397721Y962536D03*
Y968914D03*
X1399571Y965725D03*
X1395871Y959347D03*
X1399571D03*
X1401422Y962536D03*
Y968914D03*
X1408823Y962536D03*
X1405123D03*
Y968914D03*
X1395871Y965725D03*
X1408823Y968914D03*
X1403272Y978481D03*
Y972103D03*
X1406973Y978481D03*
Y972103D03*
X1397721Y975292D03*
Y981670D03*
X1399571Y978481D03*
X1395871Y972103D03*
X1399571D03*
X1401422Y975292D03*
X1399571Y984859D03*
X1405123Y981670D03*
X1408823Y975292D03*
X1405123D03*
X1406973Y984859D03*
X1395871Y978481D03*
X1401422Y981670D03*
X1395871Y984859D03*
X1408823Y981670D03*
X1403272Y984859D03*
X1399571Y991237D03*
X1397721Y988048D03*
X1406973Y991237D03*
X1405123Y988048D03*
X1406961Y997607D03*
X1399559D03*
X1401422Y988048D03*
X1395858Y997607D03*
X1395871Y991237D03*
X1403260Y997607D03*
X1408823Y988048D03*
X1403272Y991237D03*
X1400740Y1040819D03*
X1397039D03*
X1404441D03*
X1400752Y1047189D03*
X1398902Y1056756D03*
X1400752Y1053567D03*
Y1059945D03*
X1398902Y1050378D03*
X1408154Y1047189D03*
Y1053567D03*
X1406304Y1056756D03*
Y1050378D03*
X1404453Y1059945D03*
X1408154D03*
X1397052Y1047189D03*
X1404453D03*
X1395201Y1050378D03*
X1402603Y1056756D03*
Y1050378D03*
X1395201Y1056756D03*
X1397052Y1059945D03*
Y1053567D03*
X1404453D03*
X1402603Y1063134D03*
Y1069512D03*
X1397052Y1066323D03*
X1400752D03*
Y1072701D03*
X1406304Y1063134D03*
X1395201D03*
X1404453Y1072701D03*
Y1066323D03*
X1395201Y1069512D03*
X1398902Y1063134D03*
X1408154Y1072701D03*
Y1066323D03*
X1398902Y1069512D03*
X1406304D03*
X1397052Y1072701D03*
X1402603Y1075890D03*
X1400752Y1079079D03*
X1397052D03*
X1402603Y1088646D03*
Y1082268D03*
X1400752Y1085457D03*
X1406304Y1075890D03*
Y1088646D03*
X1395201Y1075890D03*
X1404453Y1079079D03*
X1398902Y1075890D03*
X1408154Y1079079D03*
X1395201Y1082268D03*
X1404453Y1085457D03*
X1395201Y1088646D03*
X1398902Y1082268D03*
X1408154Y1085457D03*
X1398902Y1088646D03*
X1397052Y1085457D03*
X1406304Y1082268D03*
X1402603Y1095024D03*
X1400752Y1091835D03*
X1397052D03*
X1402603Y1101402D03*
X1400752Y1104591D03*
X1397052D03*
X1400752Y1098213D03*
X1406304Y1101402D03*
X1395201Y1095024D03*
Y1101402D03*
X1404453Y1098213D03*
Y1091835D03*
X1398902Y1095024D03*
Y1101402D03*
X1408154Y1098213D03*
Y1091835D03*
X1397052Y1098213D03*
X1406304Y1095024D03*
X1408154Y1104591D03*
X1404453D03*
X1402603Y1107780D03*
X1397052Y1110969D03*
X1400752D03*
X1402603Y1114158D03*
X1400752Y1117347D03*
X1406304Y1107780D03*
X1398902Y1114158D03*
X1408154Y1117347D03*
Y1110969D03*
X1395201Y1114158D03*
X1404453Y1117347D03*
Y1110969D03*
X1398902Y1107780D03*
X1395201D03*
X1397052Y1117347D03*
X1406304Y1114158D03*
X1402603Y1120536D03*
Y1126914D03*
X1397052Y1123725D03*
X1400752D03*
X1402603Y1133292D03*
X1406304Y1120536D03*
Y1133292D03*
X1400752Y1130103D03*
X1398902Y1120536D03*
Y1126914D03*
X1408154Y1123725D03*
X1395201Y1120536D03*
Y1126914D03*
X1404453Y1123725D03*
X1398902Y1133292D03*
X1408154Y1130102D03*
X1395201Y1133292D03*
X1404453Y1130102D03*
X1397052D03*
X1406304Y1126914D03*
X1402603Y1139669D03*
X1397052Y1136480D03*
X1400752D03*
Y1142858D03*
X1402603Y1146047D03*
X1397052Y1149236D03*
X1408154D03*
X1404453D03*
X1398902Y1139669D03*
Y1146047D03*
X1408154Y1142858D03*
Y1136480D03*
X1395201Y1139669D03*
Y1146047D03*
X1404453Y1142858D03*
Y1136480D03*
X1397052Y1142858D03*
X1400752Y1149236D03*
X1406304Y1139669D03*
Y1146047D03*
X1398902Y1158803D03*
X1397052Y1155614D03*
X1400752D03*
X1397052Y1161992D03*
X1398902Y1165181D03*
X1406304Y1158803D03*
X1402603Y1152425D03*
X1400752Y1161992D03*
X1406304Y1152425D03*
X1404453Y1161992D03*
X1395201Y1158803D03*
X1398902Y1152425D03*
X1395201D03*
X1408154Y1155614D03*
X1395055Y1540295D03*
X1394956Y1549970D03*
X1396531Y1552698D03*
X1399256Y1540355D03*
X1401356D03*
X1402763Y1547073D03*
X1402707Y1549336D03*
X1398076Y1554453D03*
X1394956Y1563608D03*
X1396531Y1566336D03*
X1403058Y1567540D03*
X1403059Y1564618D03*
X1402970Y1561698D03*
X1395055Y1575641D03*
X1398712Y1569063D03*
X1402473Y1571658D03*
X1410674Y876434D03*
X1423602Y879623D03*
X1421751Y876434D03*
X1410674Y882812D03*
Y889190D03*
Y895568D03*
X1421751Y882812D03*
Y895568D03*
Y889190D03*
X1423602Y892379D03*
X1410674Y901946D03*
Y908324D03*
X1421751Y901946D03*
X1423602Y905134D03*
X1421751Y908324D03*
X1423602Y911512D03*
Y898757D03*
X1410674Y914701D03*
Y921079D03*
X1423602Y917890D03*
X1421751Y914701D03*
Y921079D03*
X1423602Y924268D03*
X1421751Y940213D03*
X1410674Y927457D03*
Y933835D03*
Y940213D03*
X1423602Y930646D03*
X1421751Y927457D03*
Y933835D03*
X1423602Y937024D03*
X1410674Y946591D03*
Y952969D03*
X1423602Y949780D03*
X1421751Y946591D03*
Y952969D03*
X1423602Y943402D03*
Y956158D03*
X1410674Y959347D03*
Y965725D03*
X1423602Y962536D03*
X1421751Y959347D03*
Y965725D03*
X1423602Y968914D03*
X1410674Y972103D03*
Y978481D03*
X1423602Y981670D03*
Y975292D03*
X1421751Y972103D03*
Y978481D03*
Y984859D03*
X1410674D03*
X1423602Y988048D03*
X1421751Y991237D03*
X1421764Y997607D03*
X1410661D03*
X1410674Y991237D03*
X1411855Y1059945D03*
X1422932Y1047189D03*
Y1059945D03*
Y1053567D03*
X1411855Y1047189D03*
X1410004Y1050378D03*
X1411855Y1053567D03*
X1410004Y1056756D03*
Y1063134D03*
X1411855Y1066323D03*
Y1072701D03*
X1422932D03*
Y1066323D03*
X1410004Y1069512D03*
Y1075890D03*
X1411855Y1079079D03*
Y1085457D03*
X1410004Y1088646D03*
X1422932Y1079079D03*
Y1085457D03*
X1410004Y1082268D03*
X1422932Y1091835D03*
Y1104591D03*
Y1098213D03*
X1411855Y1091835D03*
Y1104591D03*
Y1098213D03*
X1410004Y1101402D03*
Y1095024D03*
Y1107780D03*
X1411855Y1110969D03*
Y1117347D03*
X1422932Y1110969D03*
Y1117347D03*
X1410004Y1114158D03*
X1411855Y1123725D03*
X1410004Y1120536D03*
X1411855Y1130102D03*
X1410004Y1133292D03*
X1422932Y1123725D03*
Y1130102D03*
X1410004Y1126914D03*
X1411855Y1136480D03*
Y1142858D03*
Y1149236D03*
X1422932Y1136480D03*
Y1142858D03*
Y1149236D03*
X1410004Y1139669D03*
Y1146047D03*
X1411855Y1155614D03*
Y1161992D03*
X1422932Y1155614D03*
Y1161992D03*
X1410004Y1152425D03*
Y1158803D03*
X1436554Y876434D03*
X1438405Y879623D03*
X1431003Y873245D03*
X1434704Y879623D03*
Y873245D03*
X1438405D03*
X1429153Y876434D03*
X1432854D03*
X1434704Y892379D03*
X1425452Y895568D03*
X1438405Y892379D03*
X1429153Y895568D03*
Y882812D03*
X1425452Y889190D03*
X1429153D03*
X1431003Y892379D03*
X1432854Y895568D03*
X1436554Y889190D03*
Y882812D03*
X1431003Y886001D03*
X1427302D03*
Y892379D03*
X1432854Y889190D03*
X1436554Y895568D03*
X1438405Y886001D03*
X1434704Y898757D03*
Y905134D03*
X1425452Y901946D03*
Y908324D03*
X1438405Y898757D03*
Y905134D03*
X1429153Y901946D03*
Y908324D03*
X1432854Y901946D03*
X1431003Y898757D03*
Y911512D03*
Y905134D03*
X1427302D03*
X1436554Y901946D03*
X1432854Y908323D03*
X1434704Y911512D03*
X1438405D03*
X1427302D03*
X1436554Y908324D03*
X1427302Y898757D03*
X1432854Y914701D03*
X1431003Y917890D03*
X1427302D03*
X1432854Y921079D03*
X1431003Y924268D03*
X1436554Y914701D03*
X1434704Y917890D03*
Y924268D03*
X1425452Y914701D03*
Y921079D03*
X1438405Y917890D03*
Y924268D03*
X1429153Y914701D03*
Y921079D03*
X1427302Y924268D03*
X1436554Y921079D03*
X1438405Y937024D03*
X1429153Y940213D03*
X1434704Y937024D03*
X1425452Y940213D03*
X1432854Y927457D03*
X1431003Y930646D03*
X1427302D03*
X1432854Y933835D03*
Y940213D03*
X1431003Y937024D03*
X1427302D03*
X1436554Y927457D03*
Y933835D03*
X1425452Y927457D03*
X1429153D03*
Y933835D03*
X1425452D03*
X1434704Y930646D03*
X1438405D03*
X1436554Y940213D03*
X1438405Y943402D03*
Y956158D03*
X1429153Y946591D03*
Y952969D03*
X1438405Y949780D03*
X1434704Y943402D03*
Y956158D03*
X1425452Y946591D03*
Y952969D03*
X1434704Y949780D03*
X1431003Y943402D03*
Y949780D03*
X1427302D03*
X1432854Y946591D03*
Y952969D03*
X1431003Y956158D03*
X1436554Y946591D03*
X1427302Y943402D03*
Y956158D03*
X1436554Y952969D03*
X1432854Y959347D03*
X1427302Y962536D03*
X1431003D03*
X1432854Y965725D03*
X1431003Y968914D03*
X1436554Y959347D03*
X1438405Y962536D03*
X1429153Y965725D03*
Y959347D03*
X1438405Y968914D03*
X1434704Y962536D03*
X1425452Y965725D03*
Y959347D03*
X1434704Y968914D03*
X1427302D03*
X1436554Y965725D03*
X1432854Y978481D03*
X1431003Y981670D03*
X1432854Y972103D03*
X1431003Y975292D03*
X1427302D03*
X1429153Y984859D03*
X1438405Y981670D03*
X1436554Y972103D03*
Y984859D03*
X1438405Y975292D03*
X1429153Y972103D03*
Y978481D03*
X1434704Y975292D03*
X1425452Y972103D03*
Y978481D03*
X1427302Y981670D03*
X1434704D03*
X1425452Y984859D03*
X1432854D03*
X1436554Y978481D03*
X1431003Y988048D03*
X1429153Y991237D03*
X1436554D03*
X1438405Y988048D03*
X1436567Y997607D03*
X1429165D03*
X1434704Y988048D03*
X1425465Y997607D03*
X1432866D03*
X1427302Y988048D03*
X1425452Y991237D03*
X1432854D03*
X1430346Y1040819D03*
X1437748D03*
X1434047D03*
X1430334Y1047189D03*
X1424783Y1056756D03*
X1434035Y1059945D03*
X1432184Y1056756D03*
X1430334Y1053567D03*
X1424783Y1050378D03*
X1432184D03*
X1437735Y1047189D03*
Y1053567D03*
X1430334Y1059945D03*
X1426633D03*
X1434035Y1047189D03*
X1426633D03*
X1435885Y1050378D03*
X1428483D03*
X1437735Y1059945D03*
X1435885Y1056756D03*
X1428483D03*
X1426633Y1053567D03*
X1434035D03*
X1432184Y1063134D03*
X1428483D03*
X1424783D03*
X1432184Y1069512D03*
X1434035Y1072701D03*
Y1066323D03*
X1437735D03*
X1430334D03*
Y1072701D03*
X1426633Y1066323D03*
Y1072701D03*
X1435885Y1063134D03*
Y1069512D03*
X1428483D03*
X1424783D03*
X1437735Y1072701D03*
Y1079079D03*
X1428483Y1075890D03*
X1432184D03*
X1424783D03*
X1434035Y1079079D03*
X1424783Y1088646D03*
X1432184Y1082268D03*
X1428483Y1088646D03*
X1432184D03*
X1434035Y1085457D03*
X1430334Y1079079D03*
X1426633D03*
X1435885Y1075890D03*
Y1088646D03*
X1428483Y1082268D03*
X1424783D03*
X1437735Y1085457D03*
X1430334D03*
X1426633D03*
X1435885Y1082268D03*
X1432184Y1095024D03*
X1434035Y1091835D03*
Y1104591D03*
X1428483Y1101402D03*
X1432184D03*
X1434035Y1098213D03*
X1424783Y1101402D03*
X1437735Y1091835D03*
Y1104591D03*
X1435885Y1101402D03*
Y1095024D03*
X1428483D03*
X1424783D03*
X1430334Y1104591D03*
X1426633D03*
X1437735Y1098213D03*
X1430334Y1091835D03*
Y1098213D03*
X1426633Y1091835D03*
Y1098213D03*
X1428483Y1107780D03*
X1432184D03*
X1424783D03*
X1434035Y1110969D03*
Y1117347D03*
X1432184Y1114158D03*
X1437735Y1110969D03*
X1426633D03*
Y1117347D03*
X1435885Y1114158D03*
X1430334Y1110969D03*
Y1117347D03*
X1428483Y1114158D03*
X1424783D03*
X1435885Y1107780D03*
X1437735Y1117347D03*
X1432184Y1126914D03*
Y1120536D03*
X1428483D03*
X1424783D03*
X1434035Y1123725D03*
X1424783Y1133292D03*
X1428483D03*
X1432184D03*
X1437735Y1123725D03*
X1434035Y1130103D03*
X1430334Y1130102D03*
X1426633D03*
Y1123725D03*
X1435885Y1126914D03*
Y1120536D03*
X1430334Y1123725D03*
X1424783Y1126914D03*
X1428483D03*
X1437735Y1130102D03*
X1435885Y1133292D03*
X1432184Y1139669D03*
X1434035Y1136480D03*
Y1142858D03*
X1430334Y1149236D03*
X1432184Y1146047D03*
X1426633Y1149236D03*
X1437735Y1136480D03*
Y1149236D03*
X1435885Y1146047D03*
Y1139669D03*
X1428483D03*
X1424783D03*
X1434035Y1149236D03*
X1428483Y1146047D03*
X1424783D03*
X1437735Y1142858D03*
X1426633Y1136480D03*
Y1142858D03*
X1430334Y1136480D03*
Y1142858D03*
X1426633Y1161992D03*
X1424783Y1152425D03*
X1426633Y1155614D03*
X1430333D03*
X1435885Y1158803D03*
Y1152425D03*
X1428483D03*
X1432184D03*
X1434035Y1161992D03*
X1430334D03*
X1424783Y1158803D03*
X1432184D03*
X1434035Y1155614D03*
X1428484Y1158803D03*
X1437735Y1155614D03*
X1447657Y876434D03*
X1445806Y879623D03*
X1443956Y876434D03*
X1440255D03*
X1451358D03*
X1449507Y873245D03*
X1453208D03*
X1445806Y892379D03*
X1449507D03*
X1443956Y882812D03*
X1447657D03*
X1440255Y889190D03*
X1447657D03*
X1442106Y892379D03*
X1443956Y895568D03*
X1451357Y882812D03*
X1451358Y889190D03*
X1453208Y892379D03*
X1440255Y882812D03*
X1442106Y886001D03*
X1443956Y889190D03*
X1447657Y895568D03*
X1440255D03*
X1453208Y886001D03*
X1451358Y895568D03*
X1445806Y898757D03*
Y905134D03*
X1449507Y898757D03*
Y905134D03*
X1442106Y898757D03*
X1440255Y901946D03*
X1447657D03*
X1443956D03*
X1442106Y905134D03*
X1443956Y908324D03*
X1442106Y911512D03*
X1451358Y901946D03*
X1453208Y898757D03*
Y905134D03*
Y911512D03*
X1445806D03*
X1449507D03*
X1447657Y908324D03*
X1440255D03*
X1451357D03*
X1440255Y914701D03*
X1443956D03*
X1447657D03*
X1442106Y917890D03*
X1443956Y921079D03*
X1442106Y924268D03*
X1451357Y914701D03*
X1453208Y917890D03*
Y924268D03*
X1445806Y917890D03*
Y924268D03*
X1449507Y917890D03*
Y924268D03*
X1447657Y921079D03*
X1440255D03*
X1451357D03*
X1440255Y927457D03*
X1443956D03*
X1447657D03*
X1440255Y933835D03*
X1443956D03*
X1442106Y937024D03*
X1443956Y940213D03*
X1453208Y930646D03*
X1451357Y927457D03*
X1445806Y930646D03*
X1449507D03*
X1447657Y940213D03*
X1440255D03*
X1451357D03*
X1442106Y930646D03*
X1453208Y937024D03*
X1445806D03*
X1451357Y933835D03*
X1447657D03*
X1449507Y937024D03*
Y949780D03*
Y943402D03*
Y956158D03*
X1445806Y949780D03*
Y943402D03*
Y956158D03*
X1447657Y946591D03*
X1442106Y943402D03*
X1440255Y946591D03*
X1442106Y949780D03*
X1443956Y946591D03*
Y952969D03*
X1442106Y956158D03*
X1451357Y946591D03*
X1453208Y943402D03*
Y949780D03*
Y956158D03*
X1447657Y952969D03*
X1440255D03*
X1451357D03*
X1440255Y959347D03*
X1443956D03*
X1447657D03*
X1443956Y965725D03*
X1442106Y962536D03*
Y968914D03*
X1451357Y959347D03*
X1453208Y962536D03*
Y968914D03*
X1449507D03*
Y962536D03*
X1445806Y968914D03*
Y962536D03*
X1440255Y965725D03*
X1447657D03*
X1451357D03*
X1445806Y981670D03*
X1443956Y978481D03*
Y972103D03*
X1447657D03*
X1442106Y975292D03*
X1440255Y972103D03*
X1443956Y984859D03*
X1453208Y981670D03*
X1451357Y972103D03*
X1453208Y975292D03*
X1451357Y984859D03*
X1449507Y975292D03*
X1445806D03*
X1440255Y978481D03*
X1447657D03*
X1442106Y981670D03*
X1449507D03*
X1447657Y984859D03*
X1440255D03*
X1451357Y978481D03*
X1445806Y988048D03*
X1443956Y991237D03*
X1453208Y988048D03*
Y994426D03*
X1451357Y991237D03*
X1453208Y1000804D03*
X1443968Y997607D03*
X1449507Y988048D03*
X1440268Y997607D03*
X1447669D03*
X1442106Y988048D03*
X1440255Y991237D03*
X1447657D03*
X1453208Y1007182D03*
X1452542Y1040819D03*
X1445149D03*
X1441449D03*
X1448850D03*
X1445137Y1047189D03*
X1446987Y1056756D03*
X1445137Y1059945D03*
X1439586Y1056756D03*
X1445137Y1053567D03*
X1439586Y1050378D03*
X1446987D03*
X1452539Y1047189D03*
Y1053567D03*
X1441436Y1047189D03*
X1448838D03*
X1450688Y1050378D03*
Y1056756D03*
X1441436Y1059945D03*
Y1053567D03*
X1443287Y1056756D03*
X1448838Y1053567D03*
X1443287Y1050378D03*
X1448838Y1059945D03*
X1452539D03*
X1443287Y1063134D03*
X1445137Y1072701D03*
X1443287Y1069512D03*
X1448838Y1066323D03*
X1445137D03*
X1441436D03*
X1452539D03*
X1439586Y1063134D03*
Y1069512D03*
X1450688Y1063134D03*
Y1069512D03*
X1446987Y1063134D03*
Y1069512D03*
X1441436Y1072701D03*
X1448838D03*
X1452539D03*
X1445137Y1079079D03*
X1448838D03*
X1441436D03*
X1443287Y1075890D03*
Y1088646D03*
X1445137Y1085457D03*
X1443287Y1082268D03*
X1452539Y1079079D03*
X1439586Y1075890D03*
X1450688D03*
X1446987D03*
X1439586Y1088646D03*
X1450688Y1082268D03*
X1446987D03*
X1448838Y1085457D03*
X1441436D03*
X1452539D03*
X1439586Y1082268D03*
X1450688Y1088646D03*
X1446987D03*
X1441436Y1091835D03*
X1448838D03*
X1445137D03*
X1443287Y1095024D03*
X1445137Y1104591D03*
X1443287Y1101402D03*
X1445137Y1098213D03*
X1441436Y1104591D03*
X1452539Y1091835D03*
X1439586Y1101402D03*
Y1095024D03*
X1448838Y1098213D03*
X1441436D03*
X1452539D03*
X1448838Y1104591D03*
X1452539D03*
X1446987Y1101402D03*
X1450688D03*
Y1095024D03*
X1446987D03*
X1441436Y1110969D03*
X1448838D03*
X1445137D03*
X1443287Y1107780D03*
X1445137Y1117347D03*
X1443287Y1114158D03*
X1452539Y1110969D03*
X1446987Y1114158D03*
X1439586D03*
X1450688D03*
Y1107780D03*
X1446987D03*
X1439586D03*
X1448838Y1117347D03*
X1441436D03*
X1452539D03*
X1445137Y1123725D03*
X1448838D03*
X1443287Y1120536D03*
X1441436Y1123725D03*
X1443287Y1126914D03*
Y1133292D03*
X1445137Y1130102D03*
X1452539Y1123725D03*
X1446987Y1126914D03*
Y1120536D03*
X1439586Y1126914D03*
Y1120536D03*
X1450688Y1126914D03*
Y1120536D03*
X1446987Y1133292D03*
X1450688D03*
X1448838Y1130102D03*
X1441436D03*
X1452539Y1130103D03*
X1439586Y1133292D03*
X1448838Y1149236D03*
X1443287Y1146047D03*
X1441436Y1149236D03*
X1452539Y1136480D03*
Y1149236D03*
X1445137Y1142858D03*
X1443287Y1139669D03*
X1445137Y1136480D03*
X1448838D03*
X1441436D03*
X1446987Y1139669D03*
X1450688D03*
X1446987Y1146047D03*
X1439586D03*
Y1139669D03*
X1450688Y1146047D03*
X1448838Y1142858D03*
X1441436D03*
X1445137Y1149236D03*
X1452539Y1142858D03*
X1446987Y1152425D03*
X1443287Y1165181D03*
X1439586Y1158803D03*
X1446987D03*
X1450688Y1152425D03*
X1441436Y1155614D03*
X1443287Y1152425D03*
X1452539Y1161992D03*
X1441436D03*
X1445137D03*
X1448838Y1155614D03*
X1439586Y1152425D03*
X1445137Y1155614D03*
X1443287Y1158803D03*
X1450627Y1540509D03*
X1452827D03*
X1450792Y1546218D03*
X1449133Y1551121D03*
X1449626Y1556810D03*
Y1561725D03*
X1449534Y1554612D03*
X1449580Y1568698D03*
Y1570898D03*
X1451027Y1573317D03*
X1456909Y873245D03*
Y879623D03*
X1458759Y876434D03*
X1468011Y879623D03*
X1462460Y876434D03*
X1455058D03*
X1466161D03*
X1464310Y873245D03*
X1460609D03*
Y879623D03*
X1464310D03*
X1468011Y892379D03*
X1456909D03*
X1460609D03*
X1455058Y882812D03*
X1462460D03*
X1466161D03*
X1458759D03*
Y889190D03*
X1455058Y895568D03*
X1464310Y892379D03*
X1466161Y895568D03*
X1462460Y889190D03*
X1464310Y886001D03*
X1458759Y895568D03*
X1462460D03*
X1466161Y889190D03*
X1455058D03*
X1460609Y886001D03*
X1456909D03*
X1468011D03*
Y911512D03*
Y898757D03*
Y905134D03*
X1456909Y898757D03*
Y905134D03*
X1460609Y898757D03*
Y905134D03*
X1464310Y898757D03*
X1455058Y901946D03*
X1458759D03*
X1466161D03*
X1462460D03*
X1464310Y905134D03*
X1455058Y908324D03*
X1464310Y911512D03*
X1466161Y908323D03*
X1456909Y911512D03*
X1460609D03*
X1458759Y908324D03*
X1462460D03*
X1458759Y914701D03*
X1464310Y917890D03*
Y924268D03*
X1455058Y921079D03*
X1466161D03*
X1455058Y914701D03*
X1462460D03*
X1466161D03*
X1468011Y924268D03*
Y917890D03*
X1456909Y924268D03*
Y917890D03*
X1460609Y924268D03*
Y917890D03*
X1458759Y921079D03*
X1462460D03*
X1455058Y927457D03*
X1458759D03*
X1466161D03*
X1462460D03*
X1455058Y933835D03*
X1464310Y930646D03*
X1462460Y933835D03*
X1466161D03*
X1458759D03*
X1455058Y940213D03*
X1466161D03*
X1468011Y930646D03*
X1456909D03*
X1460609D03*
X1462460Y940213D03*
X1458759D03*
X1456909Y937024D03*
X1464310D03*
X1460609D03*
X1468011D03*
X1460609Y949780D03*
Y943402D03*
Y956158D03*
X1468011Y949780D03*
Y943402D03*
Y956158D03*
X1456909Y949780D03*
Y943402D03*
Y956158D03*
X1462460Y946591D03*
X1466161D03*
X1458759D03*
X1466161Y952969D03*
X1464310Y956158D03*
X1455058Y952969D03*
X1464310Y943402D03*
X1455058Y946591D03*
X1464310Y949780D03*
X1458759Y952969D03*
X1462460D03*
X1455058Y965725D03*
X1466161D03*
X1455058Y959347D03*
X1462460D03*
X1466161D03*
X1458759D03*
X1464310Y962536D03*
Y968914D03*
X1460609D03*
Y962536D03*
X1468011Y968914D03*
Y962536D03*
X1456909Y968914D03*
Y962536D03*
X1462460Y965725D03*
X1458759D03*
X1460609Y981670D03*
X1455058Y978481D03*
X1466161D03*
X1455058Y972103D03*
X1462460D03*
X1466161D03*
X1458759D03*
X1464310Y975292D03*
X1458759Y984859D03*
X1466161D03*
X1468011Y981670D03*
X1460609Y975292D03*
X1468011D03*
X1456909D03*
X1462460Y978481D03*
X1458759D03*
X1464310Y981670D03*
X1456909D03*
X1462460Y984859D03*
X1455058D03*
X1458759Y997615D03*
X1466161D03*
X1460609Y988048D03*
Y994426D03*
X1458759Y991237D03*
X1466161D03*
X1460609Y1000804D03*
X1468011Y988048D03*
Y994426D03*
Y1000804D03*
X1464310Y988048D03*
Y994426D03*
X1456909Y988048D03*
Y994426D03*
X1462460Y997615D03*
Y991237D03*
X1455058Y997615D03*
Y991237D03*
X1456909Y1000804D03*
X1464310D03*
X1458759Y1003993D03*
X1466161D03*
Y1010371D03*
X1458759D03*
X1460609Y1007182D03*
X1468011D03*
X1464310D03*
X1456909D03*
X1462460Y1010371D03*
Y1003993D03*
X1455058Y1010371D03*
Y1003993D03*
X1463641Y1028055D03*
X1456239D03*
X1459940D03*
X1467342D03*
X1459940Y1040811D03*
X1458090Y1031244D03*
X1463641Y1034433D03*
X1456239D03*
X1465491Y1031244D03*
X1454389Y1037622D03*
X1467342Y1040811D03*
X1454389Y1044000D03*
X1461791Y1037622D03*
Y1044000D03*
X1458090Y1037622D03*
Y1044000D03*
X1465491Y1037622D03*
Y1044000D03*
X1463641Y1040811D03*
X1456239D03*
X1459940Y1034433D03*
X1461791Y1031244D03*
X1454389D03*
X1467342Y1034433D03*
X1459940Y1047189D03*
X1456239Y1059945D03*
X1459940Y1053567D03*
X1454389Y1056756D03*
X1461791D03*
X1454389Y1050378D03*
X1461791D03*
X1467342Y1047189D03*
Y1059945D03*
Y1053567D03*
X1463641Y1047189D03*
X1456239D03*
X1465491Y1050378D03*
X1456239Y1053567D03*
X1463641D03*
X1458090Y1056756D03*
X1463641Y1059945D03*
X1465491Y1056756D03*
X1458090Y1050378D03*
X1459940Y1059945D03*
X1465491Y1063134D03*
X1454389D03*
X1456239Y1072701D03*
X1459940Y1066323D03*
X1463641D03*
X1465491Y1069512D03*
X1454389D03*
X1456239Y1066323D03*
X1467342Y1072701D03*
Y1066323D03*
X1461791Y1063134D03*
Y1069512D03*
X1458090Y1063134D03*
Y1069512D03*
X1463641Y1072701D03*
X1459940D03*
Y1079079D03*
X1463641D03*
X1456239D03*
X1465491Y1075890D03*
X1454389D03*
X1465491Y1088646D03*
X1454389D03*
X1456239Y1085457D03*
X1465491Y1082268D03*
X1454389D03*
X1467342Y1079079D03*
Y1085457D03*
X1461791Y1075890D03*
X1458090D03*
X1463641Y1085457D03*
X1459940D03*
X1461791Y1082268D03*
Y1088646D03*
X1458090Y1082268D03*
Y1088646D03*
X1456239Y1098213D03*
X1467342Y1091835D03*
Y1104591D03*
Y1098213D03*
X1463641Y1091835D03*
X1459940D03*
X1456239D03*
X1465491Y1095024D03*
X1454389D03*
X1459940Y1104591D03*
X1463641D03*
X1456239D03*
X1463641Y1098213D03*
X1459940D03*
X1454389Y1101402D03*
X1461791D03*
X1458090D03*
X1465491D03*
X1461791Y1095024D03*
X1458090D03*
X1465491Y1107780D03*
X1454389D03*
X1463641Y1110969D03*
X1459940D03*
X1456239D03*
Y1117347D03*
X1454389Y1114158D03*
X1465491D03*
X1467342Y1110969D03*
Y1117347D03*
X1458090Y1114158D03*
Y1107780D03*
X1461791Y1114158D03*
Y1107780D03*
X1459940Y1117347D03*
X1463641D03*
X1454389Y1120536D03*
X1465491Y1126914D03*
X1454389D03*
X1459940Y1123725D03*
X1463641D03*
X1465491Y1120536D03*
X1456239Y1123725D03*
X1454389Y1133292D03*
X1456239Y1130102D03*
X1465491Y1133292D03*
X1467342Y1123725D03*
Y1130102D03*
X1458090Y1133292D03*
X1461791D03*
X1458090Y1126914D03*
Y1120536D03*
X1461791Y1126914D03*
Y1120536D03*
X1459940Y1130102D03*
X1463641D03*
X1456239Y1142858D03*
X1465491Y1139669D03*
X1459940Y1136480D03*
X1463641D03*
X1454389Y1139669D03*
X1456239Y1136480D03*
X1465491Y1146047D03*
X1459940Y1149236D03*
X1463641D03*
X1454389Y1146047D03*
X1467342Y1136480D03*
Y1142858D03*
X1458090Y1146047D03*
Y1139669D03*
X1461791Y1146047D03*
Y1139669D03*
X1463641Y1142858D03*
X1459940D03*
X1456239Y1149236D03*
X1467342D03*
X1454389Y1158803D03*
X1467342Y1155614D03*
X1465491Y1158803D03*
X1463641Y1155614D03*
X1461791Y1152425D03*
X1458090Y1158803D03*
X1459940Y1155614D03*
X1465491Y1152425D03*
X1454389D03*
X1467342Y1161992D03*
X1463641D03*
X1456239D03*
X1461791Y1165181D03*
X1458090Y1152425D03*
X1461791Y1158803D03*
X1456239Y1155614D03*
X1454994Y1540512D03*
X1458907Y1547243D03*
X1460301Y1540295D03*
X1463631Y1547243D03*
X1465026Y1540295D03*
X1468356Y1547243D03*
X1457735Y1552195D03*
X1461777Y1552698D03*
X1460202Y1549970D03*
X1464926D03*
X1466501Y1552698D03*
X1468026Y1554453D03*
X1463301D03*
X1458577D03*
X1468577Y1561853D03*
X1463852D03*
X1459128D03*
X1460202Y1563608D03*
X1464926D03*
X1461777Y1566336D03*
X1466501D03*
X1458577Y1556953D03*
X1468577Y1559353D03*
X1463852D03*
X1459128D03*
X1463301Y1556953D03*
X1468026D03*
X1455098Y1575425D03*
X1468076Y1569063D03*
X1463351D03*
X1460301Y1575641D03*
X1458626Y1569063D03*
X1465026Y1575641D03*
X1455098Y1577625D03*
X1458013Y1625380D03*
X1465813D03*
X1464053Y1635380D03*
Y1647292D03*
X1465813Y1657292D03*
X1458013D03*
X1475413Y879623D03*
X1479113Y873245D03*
X1469861Y876434D03*
X1479113Y879623D03*
X1482814D03*
X1473562Y876434D03*
X1477263D03*
X1471712Y873245D03*
X1475413D03*
X1480964Y876434D03*
X1471712Y892379D03*
X1482814Y886001D03*
X1480964Y882812D03*
X1469861D03*
X1479113Y886001D03*
X1482814Y892379D03*
X1469861Y889190D03*
X1473562D03*
X1475413Y892379D03*
X1477263Y895568D03*
X1480964Y889190D03*
X1479113Y892379D03*
X1480964Y895568D03*
X1475413Y886001D03*
X1477263Y889190D03*
X1473562Y895568D03*
X1469861D03*
X1471712Y886001D03*
Y911512D03*
Y898757D03*
Y905134D03*
X1482814Y898757D03*
X1469861Y901946D03*
X1475413Y898757D03*
X1473562Y901946D03*
X1482814Y905134D03*
Y911512D03*
X1477263Y908324D03*
X1475413Y911512D03*
Y905134D03*
X1479113Y911512D03*
X1480964Y901946D03*
X1479113Y905134D03*
X1480964Y908324D03*
X1479113Y898757D03*
X1469861Y908324D03*
X1473562D03*
X1477263Y901946D03*
X1482814Y917890D03*
X1469861Y914701D03*
X1473562D03*
X1475413Y917890D03*
Y924268D03*
X1482814D03*
X1477263Y921079D03*
X1480964D03*
X1479113Y924268D03*
X1480964Y914701D03*
X1479113Y917890D03*
X1471712Y924268D03*
Y917890D03*
X1473562Y921079D03*
X1469861D03*
X1477263Y914701D03*
X1469861Y933835D03*
X1473562D03*
X1482814Y930646D03*
X1475413D03*
X1477263Y933835D03*
X1473562Y927457D03*
X1469861D03*
X1482814Y937024D03*
X1477263Y940213D03*
X1480964Y927457D03*
X1479113Y930646D03*
X1480964Y940213D03*
Y933835D03*
X1479113Y937024D03*
X1471712Y930646D03*
X1469861Y940213D03*
X1473562D03*
X1477263Y927457D03*
X1475413Y937024D03*
X1471712D03*
Y949780D03*
Y943402D03*
Y956158D03*
X1482814Y943402D03*
Y949780D03*
X1475413Y943402D03*
X1469861Y946591D03*
X1473562D03*
X1475413Y949780D03*
X1482814Y956158D03*
X1477263Y952969D03*
X1475413Y956158D03*
X1479113Y943402D03*
X1480964Y946591D03*
X1479113Y949780D03*
X1480964Y952969D03*
X1479113Y956158D03*
X1473562Y952969D03*
X1469861D03*
X1477263Y946591D03*
X1482814Y962536D03*
X1469861Y959347D03*
X1473562D03*
X1475413Y962536D03*
X1477263Y965725D03*
X1482814Y968914D03*
X1475413D03*
X1480964Y965725D03*
X1479113Y968914D03*
X1480964Y959347D03*
X1479113Y962536D03*
X1471712Y968914D03*
Y962536D03*
X1473562Y965725D03*
X1469861D03*
X1477263Y959347D03*
X1482814Y975292D03*
Y981670D03*
X1469861Y972103D03*
X1473562D03*
X1475413Y975292D03*
X1477263Y978481D03*
X1475413Y981670D03*
X1473562Y984859D03*
X1480964D03*
Y978481D03*
X1479113Y981670D03*
X1480964Y972103D03*
X1479113Y975292D03*
X1471712D03*
Y981670D03*
X1473562Y978481D03*
X1469861D03*
Y984859D03*
X1477263Y972103D03*
Y984859D03*
X1475413Y1000804D03*
X1482814Y988048D03*
Y994426D03*
X1473562Y991237D03*
Y997615D03*
X1475413Y988048D03*
Y994426D03*
X1482814Y1000804D03*
X1479113Y988048D03*
X1480964Y997615D03*
X1479113Y1000804D03*
X1480964Y991237D03*
X1477263D03*
X1469861Y997615D03*
Y991237D03*
X1471712Y988048D03*
Y994426D03*
X1477263Y997615D03*
X1471712Y1000804D03*
X1479113Y994426D03*
X1482814Y1007182D03*
X1473562Y1003993D03*
Y1010371D03*
X1475413Y1007182D03*
X1480964Y1003993D03*
X1479113Y1007182D03*
X1471712D03*
X1477263Y1010371D03*
Y1003993D03*
X1469861Y1010371D03*
Y1003993D03*
X1480964Y1010371D03*
X1478444Y1028055D03*
X1471043D03*
X1474743D03*
X1482145D03*
X1472893Y1031244D03*
X1469192Y1037622D03*
Y1044000D03*
X1478444Y1034433D03*
X1476594Y1037622D03*
X1474743Y1040811D03*
X1476594Y1044000D03*
X1471043Y1034433D03*
X1480295Y1031244D03*
X1482145Y1034433D03*
X1480295Y1037622D03*
X1482145Y1040811D03*
X1480295Y1044000D03*
X1478444Y1040811D03*
X1471043D03*
X1472893Y1037622D03*
Y1044000D03*
X1474743Y1034433D03*
X1476594Y1031244D03*
X1469192D03*
X1474743Y1047189D03*
X1480295Y1056756D03*
X1482145Y1059945D03*
X1469192Y1050378D03*
X1476594D03*
Y1056756D03*
X1474743Y1053567D03*
X1478444Y1059945D03*
X1469192Y1056756D03*
X1480295Y1050378D03*
X1482145Y1047189D03*
X1472893Y1050378D03*
X1478444Y1047189D03*
X1471043D03*
X1478444Y1053567D03*
X1472893Y1056756D03*
X1471043Y1053567D03*
X1474743Y1059945D03*
X1471043D03*
X1482145Y1053567D03*
X1476594Y1063134D03*
X1478444Y1072701D03*
X1476594Y1069512D03*
X1474743Y1066323D03*
X1471043D03*
X1480295Y1063134D03*
X1482145Y1066323D03*
X1480295Y1069512D03*
X1482145Y1072701D03*
X1472893Y1063134D03*
Y1069512D03*
X1469192Y1063134D03*
Y1069512D03*
X1478444Y1066323D03*
X1471043Y1072701D03*
X1474743D03*
X1476594Y1075890D03*
X1474743Y1079079D03*
X1471043D03*
X1478444Y1085457D03*
X1476594Y1088646D03*
Y1082268D03*
X1480295Y1075890D03*
X1482145Y1079079D03*
X1480295Y1082268D03*
X1482145Y1085457D03*
X1480295Y1088646D03*
X1472893Y1075890D03*
X1469192D03*
X1478444Y1079079D03*
X1474743Y1085457D03*
X1471043D03*
X1472893Y1082268D03*
Y1088646D03*
X1469192Y1082268D03*
Y1088646D03*
X1474743Y1091835D03*
X1471043D03*
X1476594Y1095024D03*
X1478444Y1098213D03*
Y1104591D03*
X1474743D03*
X1471043D03*
X1472893Y1101402D03*
X1482145Y1104591D03*
X1480295Y1095024D03*
X1482145Y1098213D03*
X1480295Y1101402D03*
X1482145Y1091835D03*
X1478444D03*
X1476594Y1101402D03*
X1474743Y1098213D03*
X1471043D03*
X1469192Y1101402D03*
X1472893Y1095024D03*
X1469192D03*
X1476594Y1107780D03*
X1474743Y1110969D03*
X1471043D03*
X1476594Y1114158D03*
X1478444Y1117347D03*
X1480295Y1114158D03*
X1482145Y1117347D03*
X1480295Y1107780D03*
X1482145Y1110969D03*
X1469192Y1107780D03*
Y1114158D03*
X1472893Y1107780D03*
Y1114158D03*
X1478444Y1110969D03*
X1474743Y1117347D03*
X1471043D03*
X1476594Y1126914D03*
Y1120536D03*
X1474743Y1123725D03*
X1471043D03*
X1478444Y1130102D03*
X1476594Y1133292D03*
X1480295Y1120536D03*
X1482145Y1123725D03*
X1480295Y1133292D03*
Y1126914D03*
X1482145Y1130102D03*
X1469192Y1120536D03*
X1472893D03*
X1478444Y1123725D03*
X1474743Y1130102D03*
X1471043D03*
X1469192Y1133292D03*
Y1126914D03*
X1472893Y1133292D03*
Y1126914D03*
X1476594Y1139669D03*
X1474743Y1136480D03*
X1471043D03*
X1478444Y1142858D03*
X1476594Y1146047D03*
X1474743Y1149236D03*
X1471043D03*
X1482145Y1136480D03*
X1480295Y1139669D03*
X1482145Y1142858D03*
X1480295Y1146047D03*
X1482145Y1149236D03*
X1478444Y1136480D03*
X1474743Y1142858D03*
X1471043D03*
X1478444Y1149236D03*
X1469192Y1146047D03*
Y1139669D03*
X1472893Y1146047D03*
Y1139669D03*
Y1158803D03*
X1471043Y1155614D03*
Y1161992D03*
X1469192Y1152425D03*
X1474743Y1155614D03*
X1478444D03*
X1472893Y1152425D03*
X1480295Y1158803D03*
X1469192D03*
X1480295Y1152425D03*
X1482145Y1155614D03*
X1476594Y1152425D03*
X1478444Y1161992D03*
X1474743D03*
X1476594Y1158803D03*
X1476778Y1165778D03*
X1469750Y1540295D03*
X1473080Y1547243D03*
X1474474Y1540295D03*
X1477805Y1547243D03*
X1479199Y1540295D03*
X1482529Y1547243D03*
X1483923Y1540295D03*
X1479099Y1549970D03*
X1483824D03*
X1480674Y1552698D03*
X1469651Y1549970D03*
X1474375D03*
X1471225Y1552698D03*
X1475950D03*
X1482199Y1554453D03*
X1477474D03*
X1472750D03*
X1482750Y1561853D03*
X1478025D03*
X1473301D03*
X1469651Y1563608D03*
X1474375D03*
X1479099D03*
X1483824D03*
X1471225Y1566336D03*
X1475950D03*
X1480674D03*
X1482199Y1556953D03*
X1482750Y1559353D03*
X1472750Y1556953D03*
X1473301Y1559353D03*
X1477474Y1556953D03*
X1478025Y1559353D03*
X1482249Y1569063D03*
X1477525D03*
X1469750Y1575641D03*
X1483923D03*
X1474474D03*
X1472800Y1569063D03*
X1479199Y1575641D03*
X1470073Y1625380D03*
X1482133D03*
X1477873D03*
X1471833Y1635380D03*
X1483893D03*
X1476113D03*
X1471833Y1647292D03*
X1483893D03*
X1476113D03*
X1470073Y1657292D03*
X1477873D03*
X1482133D03*
X1486515Y879623D03*
X1492066Y876434D03*
X1490216Y879623D03*
X1484665Y876434D03*
X1488365D03*
X1490216Y886001D03*
X1484665Y882812D03*
X1488365D03*
X1495767D03*
X1493917Y886001D03*
X1488365Y889190D03*
X1495767D03*
X1490216Y892379D03*
X1495767Y895568D03*
X1486515Y886001D03*
X1484665Y889190D03*
Y895568D03*
X1486515Y892379D03*
X1497617Y886001D03*
X1492066Y889190D03*
X1493917Y892379D03*
X1492066Y895568D03*
X1497617Y892379D03*
X1488365Y895568D03*
X1492066Y882812D03*
X1490216Y898757D03*
X1488365Y901946D03*
X1495767D03*
X1488365Y908324D03*
X1490216Y911512D03*
X1495767Y908324D03*
X1484665D03*
X1486515Y898757D03*
X1484665Y901946D03*
X1486515Y905134D03*
Y911512D03*
X1493917D03*
X1497617Y898757D03*
X1492066Y901946D03*
X1493917Y905134D03*
X1497617D03*
X1492066Y908324D03*
X1497617Y911512D03*
X1493917Y898757D03*
X1490216Y905134D03*
X1495767Y914701D03*
X1490216Y917890D03*
X1488365Y921079D03*
X1495767D03*
X1486515Y917890D03*
X1484665Y921079D03*
X1486515Y924268D03*
X1484665Y914701D03*
X1497617Y917890D03*
X1492066Y921079D03*
X1493917Y924268D03*
X1497617D03*
X1492066Y914701D03*
X1493917Y917890D03*
X1488365Y914701D03*
X1490216Y924268D03*
Y930646D03*
X1495767Y933835D03*
X1488365Y927457D03*
X1495767D03*
X1488365Y940213D03*
X1495767D03*
X1490216Y937024D03*
X1484665Y927457D03*
X1486515Y937024D03*
X1484665Y940213D03*
Y933835D03*
X1486515Y930646D03*
X1492066Y927457D03*
X1493917Y930646D03*
X1497617Y937024D03*
X1492066Y940213D03*
Y933835D03*
X1497617Y930646D03*
X1493917Y937024D03*
X1488365Y933835D03*
Y946591D03*
X1490216Y949780D03*
X1495767Y946591D03*
Y952969D03*
X1490216Y956158D03*
X1486515Y943402D03*
X1484665Y946591D03*
X1486515Y956158D03*
X1484665Y952969D03*
X1486515Y949780D03*
X1493917Y943402D03*
X1497617D03*
X1492066Y946591D03*
X1493917Y949780D03*
X1497617Y956158D03*
X1492066Y952969D03*
X1497617Y949780D03*
X1493917Y956158D03*
X1490216Y943402D03*
X1488365Y952969D03*
Y965725D03*
X1495767Y959347D03*
Y965725D03*
X1488365Y959347D03*
X1490216Y968914D03*
X1486515Y962536D03*
X1484665Y965725D03*
Y959347D03*
X1486515Y968914D03*
X1497617Y962536D03*
X1492066Y965725D03*
X1493917Y968914D03*
X1492066Y959347D03*
X1493917Y962536D03*
X1497617Y968914D03*
X1490216Y962536D03*
X1495767Y972103D03*
X1490216Y975292D03*
X1486515Y981670D03*
X1488365Y978481D03*
X1495767D03*
X1497617Y981670D03*
X1484665Y984859D03*
X1488365D03*
X1495767D03*
X1486515Y975292D03*
X1484665Y978481D03*
Y972103D03*
X1492066Y984859D03*
X1497617Y975292D03*
X1492066Y978481D03*
X1493917Y981670D03*
X1492066Y972103D03*
X1493917Y975292D03*
X1490216Y981670D03*
X1488365Y972103D03*
X1490216Y988048D03*
X1488365Y997615D03*
X1490216Y994426D03*
X1495767Y991237D03*
Y997615D03*
X1486515Y994426D03*
X1484665Y997615D03*
X1486515Y1000804D03*
Y988048D03*
X1493917D03*
X1497617Y994426D03*
X1492066Y997615D03*
X1493917Y1000804D03*
X1497617D03*
Y988048D03*
X1492066Y991237D03*
X1488365D03*
X1490216Y1000804D03*
X1493917Y994426D03*
X1484665Y991237D03*
X1488365Y1003993D03*
X1490216Y1007182D03*
X1495767Y1003993D03*
Y1010371D03*
X1484665D03*
X1486515Y1007182D03*
X1484665Y1003993D03*
X1497617Y1007182D03*
X1492066Y1003993D03*
X1493917Y1007182D03*
X1488365Y1010371D03*
X1492066D03*
X1489547Y1028055D03*
X1496948D03*
X1493247D03*
X1485846D03*
X1483995Y1031244D03*
Y1037622D03*
Y1044000D03*
X1491397Y1031244D03*
X1489547Y1040811D03*
Y1034433D03*
X1491397Y1044000D03*
X1496948Y1034433D03*
Y1040811D03*
X1485846Y1034433D03*
X1487696Y1037622D03*
X1485846Y1040811D03*
X1495098Y1031244D03*
X1493247Y1034433D03*
X1498799Y1037622D03*
X1495098D03*
X1493247Y1040811D03*
X1495098Y1044000D03*
X1491397Y1037622D03*
X1498798Y1044000D03*
Y1031244D03*
X1487696Y1044000D03*
Y1031244D03*
X1496948Y1047189D03*
X1483995Y1050378D03*
Y1056756D03*
X1489547Y1053567D03*
X1495098Y1056756D03*
X1491397Y1050378D03*
X1489547Y1059945D03*
X1493247D03*
X1496948Y1053567D03*
Y1059945D03*
X1485846D03*
X1487696Y1050378D03*
X1485846Y1053567D03*
X1495098Y1050378D03*
X1493247Y1047189D03*
X1498799Y1050378D03*
X1489547Y1047189D03*
X1491397Y1056756D03*
X1498798D03*
X1493247Y1053567D03*
X1487696Y1056756D03*
X1485846Y1047189D03*
X1483995Y1063134D03*
X1491397D03*
X1483995Y1069512D03*
X1489547Y1072701D03*
X1491397Y1069512D03*
X1496948Y1072701D03*
Y1066323D03*
X1485846Y1072701D03*
X1487696Y1063134D03*
Y1069512D03*
X1485846Y1066323D03*
X1495098Y1063134D03*
X1498799D03*
X1493247Y1066323D03*
X1495098Y1069512D03*
X1498799D03*
X1493247Y1072701D03*
X1489547Y1066323D03*
X1483995Y1075890D03*
X1489547Y1079079D03*
X1496948D03*
X1483995Y1088646D03*
X1491397D03*
X1496948Y1085457D03*
X1483995Y1082268D03*
X1491397D03*
X1487696Y1075890D03*
X1485846Y1079079D03*
X1487696Y1082268D03*
Y1088646D03*
X1485846Y1085457D03*
X1495098Y1075890D03*
X1498799D03*
X1493247Y1079079D03*
X1495098Y1082268D03*
X1498799D03*
X1493247Y1085457D03*
X1498799Y1088646D03*
X1495098D03*
X1491397Y1075890D03*
X1489547Y1085457D03*
Y1091835D03*
X1496948D03*
X1483995Y1095024D03*
Y1101402D03*
X1489547Y1098213D03*
X1491397Y1101402D03*
X1496948Y1098213D03*
Y1104591D03*
X1487696Y1101402D03*
X1485846Y1091835D03*
X1487696Y1095024D03*
X1485846Y1098213D03*
Y1104591D03*
X1498799Y1101402D03*
X1493247Y1104591D03*
X1495098Y1095024D03*
X1498799D03*
X1493247Y1098213D03*
X1495098Y1101402D03*
X1493247Y1091835D03*
X1491397Y1095024D03*
X1489547Y1104591D03*
Y1110969D03*
X1496948D03*
X1483995Y1107780D03*
X1491397D03*
X1483995Y1114158D03*
X1489547Y1117347D03*
X1496948D03*
X1485846Y1110969D03*
X1487696Y1114158D03*
X1485846Y1117347D03*
X1487696Y1107780D03*
X1495098Y1114158D03*
X1498799D03*
X1493247Y1117347D03*
X1498799Y1107780D03*
X1495098D03*
X1493247Y1110969D03*
X1491397Y1114158D03*
X1483995Y1120536D03*
X1491397D03*
X1496948Y1123725D03*
X1483995Y1126914D03*
X1491397D03*
X1483995Y1133292D03*
X1496948Y1130102D03*
X1489547Y1130103D03*
X1487696Y1120536D03*
X1485846Y1130102D03*
X1487696Y1133292D03*
Y1126914D03*
X1485846Y1123725D03*
X1495098Y1120536D03*
X1498799D03*
X1493247Y1123725D03*
X1495098Y1133292D03*
X1498799D03*
Y1126914D03*
X1495098D03*
X1493247Y1130102D03*
X1491397Y1133292D03*
X1489547Y1123725D03*
X1483995Y1139669D03*
X1489547Y1136480D03*
X1491397Y1139669D03*
X1496948Y1136480D03*
Y1142858D03*
X1483995Y1146047D03*
X1489547Y1149236D03*
X1491397Y1146047D03*
X1496948Y1149236D03*
X1485846Y1136480D03*
X1487696Y1139669D03*
X1485846Y1149236D03*
X1487696Y1146047D03*
X1485846Y1142858D03*
X1493247Y1136480D03*
X1495098Y1139669D03*
X1498799D03*
X1493247Y1142858D03*
X1498799Y1146047D03*
X1495098D03*
X1493247Y1149236D03*
X1489547Y1142858D03*
X1487696Y1165181D03*
X1498799Y1158803D03*
X1483995Y1152425D03*
X1485846Y1155614D03*
X1489547D03*
X1493247D03*
X1496948D03*
X1483995Y1158803D03*
X1491397D03*
X1493247Y1161992D03*
X1487696Y1152425D03*
X1495098D03*
X1498799D03*
X1491397D03*
X1489547Y1161992D03*
X1485846D03*
X1487696Y1158803D03*
X1495111Y1165289D03*
X1491410D03*
X1498812D03*
X1488648Y1540295D03*
X1487253Y1547243D03*
X1491978D03*
X1493372Y1540295D03*
X1496702Y1547243D03*
X1498096Y1540295D03*
X1497997Y1549970D03*
X1488548D03*
X1493273D03*
X1485399Y1552698D03*
X1490123D03*
X1494847D03*
X1496372Y1554453D03*
X1491648D03*
X1486923D03*
X1496923Y1561853D03*
X1492199D03*
X1487474D03*
X1488548Y1563608D03*
X1493273D03*
X1497997D03*
X1485399Y1566336D03*
X1490123D03*
X1494847D03*
X1496372Y1556953D03*
X1491648D03*
X1496923Y1559353D03*
X1492199D03*
X1486923Y1556953D03*
X1487474Y1559353D03*
X1491698Y1569063D03*
X1488648Y1575641D03*
X1493372D03*
X1498096D03*
X1496422Y1569063D03*
X1486973D03*
X1489933Y1625380D03*
X1494193D03*
X1495953Y1635380D03*
X1488173D03*
X1495953Y1647292D03*
X1488173D03*
X1494193Y1657292D03*
X1489933D03*
X1501318Y873245D03*
Y879623D03*
X1510570Y876434D03*
X1508720Y879623D03*
X1506869Y876434D03*
X1512421Y879623D03*
X1505019D03*
X1501318Y886001D03*
X1510570Y882812D03*
X1508720Y886001D03*
X1503169Y889190D03*
Y895568D03*
X1501318Y892379D03*
X1508720D03*
X1499468Y882812D03*
X1505019Y886001D03*
X1512421D03*
X1506869Y889190D03*
X1510570D03*
X1505019Y892379D03*
X1510570Y895568D03*
X1506869D03*
X1512421Y892379D03*
X1499468Y889190D03*
Y895568D03*
X1506869Y882812D03*
X1501318Y898757D03*
X1508720D03*
X1503169Y901946D03*
X1501318Y905134D03*
X1508720D03*
X1501318Y911512D03*
X1508720D03*
X1503169Y908323D03*
X1510570Y908324D03*
X1505019Y911512D03*
X1512421Y898757D03*
X1506869Y901946D03*
X1510570D03*
X1505019Y905134D03*
X1512421D03*
X1506869Y908324D03*
X1512421Y911512D03*
X1505019Y898757D03*
X1499468Y908324D03*
Y901946D03*
X1503169Y914701D03*
X1501318Y917890D03*
X1508720D03*
X1503169Y921079D03*
X1501318Y924268D03*
X1508720D03*
X1512421Y917890D03*
X1506869Y921079D03*
X1510570D03*
X1505019Y924268D03*
X1512421D03*
X1510570Y914701D03*
X1506869D03*
X1505019Y917890D03*
X1499468Y921079D03*
Y914701D03*
X1503169Y927457D03*
X1501318Y930646D03*
X1503169Y933835D03*
X1508720Y930646D03*
Y937024D03*
X1503169Y940213D03*
X1501318Y937024D03*
X1506869Y927457D03*
X1510570D03*
X1505019Y930646D03*
X1512421Y937024D03*
X1506869Y940213D03*
X1510570D03*
Y933835D03*
X1506869D03*
X1512421Y930646D03*
X1505019Y937024D03*
X1499468Y927457D03*
Y940213D03*
Y933835D03*
X1501318Y943402D03*
X1508720D03*
X1503169Y946591D03*
X1501318Y949780D03*
X1508720D03*
X1503169Y952969D03*
X1501318Y956158D03*
X1508720D03*
X1505019Y943402D03*
X1512421D03*
X1506869Y946591D03*
X1510570D03*
X1505019Y949780D03*
X1512421Y956158D03*
X1510570Y952969D03*
X1506869D03*
X1512421Y949780D03*
X1505019Y956158D03*
X1499468Y946591D03*
Y952969D03*
X1503169Y959347D03*
Y965725D03*
X1501318Y962536D03*
X1508720D03*
X1501318Y968914D03*
X1508720D03*
X1512421Y962536D03*
X1506869Y965725D03*
X1510570D03*
X1505019Y968914D03*
X1506869Y959347D03*
X1510570D03*
X1505019Y962536D03*
X1512421Y968914D03*
X1499468Y965725D03*
Y959347D03*
X1510570Y984859D03*
X1512421Y981670D03*
X1503169Y972103D03*
X1501318Y975292D03*
X1503169Y978481D03*
X1501318Y981670D03*
X1508720Y975292D03*
Y981670D03*
X1499468Y984859D03*
X1503169D03*
X1506869D03*
X1512421Y975292D03*
X1506869Y978481D03*
X1510570D03*
X1505019Y981670D03*
X1510570Y972103D03*
X1506869D03*
X1505019Y975292D03*
X1499468Y978481D03*
Y972103D03*
X1503169Y991237D03*
X1501318Y988048D03*
X1503169Y997615D03*
X1501318Y994426D03*
X1508720Y988048D03*
Y994426D03*
X1501318Y1000804D03*
X1508720D03*
X1505019Y988048D03*
X1512421Y994426D03*
X1510570Y997615D03*
X1506869D03*
X1505019Y1000804D03*
X1512421D03*
Y988048D03*
X1506869Y991237D03*
X1499468Y997615D03*
Y991237D03*
X1505019Y994426D03*
X1510570Y991237D03*
X1501318Y1007182D03*
X1503169Y1010371D03*
X1508720Y1007182D03*
X1503169Y1003993D03*
X1510570Y1010371D03*
X1512421Y1007182D03*
X1510570Y1003993D03*
X1506869D03*
X1505019Y1007182D03*
X1499468Y1010371D03*
Y1003993D03*
X1506869Y1010371D03*
X1504350Y1028055D03*
X1508050D03*
X1500649D03*
X1511751D03*
X1502499Y1031244D03*
X1509901D03*
X1504350Y1040811D03*
X1502499Y1037622D03*
X1504350Y1034433D03*
X1502499Y1044000D03*
X1509901Y1037622D03*
Y1044000D03*
X1506200Y1031244D03*
X1508050Y1034433D03*
X1511751D03*
X1513602Y1037622D03*
X1506200D03*
X1508050Y1040811D03*
X1511751D03*
X1506200Y1044000D03*
X1500649Y1034433D03*
Y1040811D03*
X1513602Y1044000D03*
Y1031244D03*
X1504350Y1047189D03*
Y1053567D03*
X1502499Y1050378D03*
X1509901Y1056756D03*
Y1050378D03*
X1504350Y1059945D03*
X1508050D03*
X1506200Y1056756D03*
X1502499D03*
X1506200Y1050378D03*
X1511751Y1059945D03*
X1508050Y1047189D03*
X1513602Y1050378D03*
X1511751Y1053567D03*
X1500649Y1059945D03*
Y1053567D03*
Y1047189D03*
X1513602Y1056756D03*
X1511751Y1047189D03*
X1508050Y1053567D03*
X1502499Y1063134D03*
X1509901D03*
X1502499Y1069512D03*
X1504350Y1072701D03*
Y1066323D03*
X1509901Y1069512D03*
X1511751Y1072701D03*
X1506200Y1063134D03*
X1513602D03*
X1508050Y1066323D03*
X1506200Y1069512D03*
X1513602D03*
X1508050Y1072701D03*
X1511751Y1066323D03*
X1500649Y1072701D03*
Y1066323D03*
X1502499Y1075890D03*
X1509901D03*
X1504350Y1079079D03*
Y1085457D03*
X1502499Y1088646D03*
X1509901D03*
X1502499Y1082268D03*
X1509901D03*
X1506200Y1075890D03*
X1513602D03*
X1508050Y1079079D03*
X1511751D03*
X1506200Y1082268D03*
X1513602D03*
X1508050Y1085457D03*
X1513602Y1088646D03*
X1506200D03*
X1511751Y1085457D03*
X1500649Y1079079D03*
Y1085457D03*
X1504350Y1091835D03*
X1502499Y1095024D03*
X1509901D03*
X1504350Y1098213D03*
X1502499Y1101402D03*
X1509901D03*
X1504350Y1104591D03*
X1513602Y1101402D03*
X1508050Y1104591D03*
X1511751Y1091835D03*
X1506200Y1095024D03*
X1513602D03*
X1508050Y1098213D03*
X1511751D03*
X1506200Y1101402D03*
X1511751Y1104591D03*
X1508050Y1091835D03*
X1500649D03*
Y1098213D03*
Y1104591D03*
X1502499Y1107780D03*
X1509901D03*
X1504350Y1110969D03*
X1509901Y1114158D03*
X1504350Y1117347D03*
X1502499Y1114158D03*
X1511751Y1110969D03*
X1506200Y1114158D03*
X1513602D03*
X1508050Y1117347D03*
X1511751D03*
X1513602Y1107780D03*
X1506200D03*
X1508050Y1110969D03*
X1500649D03*
Y1117347D03*
X1502499Y1120536D03*
X1504350Y1123725D03*
X1509901Y1120536D03*
X1502499Y1126914D03*
X1509901D03*
Y1133292D03*
X1502499D03*
X1504350Y1130103D03*
X1506200Y1120536D03*
X1513602D03*
X1508050Y1123725D03*
X1511751Y1130102D03*
X1506200Y1133292D03*
X1513602D03*
Y1126914D03*
X1506200D03*
X1511751Y1123725D03*
X1508050Y1130102D03*
X1500649D03*
Y1123725D03*
X1502499Y1139669D03*
X1504350Y1136480D03*
X1509901Y1139669D03*
X1504350Y1142858D03*
Y1149236D03*
X1502499Y1146047D03*
X1509901D03*
X1508050Y1136480D03*
X1511751D03*
X1506200Y1139669D03*
X1513602D03*
X1508050Y1142858D03*
X1511751Y1149236D03*
X1513602Y1146047D03*
X1506200D03*
X1511751Y1142858D03*
X1508050Y1149236D03*
X1500649Y1136480D03*
Y1149236D03*
Y1142858D03*
X1504350Y1155614D03*
X1502499Y1152425D03*
X1509901D03*
X1511751Y1155614D03*
X1502499Y1158803D03*
X1506200D03*
X1509901D03*
X1506200Y1152425D03*
X1513602D03*
X1508050Y1155614D03*
X1500649D03*
X1513602Y1158803D03*
X1500649Y1161992D03*
X1504350D03*
X1509914Y1165289D03*
X1506213D03*
X1502512D03*
X1502821Y1540295D03*
X1501427Y1547243D03*
X1506151D03*
X1507545Y1540295D03*
X1510875Y1547243D03*
X1512270Y1540295D03*
X1507446Y1549970D03*
X1512170D03*
X1502721D03*
X1509021Y1552698D03*
X1513745D03*
X1499572D03*
X1504296D03*
X1510545Y1554453D03*
X1505821D03*
X1501096D03*
X1511096Y1561853D03*
X1506372D03*
X1501647D03*
X1507446Y1563608D03*
X1512170D03*
X1502721D03*
X1509021Y1566336D03*
X1513745D03*
X1499572D03*
X1504296D03*
X1505821Y1556953D03*
X1506372Y1559353D03*
X1511096D03*
X1510545Y1556953D03*
X1501096D03*
X1501647Y1559353D03*
X1505871Y1569063D03*
X1501147D03*
X1507545Y1575641D03*
X1512270D03*
X1510595Y1569063D03*
X1502821Y1575641D03*
X1501993Y1625380D03*
X1506253D03*
X1508013Y1635380D03*
X1500233D03*
X1512293D03*
X1508013Y1647292D03*
X1500233D03*
X1512293D03*
X1501993Y1657292D03*
X1506253D03*
X1521673Y876434D03*
X1517972D03*
X1519822Y879623D03*
X1527224D03*
X1516121D03*
X1523523Y873245D03*
X1527224D03*
X1516121D03*
X1519822D03*
X1514271Y876434D03*
X1523523Y879623D03*
X1525373Y876434D03*
X1514271Y882812D03*
Y889190D03*
X1521673Y882812D03*
X1519822Y886001D03*
X1525373Y882812D03*
X1527224Y886001D03*
X1521673Y889190D03*
Y895568D03*
X1527224Y892379D03*
X1516121D03*
X1523523Y886001D03*
X1517972Y889190D03*
X1525373D03*
X1519822Y892379D03*
X1525373Y895568D03*
X1517972D03*
X1523523Y892379D03*
X1516121Y886001D03*
X1514271Y895568D03*
Y901946D03*
Y908324D03*
X1521673Y901946D03*
X1527224Y898757D03*
X1516121D03*
X1527224Y911512D03*
Y905134D03*
X1516121Y911512D03*
X1521673Y908323D03*
X1525373Y908324D03*
X1519822Y911512D03*
X1523523Y898757D03*
X1517972Y901946D03*
X1525373D03*
X1519822Y905134D03*
X1523523D03*
X1517972Y908324D03*
X1523523Y911512D03*
X1519822Y898757D03*
X1516121Y905134D03*
X1514271Y921079D03*
X1521673Y914701D03*
X1527224Y917890D03*
X1516121D03*
X1521673Y921079D03*
X1527224Y924268D03*
X1523523Y917890D03*
X1517972Y921079D03*
X1525373D03*
X1519822Y924268D03*
X1523523D03*
X1525373Y914701D03*
X1517972D03*
X1519822Y917890D03*
X1516121Y924268D03*
X1514271Y914701D03*
Y927457D03*
Y940213D03*
X1516121Y930646D03*
X1521673Y927457D03*
Y933835D03*
X1527224Y930646D03*
X1516121Y937024D03*
X1527224D03*
X1521673Y940213D03*
X1517972Y927457D03*
X1525373D03*
X1519822Y930646D03*
X1523523Y937024D03*
X1517972Y940213D03*
X1525373D03*
Y933835D03*
X1517972D03*
X1523523Y930646D03*
X1519822Y937024D03*
X1514271Y933835D03*
Y946591D03*
X1516121Y949780D03*
X1521673Y946591D03*
X1527224Y943402D03*
Y949780D03*
X1521673Y952969D03*
X1527224Y956158D03*
X1516121D03*
X1519822Y943402D03*
X1523523D03*
X1517972Y946591D03*
X1525373D03*
X1519822Y949780D03*
X1523523Y956158D03*
X1525373Y952969D03*
X1517972D03*
X1523523Y949780D03*
X1519822Y956158D03*
X1516121Y943402D03*
X1514271Y952969D03*
Y959347D03*
Y965725D03*
X1521673Y959347D03*
Y965725D03*
X1527224Y962536D03*
Y968914D03*
X1516121D03*
X1523523Y962536D03*
X1517972Y965725D03*
X1525373D03*
X1519822Y968914D03*
X1517972Y959347D03*
X1525373D03*
X1519822Y962536D03*
X1523523Y968914D03*
X1516121Y962536D03*
X1514271Y978481D03*
Y984859D03*
X1521673Y972103D03*
X1523523Y981670D03*
X1521673Y978481D03*
X1527224Y975292D03*
Y981670D03*
X1516121Y975292D03*
X1521673Y984859D03*
X1525373D03*
X1517972D03*
X1523523Y975292D03*
X1517972Y978481D03*
X1525373D03*
X1519822Y981670D03*
X1525373Y972103D03*
X1517972D03*
X1519822Y975292D03*
X1516121Y981670D03*
X1514271Y972103D03*
Y997615D03*
X1521673Y991237D03*
Y997615D03*
X1527224Y988048D03*
Y994426D03*
X1516121Y988048D03*
Y994426D03*
X1527224Y1000804D03*
X1519822Y988048D03*
X1523523Y994426D03*
X1525373Y997615D03*
X1517972D03*
X1519822Y1000804D03*
X1523523D03*
Y988048D03*
X1517972Y991237D03*
X1516121Y1000804D03*
X1514271Y991237D03*
X1519822Y994426D03*
X1525373Y991237D03*
X1514271Y1003993D03*
X1516121Y1007182D03*
X1521673Y1003993D03*
Y1010371D03*
X1527224Y1007182D03*
X1525373Y1010371D03*
X1523523Y1007182D03*
X1525373Y1003993D03*
X1517972D03*
X1519822Y1007182D03*
X1514271Y1010371D03*
X1517972D03*
X1522854Y1028055D03*
X1515452D03*
X1519153D03*
X1526554D03*
X1522854Y1034433D03*
Y1040811D03*
X1517302Y1044000D03*
X1528405Y1037622D03*
Y1044000D03*
X1515452Y1040811D03*
Y1034433D03*
X1517302Y1031244D03*
X1528405D03*
X1521003D03*
X1519153Y1034433D03*
X1526554D03*
X1524704Y1037622D03*
X1521003D03*
X1519153Y1040811D03*
X1526554D03*
X1521003Y1044000D03*
X1517302Y1037622D03*
X1524704Y1044000D03*
Y1031244D03*
X1515452Y1053567D03*
Y1059945D03*
X1522854Y1047189D03*
Y1053567D03*
X1521003Y1056756D03*
X1517302Y1050378D03*
X1522854Y1059945D03*
X1519153D03*
X1528405Y1050378D03*
Y1056756D03*
X1521003Y1050378D03*
X1526554Y1059945D03*
X1519153Y1047189D03*
X1524704Y1050378D03*
X1526554Y1053567D03*
X1517302Y1056756D03*
X1515452Y1047189D03*
X1524704Y1056756D03*
X1526554Y1047189D03*
X1519153Y1053567D03*
X1517302Y1063134D03*
X1528405D03*
X1515452Y1072701D03*
X1522854Y1066323D03*
Y1072701D03*
X1517302Y1069512D03*
X1528405D03*
X1526554Y1072701D03*
X1521003Y1063134D03*
X1524704D03*
X1519153Y1066323D03*
X1521003Y1069512D03*
X1524704D03*
X1519153Y1072701D03*
X1526554Y1066323D03*
X1515452D03*
X1528405Y1075890D03*
X1515452Y1079079D03*
X1522854D03*
X1517302Y1082268D03*
X1528405D03*
X1522854Y1085457D03*
X1517302Y1088646D03*
X1528405D03*
X1521003Y1075890D03*
X1524704D03*
X1519153Y1079079D03*
X1526554D03*
X1521003Y1082268D03*
X1524704D03*
X1519153Y1085457D03*
X1524704Y1088646D03*
X1521003D03*
X1526554Y1085457D03*
X1515452D03*
X1517302Y1075890D03*
X1515452Y1091835D03*
X1522854D03*
X1528405Y1095024D03*
X1522854Y1104591D03*
X1528405Y1101402D03*
X1515452Y1098213D03*
X1522854D03*
X1517302Y1101402D03*
X1524704D03*
X1519153Y1104591D03*
X1526554Y1091835D03*
X1521003Y1095024D03*
X1524704D03*
X1519153Y1098213D03*
X1526554D03*
X1521003Y1101402D03*
X1526554Y1104591D03*
X1519153Y1091835D03*
X1515452Y1104591D03*
X1517302Y1095024D03*
Y1107780D03*
X1528405D03*
X1522854Y1110969D03*
X1515452D03*
X1522854Y1117347D03*
X1528405Y1114158D03*
X1515452Y1117347D03*
X1526554Y1110969D03*
X1521003Y1114158D03*
X1524704D03*
X1519153Y1117347D03*
X1526554D03*
X1524704Y1107780D03*
X1521003D03*
X1519153Y1110969D03*
X1517302Y1114158D03*
X1522854Y1123725D03*
X1517302Y1120536D03*
X1528405D03*
X1517302Y1126914D03*
X1528405D03*
Y1133292D03*
X1515452Y1130102D03*
X1522854Y1130103D03*
X1521003Y1120536D03*
X1524704D03*
X1519153Y1123725D03*
X1526554Y1130102D03*
X1521003Y1133292D03*
X1524704D03*
Y1126914D03*
X1521003D03*
X1526554Y1123725D03*
X1519153Y1130102D03*
X1517302Y1133292D03*
X1515452Y1123725D03*
X1522854Y1142858D03*
Y1136480D03*
X1517302Y1139669D03*
X1528405D03*
X1515452Y1136480D03*
X1528405Y1146047D03*
X1515452Y1149236D03*
X1522854D03*
X1517302Y1146047D03*
X1519153Y1136480D03*
X1526554D03*
X1521003Y1139669D03*
X1524704D03*
X1519153Y1142858D03*
X1526554Y1149236D03*
X1524704Y1146047D03*
X1521003D03*
X1526554Y1142858D03*
X1519153Y1149236D03*
X1515452Y1142858D03*
X1528405Y1152425D03*
X1524704Y1158803D03*
X1528405D03*
X1515452Y1155614D03*
X1519153D03*
X1522854D03*
X1519153Y1161992D03*
X1521003Y1152425D03*
X1524704D03*
X1526554Y1155614D03*
X1517302Y1152425D03*
X1521003Y1158803D03*
X1515452Y1161992D03*
X1525049Y1547243D03*
X1521718Y1540295D03*
X1515600Y1547243D03*
X1516994Y1540295D03*
X1520324Y1547243D03*
X1526443Y1540295D03*
X1516895Y1549970D03*
X1521619D03*
X1526344D03*
X1518469Y1552698D03*
X1523194D03*
X1527918D03*
X1524719Y1554453D03*
X1519994D03*
X1515270D03*
X1525270Y1561853D03*
X1520545D03*
X1515821D03*
X1516895Y1563608D03*
X1521619D03*
X1526344D03*
X1518469Y1566336D03*
X1523194D03*
X1527918D03*
X1515821Y1559353D03*
X1515270Y1556953D03*
X1519994D03*
X1520545Y1559353D03*
X1525270D03*
X1524719Y1556953D03*
X1524769Y1569063D03*
X1515320D03*
X1516994Y1575641D03*
X1526443D03*
X1521718D03*
X1520044Y1569063D03*
X1514053Y1625380D03*
X1518313D03*
X1526113D03*
X1520073Y1635380D03*
X1524353D03*
X1520073Y1647292D03*
X1524353D03*
X1518313Y1657292D03*
X1514053D03*
X1526113D03*
X1529074Y876434D03*
X1538326Y879623D03*
X1542027D03*
X1540176Y876434D03*
X1530924Y873245D03*
X1534625Y879623D03*
X1536476Y876434D03*
X1530925Y886001D03*
X1529074Y889190D03*
Y895568D03*
X1540176Y882812D03*
X1536476D03*
X1534625Y886001D03*
X1540176Y889190D03*
X1542027Y892379D03*
X1534625D03*
X1538326Y886001D03*
X1532775Y889190D03*
X1536476D03*
X1530925Y892379D03*
X1536476Y895568D03*
X1532775D03*
X1538326Y892379D03*
X1540176Y895568D03*
X1542027Y886001D03*
X1532775Y882812D03*
X1529074Y901946D03*
Y908324D03*
X1542027Y898757D03*
X1540176Y901946D03*
X1534625Y898757D03*
X1540176Y908324D03*
X1542027Y911512D03*
X1534625Y905134D03*
Y911512D03*
X1536476Y908324D03*
X1530925Y911512D03*
X1538326Y898757D03*
X1532775Y901946D03*
X1536476D03*
X1530925Y905134D03*
X1538326D03*
X1532775Y908324D03*
X1538326Y911512D03*
X1530925Y898757D03*
X1542027Y905134D03*
X1529074Y914701D03*
Y921079D03*
X1542027Y917890D03*
X1534625D03*
X1540176Y921079D03*
X1534625Y924268D03*
X1538326Y917890D03*
X1532775Y921079D03*
X1536476D03*
X1530925Y924268D03*
X1538326D03*
X1536476Y914701D03*
X1532775D03*
X1530925Y917890D03*
X1542027Y924268D03*
X1540176Y914701D03*
X1529074Y927457D03*
Y933835D03*
Y940213D03*
X1540176Y927457D03*
X1542027Y930646D03*
X1534625D03*
X1542027Y937024D03*
X1540176Y940213D03*
X1534625Y937024D03*
X1532775Y927457D03*
X1536476D03*
X1530925Y930646D03*
X1538326Y937024D03*
X1532775Y940213D03*
X1536476D03*
Y933835D03*
X1532775D03*
X1538326Y930646D03*
X1530925Y937024D03*
X1540176Y933835D03*
X1529074Y946591D03*
Y952969D03*
X1540176Y946591D03*
X1542027Y949780D03*
X1534625Y943402D03*
Y949780D03*
Y956158D03*
X1542027D03*
X1530925Y943402D03*
X1538326D03*
X1532775Y946591D03*
X1536476D03*
X1530925Y949780D03*
X1538326Y956158D03*
X1536476Y952969D03*
X1532775D03*
X1538326Y949780D03*
X1530925Y956158D03*
X1540176Y952969D03*
X1542027Y943402D03*
X1529074Y959347D03*
Y965725D03*
X1540176Y959347D03*
Y965725D03*
X1534625Y962536D03*
X1542027Y968914D03*
X1534625D03*
X1538326Y962536D03*
X1532775Y965725D03*
X1536476D03*
X1530925Y968914D03*
X1532775Y959347D03*
X1536476D03*
X1530925Y962536D03*
X1538326Y968914D03*
X1542027Y962536D03*
X1538326Y981670D03*
X1542027Y975292D03*
X1540176Y978481D03*
X1534625Y975292D03*
Y981670D03*
X1536476Y984859D03*
X1540176D03*
X1529074Y972103D03*
Y978481D03*
Y984859D03*
X1532775D03*
X1538326Y975292D03*
X1532775Y978481D03*
X1536476D03*
X1530925Y981670D03*
X1536476Y972103D03*
X1532775D03*
X1530925Y975292D03*
X1542027Y981670D03*
X1540176Y972103D03*
X1529074Y991237D03*
Y997615D03*
X1542027Y988048D03*
X1540176Y997615D03*
X1542027Y994426D03*
X1534625Y988048D03*
Y994426D03*
Y1000804D03*
X1530925Y988048D03*
X1538326Y994426D03*
X1536476Y997615D03*
X1532775D03*
X1530925Y1000804D03*
X1538326D03*
Y988048D03*
X1532775Y991237D03*
X1542027Y1000804D03*
X1540176Y991237D03*
X1530924Y994426D03*
X1536476Y991237D03*
X1542027Y1007182D03*
X1534625D03*
X1529074Y1003993D03*
Y1010371D03*
X1540176Y1003993D03*
X1536476Y1010371D03*
X1538326Y1007182D03*
X1536476Y1003993D03*
X1532775D03*
X1530925Y1007182D03*
X1540176Y1010371D03*
X1532775D03*
X1530255Y1028055D03*
X1541358D03*
X1533956D03*
X1537657D03*
X1530255Y1034433D03*
Y1040811D03*
X1541357D03*
Y1034433D03*
X1543208Y1031244D03*
Y1044000D03*
X1535806Y1031244D03*
Y1037622D03*
Y1044000D03*
X1532106Y1031244D03*
X1533956Y1034433D03*
X1537657D03*
X1539507Y1037622D03*
X1532106D03*
X1533956Y1040811D03*
X1537657D03*
X1532106Y1044000D03*
X1543208Y1037622D03*
X1539507Y1044000D03*
Y1031244D03*
X1530255Y1047189D03*
Y1053567D03*
Y1059945D03*
X1541357Y1053567D03*
Y1059945D03*
X1543208Y1050378D03*
X1532106Y1056756D03*
X1535806D03*
Y1050378D03*
X1533956Y1059945D03*
X1532106Y1050378D03*
X1537657Y1059945D03*
X1533956Y1047189D03*
X1539507Y1050378D03*
X1537657Y1053567D03*
X1543208Y1056756D03*
X1541357Y1047189D03*
X1539507Y1056756D03*
X1537657Y1047189D03*
X1533956Y1053567D03*
X1530255Y1066323D03*
Y1072701D03*
X1543208Y1063134D03*
X1535806D03*
X1543208Y1069512D03*
X1541357Y1072701D03*
X1535806Y1069512D03*
X1537657Y1072701D03*
X1532106Y1063134D03*
X1539507D03*
X1533956Y1066323D03*
X1532106Y1069512D03*
X1539507D03*
X1533956Y1072701D03*
X1537657Y1066323D03*
X1541357D03*
X1530255Y1079079D03*
Y1085457D03*
X1535806Y1075890D03*
X1541357Y1079079D03*
X1543208Y1082268D03*
Y1088646D03*
X1535806D03*
Y1082268D03*
X1532106Y1075890D03*
X1539507D03*
X1533956Y1079079D03*
X1537657D03*
X1532106Y1082268D03*
X1539507D03*
X1533956Y1085457D03*
X1539507Y1088646D03*
X1532106D03*
X1537657Y1085457D03*
X1541357D03*
X1543208Y1075890D03*
X1530255Y1098213D03*
Y1104591D03*
X1541357Y1091835D03*
X1535806Y1095024D03*
X1543208Y1101402D03*
X1541357Y1098213D03*
X1535806Y1101402D03*
X1530255Y1091835D03*
X1539507Y1101402D03*
X1533956Y1104591D03*
X1537657Y1091835D03*
X1532106Y1095024D03*
X1539507D03*
X1533956Y1098213D03*
X1537657D03*
X1532106Y1101402D03*
X1537657Y1104591D03*
X1533956Y1091835D03*
X1541357Y1104591D03*
X1543208Y1095024D03*
X1530255Y1110969D03*
Y1117347D03*
X1543208Y1107780D03*
X1535806D03*
X1541357Y1110969D03*
Y1117347D03*
X1535806Y1114158D03*
X1537657Y1110969D03*
X1532106Y1114158D03*
X1539507D03*
X1533956Y1117347D03*
X1537657D03*
X1539507Y1107780D03*
X1532106D03*
X1533956Y1110969D03*
X1543208Y1114158D03*
X1530255Y1123725D03*
Y1130102D03*
X1543208Y1120536D03*
X1535806D03*
X1543208Y1126914D03*
X1535806D03*
X1541357Y1130102D03*
X1535806Y1133292D03*
X1532106Y1120536D03*
X1539507D03*
X1533956Y1123725D03*
X1537657Y1130102D03*
X1532106Y1133292D03*
X1539507D03*
Y1126914D03*
X1532106D03*
X1537657Y1123725D03*
X1533956Y1130102D03*
X1543208Y1133292D03*
X1541357Y1123725D03*
X1530255Y1142858D03*
Y1136480D03*
Y1149236D03*
X1541357Y1136480D03*
X1543208Y1139669D03*
X1535806D03*
X1543208Y1146047D03*
X1541357Y1149236D03*
X1535806Y1146047D03*
X1533956Y1136480D03*
X1537657D03*
X1532106Y1139669D03*
X1539507D03*
X1533956Y1142858D03*
X1537657Y1149236D03*
X1539507Y1146047D03*
X1532106D03*
X1537657Y1142858D03*
X1533956Y1149236D03*
X1541357Y1142858D03*
X1533956Y1161992D03*
X1543208Y1158803D03*
X1530255Y1155614D03*
X1537657D03*
X1541357D03*
X1535806Y1152425D03*
X1532106Y1158803D03*
X1535806D03*
X1541357Y1161992D03*
X1532106Y1165181D03*
Y1152425D03*
X1539507D03*
X1533956Y1155614D03*
X1539507Y1158803D03*
X1543208Y1152425D03*
X1537657Y1161992D03*
X1530255D03*
X1531167Y1540295D03*
X1529773Y1547243D03*
X1531068Y1549970D03*
X1532643Y1552698D03*
X1535368Y1540355D03*
X1537468D03*
X1538875Y1547073D03*
X1538819Y1549336D03*
X1534188Y1554453D03*
X1529443D03*
X1529994Y1561853D03*
X1531068Y1563608D03*
X1532643Y1566336D03*
X1529443Y1556953D03*
X1529994Y1559353D03*
X1539170Y1567540D03*
X1539171Y1564618D03*
X1539082Y1561698D03*
X1534824Y1569063D03*
X1531167Y1575641D03*
X1529493Y1569063D03*
X1538585Y1571658D03*
X1539170Y1569640D03*
X1530373Y1625380D03*
X1542433D03*
X1538173D03*
X1532133Y1635380D03*
X1536413D03*
X1532133Y1647292D03*
X1536413D03*
X1530373Y1657292D03*
X1542433D03*
X1538173D03*
X1545728Y873245D03*
X1553129Y879623D03*
X1549428D03*
X1545728D03*
Y886001D03*
X1547578Y882812D03*
X1553129Y886001D03*
X1551279Y882812D03*
X1547578Y889190D03*
Y895568D03*
X1553129Y892379D03*
X1547578Y901946D03*
X1553129Y898757D03*
X1547578Y908324D03*
X1553870Y906181D03*
Y912559D03*
X1547578Y914701D03*
X1553870Y918937D03*
X1547578Y921079D03*
X1553870Y925315D03*
X1547578Y927457D03*
Y933835D03*
X1553870Y931693D03*
X1547578Y940213D03*
X1553870Y938071D03*
X1547578Y946591D03*
X1553870Y944449D03*
Y950827D03*
X1547578Y952969D03*
Y959347D03*
Y965725D03*
X1553870Y957205D03*
Y963583D03*
Y969961D03*
X1543877Y984859D03*
X1547578Y972103D03*
Y978481D03*
X1553870Y976339D03*
Y982717D03*
X1547578Y984859D03*
X1545728Y988048D03*
X1547578Y991237D03*
Y997615D03*
X1553870Y989095D03*
Y995473D03*
X1547578Y1003993D03*
Y1010371D03*
X1553870Y1008229D03*
Y1001851D03*
X1543877Y1010371D03*
X1548759Y1028055D03*
X1555051Y1030197D03*
X1545058Y1028055D03*
X1548759Y1040811D03*
Y1034433D03*
X1555051Y1042953D03*
Y1036575D03*
X1546909Y1056756D03*
X1545058Y1059945D03*
X1548759Y1047189D03*
X1555051Y1049331D03*
X1548759Y1053567D03*
Y1059945D03*
X1555051Y1055709D03*
Y1062087D03*
X1548759Y1072701D03*
Y1066323D03*
X1555051Y1068465D03*
Y1074843D03*
X1548759Y1079079D03*
X1555051Y1081221D03*
X1548759Y1085457D03*
X1555051Y1087599D03*
X1548759Y1091835D03*
X1555051Y1093977D03*
X1548759Y1098213D03*
Y1104591D03*
X1555051Y1100355D03*
Y1106733D03*
X1548759Y1110969D03*
X1555051Y1113111D03*
X1548759Y1117347D03*
X1555051Y1119489D03*
Y1132245D03*
X1548759Y1123725D03*
X1555051Y1125867D03*
X1548759Y1130102D03*
Y1136480D03*
X1555051Y1138622D03*
X1548759Y1142858D03*
X1555051Y1145000D03*
X1548759Y1149236D03*
X1545058Y1155614D03*
X1548759D03*
X1555051Y1151378D03*
X1550609Y1158803D03*
X1554310D03*
X1548759Y1161992D03*
X1546909Y1165181D03*
X1550233Y1625380D03*
X1554493D03*
X1544193Y1635380D03*
X1556253D03*
X1548473D03*
X1544193Y1647292D03*
X1556253D03*
X1548473D03*
X1554493Y1657292D03*
X1550233D03*
X1562293Y1625380D03*
X1566553D03*
X1568313Y1635380D03*
X1560533D03*
X1572593D03*
X1568313Y1647292D03*
X1560533D03*
X1572593D03*
X1562293Y1657292D03*
X1566553D03*
X1583056Y1540514D03*
X1586969Y1547243D03*
X1585797Y1552195D03*
X1588264Y1549970D03*
X1580940Y1540460D03*
X1578689Y1540509D03*
X1578854Y1546218D03*
X1577195Y1551121D03*
X1586639Y1554453D03*
X1587190Y1561853D03*
X1577688Y1556810D03*
Y1561725D03*
X1588264Y1563608D03*
X1586639Y1556953D03*
X1587190Y1559353D03*
X1577596Y1554612D03*
X1586688Y1569063D03*
X1583160Y1575425D03*
X1577642Y1568698D03*
Y1570898D03*
X1583160Y1577625D03*
X1579089Y1573317D03*
X1574353Y1625380D03*
X1578613D03*
X1586413D03*
X1580373Y1635380D03*
X1584653D03*
X1580373Y1647292D03*
X1584653D03*
X1574353Y1657292D03*
X1578613D03*
X1586413D03*
X1588363Y1540295D03*
X1591693Y1547243D03*
X1593088Y1540295D03*
X1596418Y1547243D03*
X1597812Y1540295D03*
X1601142Y1547243D03*
X1602536Y1540295D03*
X1592988Y1549970D03*
X1597713D03*
X1602437D03*
X1589839Y1552698D03*
X1594563D03*
X1599287D03*
X1600812Y1554453D03*
X1596088D03*
X1591363D03*
X1601363Y1561853D03*
X1596639D03*
X1591914D03*
X1592988Y1563608D03*
X1597713D03*
X1602437D03*
X1589839Y1566336D03*
X1594563D03*
X1599287D03*
X1600812Y1556953D03*
X1596639Y1559353D03*
X1596088Y1556953D03*
X1601363Y1559353D03*
X1591363Y1556953D03*
X1591914Y1559353D03*
X1602536Y1575641D03*
X1600862Y1569063D03*
X1597812Y1575641D03*
X1596138Y1569063D03*
X1593088Y1575641D03*
X1591413Y1569063D03*
X1588363Y1575641D03*
X1590673Y1625380D03*
X1602733D03*
X1598473D03*
X1592433Y1635380D03*
X1596713D03*
X1592433Y1647292D03*
X1596713D03*
X1590673Y1657292D03*
X1598473D03*
X1602733D03*
X1605867Y1547243D03*
X1607261Y1540295D03*
X1610591Y1547243D03*
X1611985Y1540295D03*
X1615315Y1547243D03*
X1616710Y1540295D03*
X1607161Y1549970D03*
X1611886D03*
X1616610D03*
X1604012Y1552698D03*
X1608736D03*
X1613461D03*
X1614985Y1554453D03*
X1610261D03*
X1605536D03*
X1615536Y1561853D03*
X1610812D03*
X1606087D03*
X1607161Y1563608D03*
X1611886D03*
X1616610D03*
X1604012Y1566336D03*
X1608736D03*
X1613461D03*
X1610261Y1556953D03*
X1610812Y1559353D03*
X1606087D03*
X1605536Y1556953D03*
X1614985D03*
X1615536Y1559353D03*
X1610311Y1569063D03*
X1605587D03*
X1616710Y1575641D03*
X1615035Y1569063D03*
X1611985Y1575641D03*
X1607261D03*
X1610533Y1625380D03*
X1614793D03*
X1604493Y1635380D03*
X1616553D03*
X1608773D03*
X1604493Y1647292D03*
X1616553D03*
X1608773D03*
X1614793Y1657292D03*
X1610533D03*
X1620040Y1547243D03*
X1621434Y1540295D03*
X1624764Y1547243D03*
X1626158Y1540295D03*
X1629489Y1547243D03*
X1630883Y1540295D03*
X1621335Y1549970D03*
X1626059D03*
X1630783D03*
X1618185Y1552698D03*
X1622909D03*
X1627634D03*
X1632358D03*
X1629158Y1554453D03*
X1624434D03*
X1619710D03*
X1629709Y1561853D03*
X1624985D03*
X1620261D03*
X1621335Y1563608D03*
X1626059D03*
X1630783D03*
X1618185Y1566336D03*
X1622909D03*
X1627634D03*
X1632358D03*
X1624434Y1556953D03*
X1624985Y1559353D03*
X1620261D03*
X1619710Y1556953D03*
X1629709Y1559353D03*
X1629158Y1556953D03*
X1629209Y1569063D03*
X1619760D03*
X1630883Y1575641D03*
X1626158D03*
X1624484Y1569063D03*
X1621434Y1575641D03*
X1622593Y1625380D03*
X1626853D03*
X1628613Y1635380D03*
X1620833D03*
X1632893D03*
X1628613Y1647292D03*
X1620833D03*
X1632893D03*
X1622593Y1657292D03*
X1626853D03*
X1634213Y1547243D03*
X1635607Y1540295D03*
X1638937Y1547243D03*
X1640332Y1540295D03*
X1643662Y1547243D03*
X1645056Y1540295D03*
X1635508Y1549970D03*
X1640232D03*
X1644957D03*
X1637083Y1552698D03*
X1641807D03*
X1646531D03*
X1643332Y1554453D03*
X1638607D03*
X1633883D03*
X1643883Y1561853D03*
X1639158D03*
X1634434D03*
X1635508Y1563608D03*
X1640232D03*
X1644957D03*
X1637083Y1566336D03*
X1641807D03*
X1646531D03*
X1633883Y1556953D03*
X1634434Y1559353D03*
X1643332Y1556953D03*
X1643883Y1559353D03*
X1639158D03*
X1638607Y1556953D03*
X1643382Y1569063D03*
X1633933D03*
X1645056Y1575641D03*
X1640332D03*
X1638657Y1569063D03*
X1635607Y1575641D03*
X1634653Y1625380D03*
X1638923D03*
X1646713D03*
X1640673Y1635286D03*
X1644953Y1635380D03*
X1640673Y1647292D03*
X1644953D03*
X1634653Y1657292D03*
X1638913D03*
X1646713D03*
X1653111Y1547243D03*
X1648386D03*
X1649780Y1540295D03*
X1654505D03*
X1657835Y1547243D03*
X1659229Y1540295D03*
X1649681Y1549970D03*
X1654406D03*
X1659130D03*
X1651256Y1552698D03*
X1655980D03*
X1660705D03*
X1662250Y1554453D03*
X1657505D03*
X1652781D03*
X1648056D03*
X1658056Y1561853D03*
X1653332D03*
X1648607D03*
X1649681Y1563608D03*
X1654406D03*
X1659130D03*
X1651256Y1566336D03*
X1655980D03*
X1660705D03*
X1652781Y1556953D03*
X1648607Y1559353D03*
X1648056Y1556953D03*
X1658056Y1559353D03*
X1653332D03*
X1657505Y1556953D03*
X1652831Y1569063D03*
X1649780Y1575641D03*
X1648106Y1569063D03*
X1654505Y1575641D03*
X1657555Y1569063D03*
X1659229Y1575641D03*
X1652743Y1635380D03*
Y1647292D03*
X1663430Y1540355D03*
X1665530D03*
X1666937Y1547073D03*
X1666881Y1549336D03*
X1667231Y1567540D03*
X1667232Y1564618D03*
X1667143Y1561698D03*
X1670227Y1567413D03*
X1668750Y1563158D03*
X1662886Y1569063D03*
X1666647Y1571658D03*
X1667231Y1569640D03*
G54D234*
X716697Y1579704D03*
Y1576160D03*
Y1581475D03*
Y1577932D03*
Y1586790D03*
Y1588562D03*
Y1583247D03*
Y1585018D03*
X742189Y1576160D03*
Y1577932D03*
Y1581475D03*
Y1579704D03*
Y1588562D03*
Y1586790D03*
Y1583247D03*
Y1585018D03*
G54D60*
X66854Y1605956D03*
X65279D03*
X63704D03*
X62129D03*
X60554D03*
X58980D03*
X57405D03*
X55830D03*
X54255D03*
X52680D03*
Y1624854D03*
X54255D03*
X55830D03*
X57405D03*
X58980D03*
X60554D03*
X62129D03*
X63704D03*
X65279D03*
X66854D03*
X631608Y1362808D03*
X633183D03*
Y1381706D03*
X631608D03*
X634758Y1362808D03*
X636333D03*
X637908D03*
X639482D03*
X641057D03*
X642632D03*
X644207D03*
X645782D03*
X634758Y1381706D03*
X636333D03*
X637908D03*
X639482D03*
X641057D03*
X642632D03*
X644207D03*
X645782D03*
X1642196Y1416092D03*
X1643771D03*
X1645346D03*
X1646921D03*
X1645346Y1434990D03*
X1646921D03*
X1643771D03*
X1642196D03*
X1648496Y1416092D03*
X1650070D03*
X1651645D03*
X1653220D03*
X1654795D03*
X1656370D03*
X1648496Y1434990D03*
X1650070D03*
X1651645D03*
X1653220D03*
X1654795D03*
X1656370D03*
X1750116Y1659507D03*
X1748542D03*
X1746967D03*
X1745392D03*
X1743817D03*
X1742242D03*
Y1678405D03*
X1743817D03*
X1745392D03*
X1746967D03*
X1748542D03*
X1750116D03*
X1756416Y1659507D03*
X1754841D03*
X1753266D03*
X1751691D03*
Y1678405D03*
X1753266D03*
X1754841D03*
X1756416D03*
G54D42*
X50318Y1608318D03*
Y1609893D03*
Y1611468D03*
Y1613043D03*
Y1614618D03*
Y1616192D03*
Y1617767D03*
Y1619342D03*
Y1620917D03*
Y1622492D03*
X69216Y1611468D03*
Y1609893D03*
Y1608318D03*
Y1622492D03*
Y1620917D03*
Y1619342D03*
Y1617767D03*
Y1616192D03*
Y1614618D03*
Y1613043D03*
X629246Y1373044D03*
Y1366745D03*
Y1365170D03*
Y1369895D03*
Y1368320D03*
Y1371470D03*
Y1374619D03*
Y1377769D03*
Y1379344D03*
Y1376194D03*
X648144Y1366745D03*
Y1371470D03*
Y1373044D03*
Y1365170D03*
Y1368320D03*
Y1369895D03*
Y1374619D03*
Y1376194D03*
Y1379344D03*
Y1377769D03*
X1639834Y1426328D03*
Y1420029D03*
Y1418454D03*
Y1423179D03*
Y1421604D03*
Y1427903D03*
Y1424754D03*
Y1431053D03*
Y1432628D03*
Y1429478D03*
X1658732Y1420029D03*
Y1427903D03*
Y1429478D03*
Y1432628D03*
Y1431053D03*
Y1424754D03*
Y1426328D03*
Y1418454D03*
Y1421604D03*
Y1423179D03*
X1739880Y1661869D03*
Y1663444D03*
Y1665019D03*
Y1666594D03*
Y1668169D03*
Y1669743D03*
Y1671318D03*
Y1672893D03*
Y1674468D03*
Y1676043D03*
X1758778Y1671318D03*
Y1669743D03*
Y1668169D03*
Y1666594D03*
Y1665019D03*
Y1663444D03*
Y1661869D03*
Y1676043D03*
Y1674468D03*
Y1672893D03*
G54D225*
X694226Y144488D03*
Y225984D03*
G54D135*
X268312Y594420D03*
G54D343*
G01X50318Y1609893D02*
X48958D01*
X46881Y1607816D01*
Y1605157D01*
X45120Y1603396D01*
G01X41208Y1607896D02*
Y1608472D01*
X42132Y1609396D01*
X46461D01*
X48533Y1611468D01*
X50318D01*
G01X41208Y1612896D02*
X42708Y1611396D01*
X45633D01*
X46833Y1612596D01*
G01X50318Y1622492D02*
X47680D01*
X47602Y1622414D01*
G01X50318Y1620917D02*
X48593D01*
X47602Y1621908D01*
Y1622414D01*
G01X50318Y1616192D02*
X44436D01*
X43232Y1617396D01*
X41208D01*
G01X46833Y1612596D02*
X47280Y1613043D01*
X50318D01*
G01X43633Y1621596D02*
Y1620197D01*
X46063Y1617767D01*
X50318D01*
G01X41208Y1626896D02*
X45433D01*
X45833Y1626496D01*
G01X50318Y1619342D02*
X47188D01*
X45167Y1621363D01*
Y1623907D01*
X45833Y1624573D01*
Y1626496D01*
G01X43933Y1613818D02*
X44833D01*
X45633Y1614618D01*
X50318D01*
G01X51133Y1631796D02*
Y1629396D01*
X54255Y1626274D01*
Y1624854D01*
G01X47297Y1631096D02*
X52680Y1625713D01*
Y1624854D01*
G01X64457Y1542339D02*
Y1545142D01*
X64275Y1545324D01*
Y1546296D01*
G01X61133Y1631796D02*
Y1629896D01*
X60554Y1629317D01*
Y1624854D01*
G01X58980D02*
Y1629549D01*
X58633Y1629896D01*
G01X56133Y1631696D02*
X56633Y1630696D01*
Y1628779D01*
X57405Y1628007D01*
Y1624854D01*
G01X53633Y1629896D02*
Y1629643D01*
X55830Y1627446D01*
Y1624854D01*
G01X64133Y1627896D02*
X63704Y1627467D01*
Y1624854D01*
G01X64633Y1632896D02*
Y1631196D01*
X62129Y1628692D01*
Y1624854D01*
G01X70208Y1630396D02*
Y1628972D01*
X66854Y1625618D01*
Y1624854D01*
G01X65279D02*
Y1626179D01*
X67633Y1628533D01*
Y1629821D01*
X67058Y1630396D01*
G01X91499Y1536335D02*
X87635D01*
X86374Y1537596D01*
G01X111600Y1403100D02*
X112500Y1404000D01*
Y1416800D01*
X114488Y1418788D01*
Y1422181D01*
G01X110000Y1420000D02*
X111339Y1421339D01*
Y1422181D01*
G01X111500Y1418500D02*
X112913Y1419913D01*
Y1422181D01*
G01X103748Y1431226D02*
X105235Y1432713D01*
X108681D01*
G01X99818Y1546296D02*
Y1545524D01*
X100200Y1545142D01*
Y1542339D01*
G01X112305Y1382130D02*
X113625Y1380810D01*
Y1376461D01*
G01X113500Y1398600D02*
X113800D01*
X114600Y1399400D01*
Y1416672D01*
X116063Y1418135D01*
Y1422181D01*
G01X124700Y1401000D02*
Y1407463D01*
X129500Y1412263D01*
Y1417500D01*
X127087Y1419913D01*
Y1422181D01*
G01X117638D02*
Y1416638D01*
X116700Y1415700D01*
G01Y1410500D02*
X119213Y1413013D01*
Y1422181D01*
G01X122050Y1403750D02*
X119776D01*
X117938Y1405588D01*
Y1408762D01*
X120787Y1411611D01*
Y1422181D01*
G01X120700Y1408100D02*
X122362Y1409762D01*
Y1422181D01*
G01X125512D02*
Y1418488D01*
X126000Y1418000D01*
G01X129932Y1665000D02*
X126428Y1661496D01*
Y1661087D01*
G01X129932Y1679174D02*
X127272Y1680276D01*
G01X138000Y1400600D02*
X137000Y1401600D01*
Y1410800D01*
X134800Y1413000D01*
Y1424700D01*
X133087Y1426413D01*
X131319D01*
G01X129200Y1401000D02*
X131100Y1402900D01*
Y1417900D01*
X128661Y1420339D01*
Y1422181D01*
G01X134800Y1408100D02*
X133200Y1409700D01*
Y1424300D01*
X132661Y1424839D01*
X131319D01*
G01Y1427988D02*
X133512D01*
X136500Y1425000D01*
G01X141500Y1429500D02*
X136713Y1434287D01*
X131319D01*
G01X138000Y1426500D02*
X137000Y1427500D01*
X136000D01*
X133937Y1429563D01*
X131319D01*
G01X141500Y1433500D02*
X140000D01*
X137638Y1435862D01*
X131319D01*
G01X136100Y1442600D02*
X134087Y1440587D01*
X131319D01*
G01X137026Y1439500D02*
X135500D01*
X135012Y1439012D01*
X131319D01*
G01Y1437437D02*
X135936D01*
X135948Y1437425D01*
G01X141191Y1664337D02*
X140528Y1665000D01*
X139774D01*
G01X141078Y1679887D02*
X140365Y1679174D01*
X139774D01*
G01X144905Y1382130D02*
X146225Y1380810D01*
Y1376461D01*
G01X144925Y1433500D02*
X141500D01*
G01X178925Y1376461D02*
Y1380810D01*
X177605Y1382130D01*
G01X211825Y1376461D02*
Y1380810D01*
X210505Y1382130D01*
G01X243305D02*
X244625Y1380810D01*
Y1376461D01*
G01X270281Y594223D02*
Y592723D01*
X268472Y589585D01*
X266707Y588058D01*
X266601Y586578D01*
G01X271855Y594223D02*
Y592132D01*
X270291Y589457D01*
G01D02*
X269405Y587943D01*
Y585110D01*
G01X273208Y588237D02*
X273430Y591537D01*
Y594223D01*
G01X273069Y585145D02*
Y586173D01*
X273208Y588237D01*
G01X275005Y594223D02*
Y591235D01*
X275558Y589395D01*
G01D02*
X276826Y585178D01*
G01X278155Y594223D02*
Y591424D01*
X280766Y588813D01*
X285340D01*
X286876Y587277D01*
Y585177D01*
G01X276580Y594223D02*
Y591215D01*
X278447Y586707D01*
X279976Y585178D01*
G01X290161Y687897D02*
Y683548D01*
X291481Y682228D01*
G01X278225Y1330315D02*
Y1334664D01*
X276905Y1335984D01*
G01X311121Y1330287D02*
Y1334636D01*
X309801Y1335956D01*
G01X344025Y1330230D02*
Y1334579D01*
X342705Y1335899D01*
G01X355991Y707779D02*
Y703430D01*
X357311Y702110D01*
G01X376825Y1330430D02*
Y1334779D01*
X375505Y1336099D01*
G01X389031Y707847D02*
Y703498D01*
X390351Y702178D01*
G01X409407Y1349761D02*
Y1354110D01*
X408087Y1355430D01*
G01X424086Y123023D02*
X426767D01*
G01Y132865D02*
X424486D01*
X424086Y133265D01*
G01X426767Y134834D02*
X426537D01*
X423068Y136270D01*
X422890Y136700D01*
G01X422031Y685698D02*
X423351Y684378D01*
G01X452948Y104003D02*
Y106684D01*
G01X454431Y665447D02*
Y661098D01*
X455751Y659778D01*
G01X483967Y213093D02*
Y210255D01*
X483467Y209755D01*
G01X484754Y223377D02*
X483967Y222590D01*
Y218408D01*
G01X488297Y214077D02*
X490135D01*
X491635Y212577D01*
G01X485541Y218408D02*
Y222590D01*
X484754Y223377D01*
G01X487031Y638947D02*
Y634598D01*
X488351Y633278D01*
G01X516119Y130014D02*
Y123919D01*
X513772Y121572D01*
Y121220D01*
G01X507261Y135722D02*
X503122D01*
X503000Y135600D01*
G01X511394Y130014D02*
Y126836D01*
X510400Y125842D01*
X509346D01*
G01X509820Y129423D02*
Y127230D01*
X509346Y126756D01*
Y125842D01*
G01X507261Y149895D02*
X503161D01*
G01X507261Y140447D02*
X504161D01*
X503550Y141058D01*
X500136D01*
G01X507261Y145171D02*
X502775D01*
X500136Y142532D01*
Y141058D01*
G01X509820Y160919D02*
X507945D01*
G01X507261Y154620D02*
X503161D01*
G01X515410Y204590D02*
X514880Y205120D01*
Y207609D01*
X513651Y208838D01*
Y209692D01*
G01Y216828D02*
Y218666D01*
X515151Y220166D01*
G01X509320Y214072D02*
X505138D01*
X504351Y213285D01*
G01X509320Y212498D02*
X505138D01*
X504351Y213285D01*
G01X523993Y130014D02*
Y126914D01*
X524993Y125914D01*
G01X519268Y160328D02*
Y167428D01*
G01X520843Y160328D02*
Y164653D01*
X521618Y165428D01*
G01X514635Y212498D02*
X517473D01*
X517973Y211998D01*
G01X520331Y604847D02*
Y602837D01*
X520371Y602797D01*
Y600458D01*
X521651Y599178D01*
G01X531867Y130014D02*
Y126914D01*
X530867Y125914D01*
X530567D01*
G01X537575Y135722D02*
X539528D01*
X543062Y134258D01*
X543408Y133912D01*
G01X538166Y132573D02*
Y130698D01*
G01X537575Y146746D02*
X541547D01*
X541675Y146874D01*
G01X537575Y142021D02*
X541675D01*
G01X537575Y137297D02*
X541547D01*
X541675Y137169D01*
G01X537575Y151470D02*
X541675D01*
G01X537575Y156195D02*
X541675D01*
G01X533442Y160328D02*
Y164428D01*
G01X572342Y227071D02*
X570504D01*
X569004Y228571D01*
G01X576672Y222740D02*
Y218958D01*
X577859Y217771D01*
G01X575098Y222740D02*
Y219966D01*
X573911Y218779D01*
Y217771D01*
G01X576672Y228055D02*
Y229893D01*
X578172Y231393D01*
G01X627327Y1357114D02*
Y1359064D01*
X631071Y1362808D01*
X631608D01*
G01X633183D02*
Y1361470D01*
X630477Y1358764D01*
Y1357114D01*
G01X634758Y1362808D02*
Y1361244D01*
X633406Y1359892D01*
Y1358576D01*
G01X636333Y1362808D02*
Y1359895D01*
X635574Y1359136D01*
Y1354537D01*
X634776Y1353739D01*
G01X719861Y1400139D02*
X721181Y1398819D01*
Y1394470D01*
G01X752643Y1400239D02*
X753963Y1398919D01*
Y1394570D01*
G01X796276Y1336438D02*
X798544D01*
X804099Y1333835D01*
G01X796276Y1342737D02*
X800630D01*
X801171Y1343278D01*
G01X804289Y1336334D02*
X801918D01*
X798629Y1338012D01*
X796276D01*
G01X804289Y1340762D02*
X802683D01*
X802283Y1341162D01*
X796276D01*
G01X801089Y1339587D02*
X796276D01*
G01X800201Y1345388D02*
X798427Y1344312D01*
X796276D01*
G01X900723Y1146553D02*
X901264Y1147094D01*
X905618D01*
G01X901693Y1144443D02*
X903467Y1145519D01*
X905618D01*
G01X897605Y1149069D02*
X898005Y1148669D01*
X905618D01*
G01Y1153393D02*
X903574D01*
X897754Y1156119D01*
G01X897605Y1153497D02*
X899976D01*
X903265Y1151819D01*
X905618D01*
G01X900280Y1150769D02*
X900805Y1150244D01*
X905618D01*
G01X944630Y1149069D02*
X946236D01*
X946636Y1148669D01*
X952643D01*
G01X944820Y1156119D02*
X950637Y1153393D01*
X952643D01*
G01X944630Y1153497D02*
X947001D01*
X950290Y1151819D01*
X952643D01*
G01Y1147094D02*
X948289D01*
X947748Y1146553D01*
G01X948718Y1144443D02*
X950492Y1145519D01*
X952643D01*
G01X947830Y1150244D02*
X952643D01*
G01X1024961Y543499D02*
X1022350D01*
X1020202Y541351D01*
G01X1027520Y549799D02*
Y552724D01*
G01X1030079Y543499D02*
X1032690D01*
X1034838Y541351D01*
G01X1084043Y1382111D02*
X1085363Y1380791D01*
Y1376442D01*
G01X1116643Y1382111D02*
X1117963Y1380791D01*
Y1376442D01*
G01X1150663D02*
Y1380791D01*
X1149343Y1382111D01*
G01X1183563Y1376442D02*
Y1380791D01*
X1182243Y1382111D01*
G01X1209681Y1419213D02*
X1206485D01*
X1205977Y1419721D01*
X1204204D01*
G01X1239800Y1389500D02*
X1238800Y1388500D01*
X1217800D01*
X1213700Y1392600D01*
Y1403500D01*
X1215488Y1405288D01*
Y1408681D01*
G01X1211000Y1406500D02*
X1212339Y1407839D01*
Y1408681D01*
G01X1212500Y1405000D02*
X1213913Y1406413D01*
Y1408681D01*
G01X1215043Y1382111D02*
X1216363Y1380791D01*
Y1376442D01*
G01X1227000Y1401300D02*
X1224937Y1403363D01*
Y1408681D01*
G01X1228800Y1391300D02*
X1227600Y1390100D01*
X1218800D01*
X1215400Y1393500D01*
Y1402900D01*
X1217063Y1404563D01*
Y1408681D01*
G01X1219650Y1392050D02*
X1217300Y1394400D01*
Y1402100D01*
X1218638Y1403438D01*
Y1408681D01*
G01X1219500Y1398900D02*
Y1401000D01*
X1220213Y1401713D01*
Y1408681D01*
G01X1224200Y1393500D02*
Y1396600D01*
X1221787Y1399013D01*
Y1408681D01*
G01X1235400Y1391200D02*
X1232300D01*
X1223362Y1400138D01*
Y1408681D01*
G01X1226512D02*
Y1404988D01*
X1227000Y1404500D01*
G01X1233700Y1395600D02*
X1232100Y1397200D01*
Y1404400D01*
X1229661Y1406839D01*
Y1408681D01*
G01X1238200Y1395500D02*
X1235793Y1393093D01*
X1232725D01*
X1230400Y1395418D01*
Y1404100D01*
X1228087Y1406413D01*
Y1408681D01*
G01X1238500Y1400900D02*
X1236900Y1402500D01*
Y1408500D01*
X1235800Y1409600D01*
Y1411200D01*
X1234087Y1412913D01*
X1232319D01*
G01X1234900Y1404400D02*
Y1407500D01*
X1234200Y1408200D01*
Y1410800D01*
X1233661Y1411339D01*
X1232319D01*
G01X1239000Y1413000D02*
X1238000Y1414000D01*
X1236600D01*
X1234537Y1416063D01*
X1232319D01*
G01X1237500Y1411500D02*
X1237240D01*
X1234252Y1414488D01*
X1232319D01*
G01X1238731Y1422362D02*
X1232319D01*
G01X1241784D02*
X1238731D01*
G01X1237000Y1430000D02*
X1234087Y1427087D01*
X1232319D01*
G01Y1428661D02*
X1233161D01*
X1234000Y1429500D01*
Y1431500D01*
G01X1236750Y1426750D02*
X1235512Y1425512D01*
X1232319D01*
G01X1237499Y1424500D02*
X1236936Y1423937D01*
X1232319D01*
G01X1239242Y1418462D02*
X1236917Y1420787D01*
X1232319D01*
G01X1241742Y1418462D02*
X1239242D01*
G01X1253034Y1335965D02*
X1254354Y1334645D01*
Y1330296D01*
G01X1285930Y1335937D02*
X1287250Y1334617D01*
Y1330268D01*
G01X1303765Y545238D02*
X1305598D01*
X1307050Y546690D01*
G01D02*
X1307960Y547600D01*
X1309217D01*
X1313076Y551459D01*
X1315411D01*
G01X1309870Y552788D02*
X1307366D01*
G01X1315411Y554609D02*
X1312257D01*
X1310436Y552788D01*
X1309870D01*
G01X1315411Y553034D02*
X1312952D01*
X1309556Y549638D01*
X1307366D01*
G01X1315411Y559333D02*
X1313911D01*
X1312311Y560255D01*
X1310573Y561691D01*
X1309539Y562886D01*
X1307766Y563013D01*
G01X1307298Y560209D02*
X1307494Y560013D01*
X1309536D01*
X1309718Y559831D01*
X1309776D01*
G01D02*
X1313320Y557759D01*
X1315411D01*
G01Y556184D02*
X1310450D01*
G01D02*
X1307694D01*
X1307333Y556545D01*
G01X1318834Y1335880D02*
X1320154Y1334560D01*
Y1330211D01*
G01X1351634Y1336080D02*
X1352954Y1334760D01*
Y1330411D01*
G01X1369303Y617321D02*
X1367983Y618641D01*
Y622990D01*
G01X1385536Y1349742D02*
Y1354091D01*
X1384216Y1355411D01*
G01X1402003Y650221D02*
X1400683Y651541D01*
Y655890D01*
G01X1434603Y682801D02*
X1433283Y684121D01*
Y688470D01*
G01X1467521Y702378D02*
X1466201Y703698D01*
Y708047D01*
G01X1499283Y708215D02*
Y703698D01*
X1500603Y702378D01*
G01X1533403D02*
X1532083Y703698D01*
Y708047D01*
G01X1566533Y680438D02*
X1565213Y681758D01*
Y686107D01*
G01X1599303Y646669D02*
X1597983Y647989D01*
Y652338D01*
G01X1621536Y552689D02*
X1618473D01*
X1618188Y552404D01*
X1616769D01*
G01X1621536Y551114D02*
X1619598D01*
X1618148Y549664D01*
X1617322D01*
G01X1621536Y558988D02*
X1619910D01*
X1617017Y560187D01*
X1615613Y561591D01*
X1613713D01*
G01X1621536Y557414D02*
X1619798D01*
G01X1621536Y555839D02*
X1618673D01*
G01X1621536Y554264D02*
X1615299D01*
X1614899Y554664D01*
X1613523D01*
G01X1632303Y627669D02*
X1630983Y628989D01*
Y633338D01*
G01X1644001Y1413047D02*
X1645346Y1414392D01*
Y1416092D01*
G01X1646921D02*
Y1413179D01*
X1646483Y1412741D01*
G01X1641039Y1414194D02*
X1642196Y1415351D01*
Y1416092D01*
G01X1643771D02*
Y1414728D01*
X1642393Y1413350D01*
G01X1649024Y1409796D02*
X1648496Y1410324D01*
Y1416092D01*
G01X1653024Y1409796D02*
X1650070Y1412750D01*
Y1416092D01*
G01X1656824Y1409796D02*
X1655970D01*
X1654101Y1411665D01*
X1653601D01*
X1651645Y1413621D01*
Y1416092D01*
G01X1660624Y1409796D02*
X1658355Y1412065D01*
X1655606D01*
X1653220Y1414451D01*
Y1416092D01*
G01X1664424Y1409796D02*
X1660755Y1413465D01*
X1656001D01*
X1654795Y1414671D01*
Y1416092D01*
G01X1656370D02*
Y1415496D01*
X1656901Y1414965D01*
X1662146D01*
G01X1667594Y1399428D02*
X1668914Y1398108D01*
Y1393759D01*
G01X1662146Y1414965D02*
X1663255D01*
X1668424Y1409796D01*
G01X1701696Y1393859D02*
Y1398208D01*
X1700376Y1399528D01*
G01X1751558Y1579332D02*
Y1578360D01*
X1751740Y1578178D01*
Y1575375D01*
G01X1747963Y1652565D02*
Y1654465D01*
X1748542Y1655044D01*
Y1659507D01*
G01X1750116D02*
Y1654812D01*
X1750463Y1654465D01*
G01X1744963Y1656465D02*
X1745392Y1656894D01*
Y1659507D01*
G01X1744463Y1653165D02*
X1746967Y1655669D01*
Y1659507D01*
G01X1742242D02*
Y1658743D01*
X1738888Y1655389D01*
Y1653965D01*
G01X1742038D02*
X1741463Y1654540D01*
Y1655828D01*
X1743817Y1658182D01*
Y1659507D01*
G01X1752963Y1652665D02*
X1752463Y1653665D01*
Y1655582D01*
X1751691Y1656354D01*
Y1659507D01*
G01X1755463Y1654465D02*
Y1654718D01*
X1753266Y1656915D01*
Y1659507D01*
G01X1757963Y1652565D02*
Y1654965D01*
X1754841Y1658087D01*
Y1659507D01*
G01X1761799Y1653265D02*
X1756416Y1658648D01*
Y1659507D01*
G01X1758778Y1661869D02*
X1761416D01*
X1761494Y1661947D01*
G01D02*
Y1662453D01*
X1760503Y1663444D01*
X1758778D01*
G01X1768353Y1666984D02*
X1767168Y1668169D01*
X1758778D01*
G01X1762263Y1671765D02*
X1761816Y1671318D01*
X1758778D01*
G01X1765463Y1662765D02*
Y1664164D01*
X1763033Y1666594D01*
X1758778D01*
G01Y1665019D02*
X1761908D01*
X1763929Y1662998D01*
Y1660454D01*
X1763263Y1659788D01*
Y1657865D01*
G01X1767888Y1657465D02*
X1763663D01*
X1763263Y1657865D01*
G01X1765163Y1670543D02*
X1764263D01*
X1763463Y1669743D01*
X1758778D01*
G01Y1674468D02*
X1760138D01*
X1762713Y1677043D01*
Y1679515D01*
X1763163Y1679965D01*
G01X1767888Y1678172D02*
X1768012Y1678048D01*
Y1677029D01*
X1765948Y1674965D01*
X1762635D01*
X1760563Y1672893D01*
X1758778D01*
G01X1768233Y1674057D02*
X1767141Y1672965D01*
X1763463D01*
X1762263Y1671765D01*
G01X1773657Y1570632D02*
X1774918Y1569371D01*
X1778782D01*
G01X1787483Y1575375D02*
Y1578178D01*
X1787101Y1578560D01*
Y1579268D01*
X1787239Y1579406D01*
G54D334*
G01X304992Y880671D02*
X303154Y879624D01*
G01X304992Y887049D02*
X303154Y886002D01*
G01X306842Y883860D02*
X305004Y882813D01*
G01X304992Y893427D02*
X303154Y892380D01*
G01X304992Y899805D02*
X303154Y898758D01*
G01X304992Y906182D02*
X302413D01*
G01X304992Y912560D02*
X302413D01*
G01X304992Y918938D02*
X302413D01*
G01X304992Y925316D02*
X302413D01*
G01X304992Y931694D02*
X302413D01*
G01X304992Y938072D02*
X302413D01*
G01X304992Y944450D02*
X302413D01*
G01X304992Y950828D02*
X302413D01*
G01X304992Y957206D02*
X302413D01*
G01X304992Y963584D02*
X302413D01*
G01X304992Y969962D02*
X302413D01*
G01X304992Y976340D02*
X302413D01*
G01X304992Y982718D02*
X302413D01*
G01X304992Y989096D02*
X302413D01*
G01X304992Y995474D02*
X302413D01*
G01X304992Y1008230D02*
X302413D01*
G01X304992Y1001852D02*
X302413D01*
G01X306173Y1030198D02*
X303594D01*
G01X306173Y1036576D02*
X303594D01*
G01X306173Y1042954D02*
X303594D01*
G01X306173Y1055710D02*
X303594D01*
G01X306173Y1049332D02*
X303594D01*
G01X306173Y1062088D02*
X303594D01*
G01X306173Y1074844D02*
X303594D01*
G01X306173Y1068466D02*
X303594D01*
G01X306173Y1081222D02*
X303594D01*
G01X306173Y1087600D02*
X303594D01*
G01X306173Y1093978D02*
X303594D01*
G01X306173Y1100356D02*
X303594D01*
G01X306173Y1106734D02*
X303594D01*
G01X306173Y1113112D02*
X303594D01*
G01X306173Y1119490D02*
X303594D01*
G01X306173Y1125868D02*
X303594D01*
G01X306173Y1132246D02*
X303594D01*
G01X306173Y1138623D02*
X303594D01*
G01X306173Y1145001D02*
X303594D01*
G01X306173Y1157757D02*
X303594D01*
G01X306173Y1151379D02*
X303594D01*
G01X312393Y874293D02*
X310555Y873246D01*
G01X319795Y880671D02*
X317957Y879624D01*
G01X312393Y880671D02*
X310555Y879624D01*
G01X321645Y877482D02*
X319807Y876435D01*
G01X316094Y874293D02*
X314256Y873246D01*
G01X312393Y887049D02*
X310555Y886002D01*
G01X316094Y887049D02*
X314256Y886002D01*
G01X317944Y883860D02*
X316107Y882813D01*
G01X317944Y890238D02*
X316107Y889191D01*
G01X310543Y890238D02*
X308705Y889191D01*
G01X321645Y883860D02*
X319807Y882813D01*
G01X316094Y893427D02*
X314256Y892380D01*
G01X310543Y896616D02*
X308705Y895569D01*
G01X310543Y883860D02*
X308705Y882813D01*
G01X317944Y896616D02*
X316107Y895569D01*
G01X316094Y899805D02*
X314256Y898758D01*
G01X317944Y902994D02*
X316107Y901947D01*
G01X310543Y902994D02*
X308705Y901947D01*
G01X310543Y909371D02*
X308705Y908325D01*
G01X316094Y912560D02*
X314256Y911513D01*
G01X317944Y909371D02*
X316107Y908325D01*
G01X316094Y906182D02*
X314256Y905135D01*
G01X316094Y918938D02*
X314256Y917891D01*
G01X310543Y915749D02*
X308705Y914702D01*
G01X310543Y922127D02*
X308705Y921080D01*
G01X317944Y922127D02*
X316107Y921080D01*
G01X317944Y915749D02*
X316107Y914702D01*
G01X316094Y925316D02*
X314256Y924269D01*
G01X317944Y941261D02*
X316107Y940214D01*
G01X310543Y928505D02*
X308705Y927458D01*
G01X317944Y928505D02*
X316107Y927458D01*
G01X310543Y934883D02*
X308705Y933836D01*
G01X316094Y931694D02*
X314256Y930647D01*
G01X316094Y938072D02*
X314256Y937025D01*
G01X310543Y941261D02*
X308705Y940214D01*
G01X317944Y934883D02*
X316107Y933836D01*
G01X316094Y950828D02*
X314256Y949781D01*
G01X317944Y947639D02*
X316107Y946592D01*
G01X310543Y947639D02*
X308705Y946592D01*
G01X310543Y954017D02*
X308705Y952970D01*
G01X316094Y957206D02*
X314256Y956159D01*
G01X316094Y944450D02*
X314256Y943403D01*
G01X317944Y954017D02*
X316107Y952970D01*
G01X317944Y960395D02*
X316107Y959348D01*
G01X310543Y960395D02*
X308705Y959348D01*
G01X310543Y966773D02*
X308705Y965726D01*
G01X317944Y966773D02*
X316107Y965726D01*
G01X316094Y969962D02*
X314256Y968915D01*
G01X316094Y963584D02*
X314256Y962537D01*
G01X319795Y982718D02*
X317957Y981671D01*
G01X310543Y979529D02*
X308705Y978482D01*
G01X317944Y979529D02*
X316107Y978482D01*
G01X316094Y976340D02*
X314256Y975293D01*
G01X310543Y973151D02*
X308705Y972104D01*
G01X317944Y985907D02*
X316107Y984860D01*
G01X310543Y985907D02*
X308705Y984860D01*
G01X314244Y985907D02*
X312406Y984860D01*
G01X321645Y985907D02*
X319807Y984860D01*
G01X316094Y982718D02*
X314256Y981671D01*
G01X317944Y973151D02*
X316107Y972104D01*
G01X310543Y992285D02*
X308705Y991238D01*
G01X312393Y989096D02*
X310555Y988049D01*
G01X316094Y989096D02*
X314256Y988049D01*
G01X317944Y998663D02*
X316107Y997616D01*
G01X310543Y998663D02*
X308705Y997616D01*
G01X316094Y995474D02*
X314256Y994427D01*
G01X317944Y992285D02*
X316107Y991238D01*
G01X316094Y1001852D02*
X314256Y1000805D01*
G01X317944Y1005041D02*
X316107Y1003994D01*
G01X316094Y1008230D02*
X314256Y1007183D01*
G01X317944Y1011419D02*
X316107Y1010372D01*
G01X310543Y1011419D02*
X308705Y1010372D01*
G01X310543Y1005041D02*
X308705Y1003994D01*
G01X311724Y1027009D02*
X309886Y1028056D01*
G01X317275Y1030198D02*
X315437Y1031245D01*
G01X319126Y1027009D02*
X317288Y1028056D01*
G01X319126Y1039765D02*
X317288Y1040812D01*
G01X311724Y1039765D02*
X309886Y1040812D01*
G01X319126Y1033387D02*
X317288Y1034434D01*
G01X311724Y1033387D02*
X309886Y1034434D01*
G01X317275Y1042954D02*
X315437Y1044001D01*
G01X317275Y1036576D02*
X315437Y1037623D01*
G01X311724Y1046143D02*
X309886Y1047190D01*
G01X313574Y1055710D02*
X311736Y1056757D01*
G01X311724Y1052521D02*
X309886Y1053568D01*
G01X317275Y1049332D02*
X315437Y1050379D01*
G01X319126Y1052521D02*
X317288Y1053568D01*
G01X319126Y1058899D02*
X317288Y1059946D01*
G01X311724Y1058899D02*
X309886Y1059946D01*
G01X315425Y1058899D02*
X313587Y1059946D01*
G01X319126Y1046143D02*
X317288Y1047190D01*
G01X317275Y1055710D02*
X315437Y1056757D01*
G01X317275Y1062088D02*
X315437Y1063135D01*
G01X319126Y1071655D02*
X317288Y1072702D01*
G01X311724Y1071655D02*
X309886Y1072702D01*
G01X311724Y1065277D02*
X309886Y1066324D01*
G01X317275Y1068466D02*
X315437Y1069513D01*
G01X319126Y1065277D02*
X317288Y1066324D01*
G01X317275Y1074844D02*
X315437Y1075891D01*
G01X319126Y1078033D02*
X317288Y1079080D01*
G01X311724Y1078033D02*
X309886Y1079080D01*
G01X317275Y1081222D02*
X315437Y1082269D01*
G01X317275Y1087600D02*
X315437Y1088647D01*
G01X311724Y1084411D02*
X309886Y1085458D01*
G01X319126Y1084411D02*
X317288Y1085458D01*
G01X311724Y1090789D02*
X309886Y1091836D01*
G01X319126Y1090789D02*
X317288Y1091836D01*
G01X311724Y1103545D02*
X309886Y1104592D01*
G01X317275Y1100356D02*
X315437Y1101403D01*
G01X319126Y1097167D02*
X317288Y1098214D01*
G01X311724Y1097167D02*
X309886Y1098214D01*
G01X317275Y1093978D02*
X315437Y1095025D01*
G01X319126Y1103545D02*
X317288Y1104592D01*
G01X317275Y1106734D02*
X315437Y1107781D01*
G01X311724Y1109923D02*
X309886Y1110970D01*
G01X319126Y1109923D02*
X317288Y1110970D01*
G01X311724Y1116301D02*
X309886Y1117348D01*
G01X319126Y1116301D02*
X317288Y1117348D01*
G01X317275Y1119490D02*
X315437Y1120537D01*
G01X317275Y1113112D02*
X315437Y1114159D01*
G01X311724Y1122679D02*
X309886Y1123726D01*
G01X317275Y1125868D02*
X315437Y1126915D01*
G01X311724Y1129057D02*
X309886Y1130103D01*
G01X319126Y1129057D02*
X317288Y1130103D01*
G01X319126Y1122679D02*
X317288Y1123726D01*
G01X317275Y1132246D02*
X315437Y1133293D01*
G01X311724Y1135434D02*
X309886Y1136481D01*
G01X317275Y1138623D02*
X315437Y1139670D01*
G01X319126Y1135434D02*
X317288Y1136481D01*
G01X311724Y1141812D02*
X309886Y1142859D01*
G01X319126Y1148190D02*
X317288Y1149237D01*
G01X311724Y1148190D02*
X309886Y1149237D01*
G01X317275Y1145001D02*
X315437Y1146048D01*
G01X319126Y1141812D02*
X317288Y1142859D01*
G01X319126Y1154568D02*
X317288Y1155615D01*
G01X311724Y1154568D02*
X309886Y1155615D01*
G01X315425Y1154568D02*
X313587Y1155615D01*
G01X309874Y1157757D02*
X308036Y1158804D01*
G01X313574Y1164135D02*
X311736Y1165182D01*
G01X320976Y1157757D02*
X319138Y1158804D01*
G01X317275Y1151379D02*
X315437Y1152426D01*
G01X329047Y877482D02*
X327209Y876435D01*
G01X334598Y880671D02*
X332760Y879624D01*
G01X327196Y880671D02*
X325358Y879624D01*
G01X334598Y874293D02*
Y872066D01*
G01X336448Y883860D02*
X334610Y882813D01*
G01X323496Y887049D02*
X321658Y886002D01*
G01X327196Y887049D02*
X325358Y886002D01*
G01X332748Y883860D02*
X330910Y882813D01*
G01X330897Y887049D02*
X329059Y886002D01*
G01X336448Y890238D02*
X334610Y889191D01*
G01X329047Y890238D02*
X327209Y889191D01*
G01X336448Y896616D02*
X334610Y895569D01*
G01X323496Y893427D02*
X321658Y892380D01*
G01X329047Y896616D02*
X327209Y895569D01*
G01X330897Y893427D02*
X329059Y892380D01*
G01X336448Y902994D02*
X334610Y901947D01*
G01X323496Y899805D02*
X321658Y898758D01*
G01X329047Y902994D02*
X327209Y901947D01*
G01X330897Y899805D02*
X329059Y898758D01*
G01X323496Y906182D02*
X321658Y905135D01*
G01X323496Y912560D02*
X321658Y911513D01*
G01X330897Y906182D02*
X329059Y905135D01*
G01X330897Y912560D02*
X329059Y911513D01*
G01X329047Y909371D02*
X327209Y908325D01*
G01X336448Y909371D02*
X334610Y908324D01*
G01X336448Y915749D02*
X334610Y914702D01*
G01X323496Y918938D02*
X321658Y917891D01*
G01X329047Y915749D02*
X327209Y914702D01*
G01X330897Y918938D02*
X329059Y917891D01*
G01X336448Y922127D02*
X334610Y921080D01*
G01X323496Y925316D02*
X321658Y924269D01*
G01X330897Y925316D02*
X329059Y924269D01*
G01X329047Y922127D02*
X327209Y921080D01*
G01X336448Y928505D02*
X334610Y927458D01*
G01X336448Y934883D02*
X334610Y933836D01*
G01X323496Y931694D02*
X321658Y930647D01*
G01X329047Y928505D02*
X327209Y927458D01*
G01X329047Y934883D02*
X327209Y933836D01*
G01X330897Y931694D02*
X329059Y930647D01*
G01X336448Y941261D02*
X334610Y940214D01*
G01X323496Y938072D02*
X321658Y937025D01*
G01X329047Y941261D02*
X327209Y940214D01*
G01X330897Y938072D02*
X329059Y937025D01*
G01X330897Y957206D02*
X329059Y956159D01*
G01X336448Y947639D02*
X334610Y946592D01*
G01X323496Y944450D02*
X321658Y943403D01*
G01X323496Y950828D02*
X321658Y949781D01*
G01X330897Y944450D02*
X329059Y943403D01*
G01X330897Y950828D02*
X329059Y949781D01*
G01X329047Y947639D02*
X327209Y946592D01*
G01X336448Y954017D02*
X334610Y952970D01*
G01X323496Y957206D02*
X321658Y956159D01*
G01X329047Y954017D02*
X327209Y952970D01*
G01X336448Y960395D02*
X334610Y959348D01*
G01X336448Y966773D02*
X334610Y965726D01*
G01X330897Y963584D02*
X329059Y962537D01*
G01X329047Y966773D02*
X327209Y965726D01*
G01X323496Y963584D02*
X321658Y962537D01*
G01X329047Y960395D02*
X327209Y959348D01*
G01X323496Y969962D02*
X321658Y968915D01*
G01X330897Y969962D02*
X329059Y968915D01*
G01X336448Y973151D02*
X334610Y972104D01*
G01X336448Y979529D02*
X334610Y978482D01*
G01X323496Y976340D02*
X321658Y975293D01*
G01X323496Y982718D02*
X321658Y981671D01*
G01X330897Y976340D02*
X329059Y975293D01*
G01X329047Y973151D02*
X327209Y972104D01*
G01X334598Y982718D02*
X332760Y981671D01*
G01X330897Y982718D02*
X329059Y981671D01*
G01X329047Y979529D02*
X327209Y978482D01*
G01X336448Y985907D02*
X334610Y984860D01*
G01X329047Y985907D02*
X327209Y984860D01*
G01X332748Y985907D02*
X330910Y984860D01*
G01X336448Y992285D02*
X334610Y991238D01*
G01X336448Y998663D02*
X334610Y997616D01*
G01X323496Y989096D02*
X321658Y988049D01*
G01X323496Y995474D02*
X321658Y994427D01*
G01X329047Y992285D02*
X327209Y991238D01*
G01X330897Y989096D02*
X329059Y988049D01*
G01X330897Y995474D02*
X329059Y994427D01*
G01X329047Y998663D02*
X327209Y997616D01*
G01X323496Y1001852D02*
X321658Y1000805D01*
G01X330897Y1001852D02*
X329059Y1000805D01*
G01X336448Y1005041D02*
X334610Y1003994D01*
G01X336448Y1011419D02*
X334610Y1010372D01*
G01X323496Y1008230D02*
X321658Y1007183D01*
G01X329047Y1011419D02*
X327209Y1010372D01*
G01X330897Y1008230D02*
X329059Y1007183D01*
G01X329047Y1005041D02*
X327209Y1003994D01*
G01X330228Y1027009D02*
X328390Y1028056D01*
G01X324677Y1030198D02*
X322839Y1031245D01*
G01X332078Y1030198D02*
X330240Y1031245D01*
G01X324677Y1036576D02*
X322839Y1037623D01*
G01X324677Y1042954D02*
X322839Y1044001D01*
G01X330228Y1039765D02*
X328390Y1040812D01*
G01X330228Y1033387D02*
X328390Y1034434D01*
G01X332078Y1036576D02*
X330240Y1037623D01*
G01X332078Y1042954D02*
X330240Y1044001D01*
G01X330228Y1046143D02*
X328390Y1047190D01*
G01X324677Y1049332D02*
X322839Y1050379D01*
G01X324677Y1055710D02*
X322839Y1056757D01*
G01X328378Y1055710D02*
X326539Y1056757D01*
G01X330228Y1052521D02*
X328390Y1053568D01*
G01X330228Y1058899D02*
X328390Y1059946D01*
G01X326527Y1058899D02*
X324689Y1059946D01*
G01X332078Y1049332D02*
X330240Y1050379D01*
G01X332078Y1055710D02*
X330240Y1056757D01*
G01X330228Y1071655D02*
X328390Y1072702D01*
G01X332078Y1068466D02*
X330240Y1069513D01*
G01X324677Y1062088D02*
X322839Y1063135D01*
G01X332078Y1062088D02*
X330240Y1063135D01*
G01X324677Y1068466D02*
X322839Y1069513D01*
G01X330228Y1065277D02*
X328390Y1066324D01*
G01X324677Y1074844D02*
X322839Y1075891D01*
G01X332078Y1074844D02*
X330240Y1075891D01*
G01X330228Y1078033D02*
X328390Y1079080D01*
G01X324677Y1087600D02*
X322839Y1088647D01*
G01X330228Y1084411D02*
X328390Y1085458D01*
G01X332078Y1087600D02*
X330240Y1088647D01*
G01X324677Y1081222D02*
X322839Y1082269D01*
G01X332078Y1081222D02*
X330240Y1082269D01*
G01X330228Y1090789D02*
X328390Y1091836D01*
G01X324677Y1093978D02*
X322839Y1095025D01*
G01X332078Y1093978D02*
X330240Y1095025D01*
G01X330228Y1103545D02*
X328390Y1104592D01*
G01X330228Y1097167D02*
X328390Y1098214D01*
G01X324677Y1100356D02*
X322839Y1101403D01*
G01X332078Y1100356D02*
X330240Y1101403D01*
G01X324677Y1106734D02*
X322839Y1107781D01*
G01X332078Y1106734D02*
X330240Y1107781D01*
G01X330228Y1109923D02*
X328390Y1110970D01*
G01X330228Y1116301D02*
X328390Y1117348D01*
G01X332078Y1113112D02*
X330240Y1114159D01*
G01X324677Y1113112D02*
X322839Y1114159D01*
G01X332078Y1119490D02*
X330240Y1120537D01*
G01X324677Y1119490D02*
X322839Y1120537D01*
G01X332078Y1125868D02*
X330240Y1126915D01*
G01X324677Y1125868D02*
X322839Y1126915D01*
G01X330228Y1122679D02*
X328390Y1123726D01*
G01X324677Y1132246D02*
X322839Y1133293D01*
G01X332078Y1132246D02*
X330240Y1133293D01*
G01X330228Y1129057D02*
X328390Y1130103D01*
G01X330228Y1141812D02*
X328390Y1142859D01*
G01X324677Y1138623D02*
X322839Y1139670D01*
G01X330228Y1135434D02*
X328390Y1136481D01*
G01X332078Y1138623D02*
X330240Y1139670D01*
G01X330228Y1148190D02*
X328390Y1149237D01*
G01X332078Y1145001D02*
X330240Y1146048D01*
G01X324677Y1145001D02*
X322839Y1146048D01*
G01X322826Y1154568D02*
X320988Y1155615D01*
G01X322826Y1160946D02*
X320988Y1161993D01*
G01X330228Y1154568D02*
X328390Y1155615D01*
G01X332078Y1151379D02*
X330240Y1152426D01*
G01X324677Y1151379D02*
X322839Y1152426D01*
G01X328378Y1157757D02*
X326539Y1158804D01*
G01X332078Y1157757D02*
X330240Y1158804D01*
G01X335779Y1157757D02*
X333941Y1158804D01*
G01X324677Y1157757D02*
X322839Y1158804D01*
G01X330228Y1160946D02*
X328390Y1161993D01*
G01X332078Y1164135D02*
X330240Y1165182D01*
G01X345700Y880671D02*
X343862Y879624D01*
G01X340149Y877482D02*
Y879555D01*
X340162Y879568D01*
G01X347551Y883860D02*
X345713Y882813D01*
G01X338299Y887049D02*
X336461Y886002D01*
G01X342000Y887049D02*
X340162Y886002D01*
G01X349401Y887049D02*
X347563Y886002D01*
G01X343850Y883860D02*
X342012Y882813D01*
G01X349401Y893427D02*
X347563Y892380D01*
G01X343850Y890238D02*
X342012Y889191D01*
G01X342000Y893427D02*
X340162Y892380D01*
G01X343850Y896616D02*
X342012Y895569D01*
G01X349401Y899805D02*
X347563Y898758D01*
G01X349401Y906182D02*
X347563Y905135D01*
G01X349401Y912560D02*
X347563Y911513D01*
G01X343850Y902994D02*
X342012Y901947D01*
G01X342000Y899805D02*
X340162Y898758D01*
G01X342000Y912560D02*
X340162Y911513D01*
G01X343850Y909371D02*
X342012Y908325D01*
G01X342000Y906182D02*
X340162Y905135D01*
G01X349401Y918938D02*
X347563Y917891D01*
G01X349401Y925316D02*
X347563Y924269D01*
G01X342000Y918938D02*
X340162Y917891D01*
G01X343850Y922127D02*
X342012Y921080D01*
G01X343850Y915749D02*
X342012Y914702D01*
G01X342000Y925316D02*
X340162Y924269D01*
G01X349401Y931694D02*
X347563Y930647D01*
G01X349401Y938072D02*
X347563Y937025D01*
G01X343850Y928505D02*
X342012Y927458D01*
G01X342000Y931694D02*
X340162Y930647D01*
G01X343850Y941261D02*
X342012Y940214D01*
G01X342000Y938072D02*
X340162Y937025D01*
G01X343850Y934883D02*
X342012Y933836D01*
G01X349401Y944450D02*
X347563Y943403D01*
G01X349401Y950828D02*
X347563Y949781D01*
G01X349401Y957206D02*
X347563Y956159D01*
G01X342000Y950828D02*
X340162Y949781D01*
G01X343850Y947639D02*
X342012Y946592D01*
G01X342000Y957206D02*
X340162Y956159D01*
G01X342000Y944450D02*
X340162Y943403D01*
G01X343850Y954017D02*
X342012Y952970D01*
G01X349401Y963584D02*
X347563Y962537D01*
G01X349401Y969962D02*
X347563Y968915D01*
G01X343850Y960395D02*
X342012Y959348D01*
G01X343850Y966773D02*
X342012Y965726D01*
G01X342000Y969962D02*
X340162Y968915D01*
G01X342000Y963584D02*
X340162Y962537D01*
G01X349401Y976340D02*
X347563Y975293D01*
G01X349401Y982718D02*
X347563Y981671D01*
G01X347551Y985907D02*
X345713Y984860D01*
G01X342000Y976340D02*
X340162Y975293D01*
G01X345700Y982718D02*
X343862Y981671D01*
G01X343850Y979529D02*
X342012Y978482D01*
G01X343850Y985907D02*
X342012Y984860D01*
G01X342000Y982718D02*
X340162Y981671D01*
G01X343850Y973151D02*
X342012Y972104D01*
G01X349401Y989096D02*
X347563Y988049D01*
G01X349401Y995474D02*
X347563Y994427D01*
G01X349401Y1001852D02*
X347563Y1000805D01*
G01X342000Y989096D02*
X340162Y988049D01*
G01X343850Y998663D02*
X342012Y997616D01*
G01X342000Y995474D02*
X340162Y994427D01*
G01X343850Y992285D02*
X342012Y991238D01*
G01X342000Y1001852D02*
X340162Y1000805D01*
G01X349401Y1008230D02*
X347563Y1007183D01*
G01X343850Y1011419D02*
X342012Y1010372D01*
G01X342000Y1008230D02*
X340162Y1007183D01*
G01X343850Y1005041D02*
X342012Y1003994D01*
G01X337629Y1027009D02*
X335791Y1028056D01*
G01X343181Y1030198D02*
X341343Y1031245D01*
G01X345031Y1027009D02*
X343193Y1028056D01*
G01X337629Y1039765D02*
X335791Y1040812D01*
G01X337629Y1033387D02*
X335791Y1034434D01*
G01X350582Y1030198D02*
X348744Y1031245D01*
G01X345031Y1039765D02*
X343193Y1040812D01*
G01X350582Y1036576D02*
X348744Y1037623D01*
G01X345031Y1033387D02*
X343193Y1034434D01*
G01X350582Y1042954D02*
X348744Y1044001D01*
G01X343181Y1042954D02*
X341343Y1044001D01*
G01X343181Y1036576D02*
X341343Y1037623D01*
G01X337629Y1046143D02*
X335791Y1047190D01*
G01X337629Y1052521D02*
X335791Y1053568D01*
G01X337629Y1058899D02*
X335791Y1059946D01*
G01X352433Y1058899D02*
X350595Y1059946D01*
G01X339480Y1055710D02*
X337642Y1056757D01*
G01X350582Y1055710D02*
X348744Y1056757D01*
G01X345031Y1052521D02*
X343193Y1053568D01*
G01X343181Y1049332D02*
X341343Y1050379D01*
G01X350582Y1049332D02*
X348744Y1050379D01*
G01X345031Y1058899D02*
X343193Y1059946D01*
G01X341330Y1058899D02*
X339492Y1059946D01*
G01X345031Y1046143D02*
X343193Y1047190D01*
G01X343181Y1055710D02*
X341343Y1056757D01*
G01X337629Y1071655D02*
X335791Y1072702D01*
G01X337629Y1065277D02*
X335791Y1066324D01*
G01X343181Y1062088D02*
X341343Y1063135D01*
G01X350582Y1062088D02*
X348744Y1063135D01*
G01X343181Y1068466D02*
X341343Y1069513D01*
G01X345031Y1071655D02*
X343193Y1072702D01*
G01X350582Y1068466D02*
X348744Y1069513D01*
G01X350582Y1074844D02*
X348744Y1075891D01*
G01X345031Y1065277D02*
X343193Y1066324D01*
G01X343181Y1074844D02*
X341343Y1075891D01*
G01X337629Y1078033D02*
X335791Y1079080D01*
G01X337629Y1084411D02*
X335791Y1085458D01*
G01X345031Y1078033D02*
X343193Y1079080D01*
G01X343181Y1081222D02*
X341343Y1082269D01*
G01X350582Y1081222D02*
X348744Y1082269D01*
G01X343181Y1087600D02*
X341343Y1088647D01*
G01X350582Y1087600D02*
X348744Y1088647D01*
G01X345031Y1084411D02*
X343193Y1085458D01*
G01X337629Y1090789D02*
X335791Y1091836D01*
G01X337629Y1103545D02*
X335791Y1104592D01*
G01X337629Y1097167D02*
X335791Y1098214D01*
G01X350582Y1093978D02*
X348744Y1095025D01*
G01X345031Y1090789D02*
X343193Y1091836D01*
G01X350582Y1100356D02*
X348744Y1101403D01*
G01X343181Y1100356D02*
X341343Y1101403D01*
G01X345031Y1097167D02*
X343193Y1098214D01*
G01X345031Y1103545D02*
X343193Y1104592D01*
G01X343181Y1093978D02*
X341343Y1095025D01*
G01X337629Y1109923D02*
X335791Y1110970D01*
G01X337629Y1116301D02*
X335791Y1117348D01*
G01X343181Y1106734D02*
X341343Y1107781D01*
G01X350582Y1106734D02*
X348744Y1107781D01*
G01X345031Y1109923D02*
X343193Y1110970D01*
G01X345031Y1116301D02*
X343193Y1117348D01*
G01X350582Y1113112D02*
X348744Y1114159D01*
G01X350582Y1119490D02*
X348744Y1120537D01*
G01X343181Y1119490D02*
X341343Y1120537D01*
G01X343181Y1113112D02*
X341343Y1114159D01*
G01X337629Y1122679D02*
X335791Y1123726D01*
G01X343181Y1125868D02*
X341343Y1126915D01*
G01X350582Y1125868D02*
X348744Y1126915D01*
G01X350582Y1132246D02*
X348744Y1133293D01*
G01X345031Y1129057D02*
X343193Y1130103D01*
G01X337629Y1129057D02*
X335793Y1130102D01*
X335792Y1130105D01*
G01X343181Y1132246D02*
X341343Y1133293D01*
G01X345031Y1122679D02*
X343193Y1123726D01*
G01X337629Y1135434D02*
X335791Y1136481D01*
G01X337629Y1141812D02*
X335791Y1142859D01*
G01X337629Y1148190D02*
X335791Y1149237D01*
G01X343181Y1138623D02*
X341343Y1139670D01*
G01X345031Y1135434D02*
X343193Y1136481D01*
G01X350582Y1138623D02*
X348744Y1139670D01*
G01X345031Y1148190D02*
X343193Y1149237D01*
G01X350582Y1145001D02*
X348744Y1146048D01*
G01X343181Y1145001D02*
X341343Y1146048D01*
G01X345031Y1141812D02*
X343193Y1142859D01*
G01X337629Y1154568D02*
X335791Y1155615D01*
G01X337629Y1160946D02*
X335791Y1161993D01*
G01X350582Y1151379D02*
X348744Y1152426D01*
G01X339480Y1157757D02*
X337642Y1158804D01*
G01X343181Y1157757D02*
X341343Y1158804D01*
G01X350582Y1157757D02*
X348744Y1158804D01*
G01X341330Y1154568D02*
X339492Y1155615D01*
G01X345031Y1154568D02*
X343193Y1155615D01*
G01X348732Y1154568D02*
X346894Y1155615D01*
G01X339480Y1164135D02*
X337642Y1165182D01*
G01X345031Y1160946D02*
X343193Y1161993D01*
G01X348732Y1160946D02*
X346894Y1161993D01*
G01X350582Y1164135D02*
X348744Y1165182D01*
G01X346881Y1157757D02*
X345043Y1158804D01*
G01X343181Y1151379D02*
X341343Y1152426D01*
G01X351252Y877482D02*
Y879555D01*
X351265Y879568D01*
G01X362354Y877482D02*
X360516Y876435D01*
G01X356803Y880671D02*
X354965Y879624D01*
G01X356803Y874293D02*
Y872066D01*
G01X353102Y887049D02*
X351264Y886002D01*
G01X364204Y887049D02*
X362366Y886002D01*
G01X358653Y883860D02*
X356815Y882813D01*
G01X362354Y883860D02*
X360516Y882813D01*
G01X354952Y883860D02*
X353114Y882813D01*
G01X356803Y887049D02*
X354965Y886002D01*
G01X356803Y893427D02*
X354965Y892380D01*
G01X362354Y890238D02*
X360516Y889191D01*
G01X362354Y896616D02*
X360516Y895569D01*
G01X354952Y890238D02*
X353114Y889191D01*
G01X354952Y896616D02*
X353114Y895569D01*
G01X356803Y899805D02*
X354965Y898758D01*
G01X362354Y902994D02*
X360516Y901947D01*
G01X354952Y902994D02*
X353114Y901947D01*
G01X356803Y912560D02*
X354965Y911513D01*
G01X356803Y906182D02*
X354965Y905135D01*
G01X362354Y909371D02*
X360516Y908325D01*
G01X354952Y909371D02*
X353114Y908324D01*
G01X356803Y918938D02*
X354965Y917891D01*
G01X362354Y915749D02*
X360516Y914702D01*
G01X354952Y915749D02*
X353114Y914702D01*
G01X356803Y925316D02*
X354965Y924269D01*
G01X362354Y922127D02*
X360516Y921080D01*
G01X354952Y922127D02*
X353114Y921080D01*
G01X356803Y931694D02*
X354965Y930647D01*
G01X362354Y928505D02*
X360516Y927458D01*
G01X362354Y934883D02*
X360516Y933836D01*
G01X354952Y934883D02*
X353114Y933836D01*
G01X354952Y928505D02*
X353114Y927458D01*
G01X356803Y938072D02*
X354965Y937025D01*
G01X362354Y941261D02*
X360516Y940214D01*
G01X354952Y941261D02*
X353114Y940214D01*
G01X362354Y947639D02*
X360516Y946592D01*
G01X354952Y947639D02*
X353114Y946592D01*
G01X362354Y954017D02*
X360516Y952970D01*
G01X354952Y954017D02*
X353114Y952970D01*
G01X356803Y957206D02*
X354965Y956159D01*
G01X356803Y944450D02*
X354965Y943403D01*
G01X356803Y950828D02*
X354965Y949781D01*
G01X362354Y960395D02*
X360516Y959348D01*
G01X362354Y966773D02*
X360516Y965726D01*
G01X354952Y960395D02*
X353114Y959348D01*
G01X354952Y966773D02*
X353114Y965726D01*
G01X356803Y963584D02*
X354965Y962537D01*
G01X356803Y969962D02*
X354965Y968915D01*
G01X356803Y976340D02*
X354965Y975293D01*
G01X356803Y982718D02*
X354965Y981671D01*
G01X362354Y973151D02*
X360516Y972104D01*
G01X362354Y979529D02*
X360516Y978482D01*
G01X360504Y982718D02*
X358665Y981671D01*
G01X354952Y973151D02*
X353114Y972104D01*
G01X354952Y979529D02*
X353114Y978482D01*
G01X362354Y985907D02*
X360516Y984860D01*
G01X358653Y985907D02*
X356815Y984860D01*
G01X354952Y985907D02*
X353114Y984860D01*
G01X362354Y998663D02*
X360516Y997616D01*
G01X362354Y992285D02*
X360516Y991238D01*
G01X354952Y992285D02*
X353114Y991238D01*
G01X354952Y998663D02*
X353114Y997616D01*
G01X356803Y989096D02*
X354965Y988049D01*
G01X356803Y995474D02*
X354965Y994427D01*
G01X356803Y1001852D02*
X354965Y1000805D01*
G01X356803Y1008230D02*
X354965Y1007183D01*
G01X362354Y1005041D02*
X360516Y1003994D01*
G01X354952Y1005041D02*
X353114Y1003994D01*
G01X362354Y1011419D02*
X360516Y1010372D01*
G01X354952Y1011419D02*
X353114Y1010372D01*
G01X356133Y1027009D02*
X354295Y1028056D01*
G01X363535Y1027009D02*
X361697Y1028056D01*
G01X357984Y1030198D02*
X356146Y1031245D01*
G01X363535Y1039765D02*
X361697Y1040812D01*
G01X357984Y1042954D02*
X356146Y1044001D01*
G01X356133Y1039765D02*
X354295Y1040812D01*
G01X356133Y1033387D02*
X354295Y1034434D01*
G01X357984Y1036576D02*
X356146Y1037623D01*
G01X363535Y1033387D02*
X361697Y1034434D01*
G01X356133Y1046143D02*
X354295Y1047190D01*
G01X363535Y1046143D02*
X361697Y1047190D01*
G01X356133Y1052521D02*
X354295Y1053568D01*
G01X356133Y1058899D02*
X354295Y1059946D01*
G01X365385Y1055710D02*
X363547Y1056757D01*
G01X357984Y1055710D02*
X356146Y1056757D01*
G01X357984Y1049332D02*
X356146Y1050379D01*
G01X363535Y1052521D02*
X361697Y1053568D01*
G01X367236Y1058899D02*
X365398Y1059946D01*
G01X363535Y1058899D02*
X361697Y1059946D01*
G01X354283Y1055710D02*
X352445Y1056757D01*
G01X357984Y1062088D02*
X356146Y1063135D01*
G01X356133Y1071655D02*
X354295Y1072702D01*
G01X356133Y1065277D02*
X354295Y1066324D01*
G01X357984Y1068466D02*
X356146Y1069513D01*
G01X363535Y1065277D02*
X361697Y1066324D01*
G01X363535Y1071655D02*
X361697Y1072702D01*
G01X357984Y1074844D02*
X356146Y1075891D01*
G01X356133Y1078033D02*
X354295Y1079080D01*
G01X363535Y1078033D02*
X361697Y1079080D01*
G01X356133Y1084411D02*
X354295Y1085458D01*
G01X357984Y1087600D02*
X356146Y1088647D01*
G01X363535Y1084411D02*
X361697Y1085458D01*
G01X357984Y1081222D02*
X356146Y1082269D01*
G01X356133Y1090789D02*
X354295Y1091836D01*
G01X363535Y1090789D02*
X361697Y1091836D01*
G01X357984Y1093978D02*
X356146Y1095025D01*
G01X356133Y1103545D02*
X354295Y1104592D01*
G01X356133Y1097167D02*
X354295Y1098214D01*
G01X363535Y1103545D02*
X361697Y1104592D01*
G01X357984Y1100356D02*
X356146Y1101403D01*
G01X363535Y1097167D02*
X361697Y1098214D01*
G01X357984Y1106734D02*
X356146Y1107781D01*
G01X356133Y1109923D02*
X354295Y1110970D01*
G01X363535Y1109923D02*
X361697Y1110970D01*
G01X363535Y1116301D02*
X361697Y1117348D01*
G01X357984Y1113112D02*
X356146Y1114159D01*
G01X356133Y1116301D02*
X354295Y1117348D01*
G01X357984Y1119490D02*
X356146Y1120537D01*
G01X356133Y1122679D02*
X354295Y1123726D01*
G01X357984Y1125868D02*
X356146Y1126915D01*
G01X363535Y1122679D02*
X361697Y1123726D01*
G01X357984Y1132246D02*
X356146Y1133293D01*
G01X363535Y1129057D02*
X361697Y1130103D01*
G01X356133Y1129057D02*
X354297Y1130102D01*
X354296Y1130105D01*
G01X356133Y1135434D02*
X354295Y1136481D01*
G01X357984Y1138623D02*
X356146Y1139670D01*
G01X363535Y1135434D02*
X361697Y1136481D01*
G01X356133Y1141812D02*
X354295Y1142859D01*
G01X363535Y1141812D02*
X361697Y1142859D01*
G01X363535Y1148190D02*
X361697Y1149237D01*
G01X357984Y1145001D02*
X356146Y1146048D01*
G01X356133Y1148190D02*
X354295Y1149237D01*
G01X365385Y1164135D02*
X363547Y1165182D01*
G01X357984Y1164135D02*
X356146Y1165182D01*
G01X363535Y1160946D02*
X361697Y1161993D01*
G01X365385Y1157757D02*
X363547Y1158804D01*
G01X357984Y1157757D02*
X356146Y1158804D01*
G01X361685Y1157757D02*
X359847Y1158804D01*
G01X354283Y1157757D02*
X352445Y1158804D01*
G01X367236Y1154568D02*
X365398Y1155615D01*
G01X357984Y1151379D02*
X356146Y1152426D01*
G01X363535Y1154568D02*
X361697Y1155615D01*
G01X356133Y1154568D02*
X354295Y1155615D01*
G01X356133Y1160946D02*
X354295Y1161993D01*
G01X371606Y880671D02*
X369768Y879624D01*
G01X375307Y880671D02*
X373469Y879624D01*
G01X377157Y877482D02*
X375319Y876435D01*
G01X379007Y880671D02*
X377169Y879624D01*
G01X369755Y877482D02*
X367917Y876435D01*
G01X373456Y877482D02*
X371618Y876435D01*
G01X380858Y877482D02*
X379020Y876435D01*
G01X367905Y887049D02*
X366067Y886002D01*
G01X367905Y893427D02*
X366067Y892380D01*
G01X369755Y890238D02*
X367917Y889191D01*
G01X375307Y893427D02*
X373469Y892380D01*
G01X369755Y883860D02*
X367917Y882813D01*
G01X375307Y887049D02*
X373469Y886002D01*
G01X380858Y883860D02*
X379020Y882813D01*
G01X379007Y887049D02*
X377169Y886002D01*
G01X380858Y896616D02*
X379020Y895569D01*
G01X373456Y883860D02*
X371618Y882813D01*
G01X377157Y883860D02*
X375319Y882813D01*
G01X380858Y890238D02*
X379020Y889191D01*
G01X369755Y896616D02*
X367917Y895569D01*
G01X367905Y899805D02*
X366067Y898758D01*
G01X367905Y912560D02*
X366067Y911513D01*
G01X369755Y902994D02*
X367917Y901947D01*
G01X375307Y899805D02*
X373469Y898758D01*
G01X380858Y909371D02*
X379020Y908325D01*
G01X375307Y912560D02*
X373469Y911513D01*
G01X375307Y906182D02*
X373469Y905135D01*
G01X369755Y909371D02*
X367917Y908324D01*
G01X367905Y906182D02*
X366067Y905135D01*
G01X380858Y902994D02*
X379020Y901947D01*
G01X367905Y918938D02*
X366067Y917891D01*
G01X375307Y918938D02*
X373469Y917891D01*
G01X369755Y922127D02*
X367917Y921080D01*
G01X375307Y925316D02*
X373469Y924269D01*
G01X380858Y922127D02*
X379020Y921080D01*
G01X369755Y915749D02*
X367917Y914702D01*
G01X367905Y925316D02*
X366067Y924269D01*
G01X380858Y915749D02*
X379020Y914702D01*
G01X367905Y931694D02*
X366067Y930647D01*
G01X367905Y938072D02*
X366067Y937025D01*
G01X369755Y928505D02*
X367917Y927458D01*
G01X380858Y934883D02*
X379020Y933836D01*
G01X375307Y931694D02*
X373469Y930647D01*
G01X369755Y941261D02*
X367917Y940214D01*
G01X375307Y938072D02*
X373469Y937025D01*
G01X380858Y941261D02*
X379020Y940214D01*
G01X380858Y928505D02*
X379020Y927458D01*
G01X369755Y934883D02*
X367917Y933836D01*
G01X367905Y950828D02*
X366067Y949781D01*
G01X367905Y957206D02*
X366067Y956159D01*
G01X369755Y947639D02*
X367917Y946592D01*
G01X375307Y944450D02*
X373469Y943403D01*
G01X375307Y950828D02*
X373469Y949781D01*
G01X375307Y957206D02*
X373469Y956159D01*
G01X380858Y954017D02*
X379020Y952970D01*
G01X380858Y947639D02*
X379020Y946592D01*
G01X369755Y954017D02*
X367917Y952970D01*
G01X367905Y944450D02*
X366067Y943403D01*
G01X367905Y969962D02*
X366067Y968915D01*
G01X369755Y960395D02*
X367917Y959348D01*
G01X369755Y966773D02*
X367917Y965726D01*
G01X375307Y963584D02*
X373469Y962537D01*
G01X375307Y969962D02*
X373469Y968915D01*
G01X380858Y966773D02*
X379020Y965726D01*
G01X380858Y960395D02*
X379020Y959348D01*
G01X367905Y963584D02*
X366067Y962537D01*
G01X367905Y976340D02*
X366067Y975293D01*
G01X371606Y982718D02*
X369768Y981671D01*
G01X369755Y979529D02*
X367917Y978482D01*
G01X375307Y976340D02*
X373469Y975293D01*
G01X375307Y982718D02*
X373469Y981671D01*
G01X369755Y985907D02*
X367917Y984860D01*
G01X380858Y985907D02*
X379020Y984860D01*
G01X373456Y985907D02*
X371618Y984860D01*
G01X380858Y979529D02*
X379020Y978482D01*
G01X380858Y973151D02*
X379020Y972104D01*
G01X369755Y973151D02*
X367917Y972104D01*
G01X367905Y982718D02*
X366067Y981671D01*
G01X367905Y995474D02*
X366067Y994427D01*
G01X367905Y989096D02*
X366067Y988049D01*
G01X369755Y998663D02*
X367917Y997616D01*
G01X380858Y992285D02*
X379020Y991238D01*
G01X375307Y989096D02*
X373469Y988049D01*
G01X380858Y998663D02*
X379020Y997616D01*
G01X375307Y995474D02*
X373469Y994427D01*
G01X375307Y1001852D02*
X373469Y1000805D01*
G01X369755Y992285D02*
X367917Y991238D01*
G01X367905Y1001852D02*
X366067Y1000805D01*
G01X367905Y1008230D02*
X366067Y1007183D01*
G01X375307Y1008230D02*
X373469Y1007183D01*
G01X369755Y1005041D02*
X367917Y1003994D01*
G01X380858Y1005041D02*
X379020Y1003994D01*
G01X369755Y1011419D02*
X367917Y1010372D01*
G01X380858Y1011419D02*
X379020Y1010372D01*
G01X382039Y1027009D02*
X380201Y1028056D01*
G01X369086Y1030198D02*
X367248Y1031245D01*
G01X376488Y1030198D02*
X374650Y1031245D01*
G01X370937Y1027009D02*
X369099Y1028056D01*
G01X369086Y1042954D02*
X367248Y1044001D01*
G01X370937Y1033387D02*
X369099Y1034434D01*
G01X370937Y1039765D02*
X369099Y1040812D01*
G01X382039Y1039765D02*
X380201Y1040812D01*
G01X382039Y1033387D02*
X380201Y1034434D01*
G01X376488Y1036576D02*
X374650Y1037623D01*
G01X376488Y1042954D02*
X374650Y1044001D01*
G01X369086Y1036576D02*
X367248Y1037623D01*
G01X369086Y1049332D02*
X367248Y1050379D01*
G01X382039Y1046143D02*
X380201Y1047190D01*
G01X370937Y1052521D02*
X369099Y1053568D01*
G01X370937Y1058899D02*
X369099Y1059946D01*
G01X382039Y1052521D02*
X380201Y1053568D01*
G01X380189Y1055710D02*
X378351Y1056757D01*
G01X376488Y1049332D02*
X374650Y1050379D01*
G01X376488Y1055710D02*
X374650Y1056757D01*
G01X382039Y1058899D02*
X380201Y1059946D01*
G01X378338Y1058899D02*
X376500Y1059946D01*
G01X370937Y1046143D02*
X369099Y1047190D01*
G01X369086Y1055710D02*
X367248Y1056757D01*
G01X369086Y1062088D02*
X367248Y1063135D01*
G01X369086Y1068466D02*
X367248Y1069513D01*
G01X376488Y1062088D02*
X374650Y1063135D01*
G01X370937Y1071655D02*
X369099Y1072702D01*
G01X382039Y1071655D02*
X380201Y1072702D01*
G01X376488Y1068466D02*
X374650Y1069513D01*
G01X376488Y1074844D02*
X374650Y1075891D01*
G01X382039Y1065277D02*
X380201Y1066324D01*
G01X370937Y1065277D02*
X369099Y1066324D01*
G01X369086Y1074844D02*
X367248Y1075891D01*
G01X369086Y1087600D02*
X367248Y1088647D01*
G01X369086Y1081222D02*
X367248Y1082269D01*
G01X370937Y1078033D02*
X369099Y1079080D01*
G01X382039Y1084411D02*
X380201Y1085458D01*
G01X376488Y1087600D02*
X374650Y1088647D01*
G01X376488Y1081222D02*
X374650Y1082269D01*
G01X382039Y1078033D02*
X380201Y1079080D01*
G01X370937Y1084411D02*
X369099Y1085458D01*
G01X369086Y1100356D02*
X367248Y1101403D01*
G01X370937Y1090789D02*
X369099Y1091836D01*
G01X376488Y1093978D02*
X374650Y1095025D01*
G01X370937Y1097167D02*
X369099Y1098214D01*
G01X382039Y1103545D02*
X380201Y1104592D01*
G01X382039Y1097167D02*
X380201Y1098214D01*
G01X376488Y1100356D02*
X374650Y1101403D01*
G01X370937Y1103545D02*
X369099Y1104592D01*
G01X369086Y1093978D02*
X367248Y1095025D01*
G01X382039Y1090789D02*
X380201Y1091836D01*
G01X369086Y1106734D02*
X367248Y1107781D01*
G01X376488Y1106734D02*
X374650Y1107781D01*
G01X370937Y1109923D02*
X369099Y1110970D01*
G01X370937Y1116301D02*
X369099Y1117348D01*
G01X382039Y1116301D02*
X380201Y1117348D01*
G01X376488Y1113112D02*
X374650Y1114159D01*
G01X369086Y1119490D02*
X367248Y1120537D01*
G01X376488Y1119490D02*
X374650Y1120537D01*
G01X382039Y1109923D02*
X380201Y1110970D01*
G01X369086Y1113112D02*
X367248Y1114159D01*
G01X369086Y1125868D02*
X367248Y1126915D01*
G01X376488Y1125868D02*
X374650Y1126915D01*
G01X382039Y1129057D02*
X380201Y1130103D01*
G01X376488Y1132246D02*
X374650Y1133293D01*
G01X370937Y1129057D02*
X369099Y1130103D01*
G01X369086Y1132246D02*
X367248Y1133293D01*
G01X370937Y1122679D02*
X369099Y1123726D01*
G01X382039Y1122679D02*
X380201Y1123726D01*
G01X369086Y1138623D02*
X367248Y1139670D01*
G01X369086Y1145001D02*
X367248Y1146048D01*
G01X382039Y1141812D02*
X380201Y1142859D01*
G01X376488Y1138623D02*
X374650Y1139670D01*
G01X370937Y1135434D02*
X369099Y1136481D01*
G01X370937Y1148190D02*
X369099Y1149237D01*
G01X376488Y1145001D02*
X374650Y1146048D01*
G01X382039Y1148190D02*
X380201Y1149237D01*
G01X370937Y1141812D02*
X369099Y1142859D01*
G01X382039Y1135434D02*
X380201Y1136481D01*
G01X382039Y1154568D02*
X380201Y1155615D01*
G01X370937Y1154568D02*
X369099Y1155615D01*
G01X374637Y1154568D02*
X372799Y1155615D01*
G01X376488Y1151379D02*
X374650Y1152426D01*
G01X380189Y1157757D02*
X378351Y1158804D01*
G01X376488Y1157757D02*
X374650Y1158804D01*
G01X378338Y1160946D02*
X376500Y1161993D01*
G01X382039Y1160946D02*
X380201Y1161993D01*
G01X374637Y1160946D02*
X372799Y1161993D01*
G01X370937Y1160946D02*
X369099Y1161993D01*
G01X372787Y1157757D02*
X370949Y1158804D01*
G01X369086Y1151379D02*
X367248Y1152426D01*
G01X388259Y877482D02*
X386421Y876435D01*
G01X390110Y880671D02*
X388272Y879624D01*
G01X386409Y874293D02*
X384571Y873246D01*
G01X395661Y877482D02*
X393823Y876435D01*
G01X384559Y877482D02*
X382721Y876435D01*
G01X391960Y877482D02*
X390122Y876435D01*
G01X384559Y883860D02*
X382721Y882813D01*
G01X384559Y890238D02*
X382721Y889191D01*
G01X382708Y893427D02*
X380870Y892380D01*
G01X386409Y887049D02*
X384571Y886002D01*
G01X388259Y883860D02*
X386421Y882813D01*
G01X395661Y883860D02*
X393823Y882813D01*
G01X390110Y887049D02*
X388272Y886002D01*
G01X391960Y883860D02*
X390122Y882813D01*
G01X393811Y893427D02*
X391973Y892380D01*
G01X391960Y896616D02*
X390122Y895569D01*
G01X388259Y890238D02*
X386421Y889191D01*
G01X395661Y890238D02*
X393823Y889191D01*
G01X393811Y887049D02*
X391973Y886002D01*
G01X395661Y896616D02*
X393823Y895569D01*
G01X382708Y887049D02*
X380870Y886002D01*
G01X384559Y896616D02*
X382721Y895569D01*
G01X391960Y890238D02*
X390122Y889191D01*
G01X388259Y896616D02*
X386421Y895569D01*
G01X384559Y902994D02*
X382721Y901947D01*
G01X382708Y899805D02*
X380870Y898758D01*
G01X382708Y912560D02*
X380870Y911513D01*
G01X382708Y906182D02*
X380870Y905135D01*
G01X395661Y902994D02*
X393823Y901947D01*
G01X393811Y899805D02*
X391973Y898758D01*
G01X391960Y902994D02*
X390122Y901947D01*
G01X388259Y902994D02*
X386421Y901947D01*
G01X393811Y906182D02*
X391973Y905135D01*
G01X393811Y912560D02*
X391973Y911513D01*
G01X391960Y909371D02*
X390122Y908325D01*
G01X395661Y909371D02*
X393823Y908325D01*
G01X388259Y909371D02*
X386421Y908325D01*
G01X384559Y909371D02*
X382721Y908325D01*
G01X384559Y915749D02*
X382721Y914702D01*
G01X382708Y918938D02*
X380870Y917891D01*
G01X382708Y925316D02*
X380870Y924269D01*
G01X388259Y915749D02*
X386421Y914702D01*
G01X393811Y918938D02*
X391973Y917891D01*
G01X395661Y915749D02*
X393823Y914702D01*
G01X391960Y915749D02*
X390122Y914702D01*
G01X391960Y922127D02*
X390122Y921080D01*
G01X393811Y925316D02*
X391973Y924269D01*
G01X395661Y922127D02*
X393823Y921080D01*
G01X384559Y922127D02*
X382721Y921080D01*
G01X388259Y922127D02*
X386421Y921080D01*
G01X384559Y928505D02*
X382721Y927458D01*
G01X384559Y934883D02*
X382721Y933836D01*
G01X382708Y931694D02*
X380870Y930647D01*
G01X388259Y928505D02*
X386421Y927458D01*
G01X388259Y934883D02*
X386421Y933836D01*
G01X395661Y928505D02*
X393823Y927458D01*
G01X391960Y928505D02*
X390122Y927458D01*
G01X395661Y934883D02*
X393823Y933836D01*
G01X393811Y931694D02*
X391973Y930647D01*
G01X391960Y934883D02*
X390122Y933836D01*
G01X391960Y941261D02*
X390122Y940214D01*
G01X395661Y941261D02*
X393823Y940214D01*
G01X384559Y941261D02*
X382721Y940214D01*
G01X388259Y941261D02*
X386421Y940214D01*
G01X382708Y938072D02*
X380870Y937025D01*
G01X384559Y947639D02*
X382721Y946592D01*
G01X382708Y944450D02*
X380870Y943403D01*
G01X382708Y950828D02*
X380870Y949781D01*
G01X382708Y957206D02*
X380870Y956159D01*
G01X388259Y947639D02*
X386421Y946592D01*
G01X393811Y944450D02*
X391973Y943403D01*
G01X393811Y950828D02*
X391973Y949781D01*
G01X395661Y947639D02*
X393823Y946592D01*
G01X391960Y947639D02*
X390122Y946592D01*
G01X393811Y957206D02*
X391973Y956159D01*
G01X391960Y954017D02*
X390122Y952970D01*
G01X395661Y954017D02*
X393823Y952970D01*
G01X384559Y954017D02*
X382721Y952970D01*
G01X388259Y954017D02*
X386421Y952970D01*
G01X384559Y960395D02*
X382721Y959348D01*
G01X382708Y963584D02*
X380870Y962537D01*
G01X382708Y969962D02*
X380870Y968915D01*
G01X395661Y960395D02*
X393823Y959348D01*
G01X391960Y960395D02*
X390122Y959348D01*
G01X391960Y966773D02*
X390122Y965726D01*
G01X388259Y960395D02*
X386421Y959348D01*
G01X393811Y963584D02*
X391973Y962537D01*
G01X393811Y969962D02*
X391973Y968915D01*
G01X395661Y966773D02*
X393823Y965726D01*
G01X384559Y966773D02*
X382721Y965726D01*
G01X388259Y966773D02*
X386421Y965726D01*
G01X388259Y985907D02*
X386421Y984860D01*
G01X384559Y973151D02*
X382721Y972104D01*
G01X382708Y976340D02*
X380870Y975293D01*
G01X395661Y973151D02*
X393823Y972104D01*
G01X391960Y973151D02*
X390122Y972104D01*
G01X391960Y979529D02*
X390122Y978482D01*
G01X386409Y982718D02*
X384571Y981671D01*
G01X393811Y982718D02*
X391973Y981671D01*
G01X393811Y976340D02*
X391973Y975293D01*
G01X388259Y973151D02*
X386421Y972104D01*
G01X395661Y985907D02*
X393823Y984860D01*
G01X382708Y982718D02*
X380870Y981671D01*
G01X384559Y985907D02*
X382721Y984860D01*
G01X390110Y982718D02*
X388272Y981671D01*
G01X391960Y985907D02*
X390122Y984860D01*
G01X388259Y979529D02*
X386421Y978482D01*
G01X395661Y979529D02*
X393823Y978482D01*
G01X384559Y979529D02*
X382721Y978482D01*
G01X393811Y989096D02*
X391973Y988049D01*
G01X386409Y995474D02*
X384571Y994427D01*
G01X386409Y989096D02*
X384571Y988049D01*
G01X393811Y995474D02*
X391973Y994427D01*
G01X395661Y992285D02*
X393823Y991238D01*
G01X388259Y992285D02*
X386421Y991238D01*
G01X388259Y998663D02*
X386421Y997616D01*
G01X393811Y1001852D02*
X391973Y1000805D01*
G01X386409Y1001852D02*
X384571Y1000805D01*
G01X395661Y998663D02*
X393823Y997616D01*
G01X382708Y989096D02*
X380870Y988049D01*
G01X382708Y995474D02*
X380870Y994427D01*
G01X384559Y998663D02*
X382721Y997616D01*
G01X384559Y992285D02*
X382721Y991238D01*
G01X382708Y1001852D02*
X380870Y1000805D01*
G01X390110Y995474D02*
X388272Y994427D01*
G01X391960Y998663D02*
X390122Y997616D01*
G01X390110Y989096D02*
X388272Y988049D01*
G01X391960Y992285D02*
X390122Y991238D01*
G01X390110Y1001852D02*
X388272Y1000805D01*
G01X388259Y1005041D02*
X386421Y1003994D01*
G01X384559Y1011419D02*
X382721Y1010372D01*
G01X391960Y1011419D02*
X390122Y1010372D01*
G01X393811Y1008230D02*
X391973Y1007183D01*
G01X395661Y1005041D02*
X393823Y1003994D01*
G01X386409Y1008230D02*
X384571Y1007183D01*
G01X382708Y1008230D02*
X380870Y1007183D01*
G01X384559Y1005041D02*
X382721Y1003994D01*
G01X390110Y1008230D02*
X388272Y1007183D01*
G01X391960Y1005041D02*
X390122Y1003994D01*
G01X388259Y1011419D02*
X386421Y1010372D01*
G01X395661Y1011419D02*
X393823Y1010372D01*
G01X389441Y1027009D02*
X387603Y1028056D01*
G01X396842Y1027009D02*
X395004Y1028056D01*
G01X387590Y1030198D02*
X385752Y1031245D01*
G01X394992Y1030198D02*
X393154Y1031245D01*
G01X385740Y1027009D02*
X383902Y1028056D01*
G01X393141Y1027009D02*
X391303Y1028056D01*
G01X391291Y1030198D02*
X389453Y1031245D01*
G01X383889Y1030198D02*
X382051Y1031245D01*
G01X394992Y1042954D02*
X393154Y1044001D01*
G01X387590Y1036576D02*
X385752Y1037623D01*
G01X387590Y1042954D02*
X385752Y1044001D01*
G01X396842Y1039765D02*
X395004Y1040812D01*
G01X389441Y1033387D02*
X387603Y1034434D01*
G01X389441Y1039765D02*
X387603Y1040812D01*
G01X396842Y1033387D02*
X395004Y1034434D01*
G01X394992Y1036576D02*
X393154Y1037623D01*
G01X385740Y1033387D02*
X383902Y1034434D01*
G01X385740Y1039765D02*
X383902Y1040812D01*
G01X391291Y1042954D02*
X389453Y1044001D01*
G01X393141Y1039765D02*
X391303Y1040812D01*
G01X391291Y1036576D02*
X389453Y1037623D01*
G01X393141Y1033387D02*
X391303Y1034434D01*
G01X383889Y1042954D02*
X382051Y1044001D01*
G01X383889Y1036576D02*
X382051Y1037623D01*
G01X396842Y1046143D02*
X395004Y1047190D01*
G01X389441Y1046143D02*
X387603Y1047190D01*
G01X389441Y1052521D02*
X387603Y1053568D01*
G01X393141Y1058899D02*
X391303Y1059946D01*
G01X396842Y1052521D02*
X395004Y1053568D01*
G01X387590Y1049332D02*
X385752Y1050379D01*
G01X394992Y1055710D02*
X393154Y1056757D01*
G01X394992Y1049332D02*
X393154Y1050379D01*
G01X391291Y1055710D02*
X389453Y1056757D01*
G01X389441Y1058899D02*
X387603Y1059946D01*
G01X385740Y1058899D02*
X383902Y1059946D01*
G01X396842Y1058899D02*
X395004Y1059946D01*
G01X385740Y1046143D02*
X383902Y1047190D01*
G01X393141Y1046143D02*
X391303Y1047190D01*
G01X383889Y1049332D02*
X382051Y1050379D01*
G01X391291Y1049332D02*
X389453Y1050379D01*
G01X393141Y1052521D02*
X391303Y1053568D01*
G01X387590Y1055710D02*
X385752Y1056757D01*
G01X383889Y1062088D02*
X382051Y1063135D01*
G01X383889Y1068466D02*
X382051Y1069513D01*
G01X394992Y1062088D02*
X393154Y1063135D01*
G01X396842Y1065277D02*
X395004Y1066324D01*
G01X389441Y1065277D02*
X387603Y1066324D01*
G01X385740Y1065277D02*
X383902Y1066324D01*
G01X393141Y1071655D02*
X391303Y1072702D01*
G01X393141Y1065277D02*
X391303Y1066324D01*
G01X394992Y1068466D02*
X393154Y1069513D01*
G01X383889Y1074844D02*
X382051Y1075891D01*
G01X394992Y1074844D02*
X393154Y1075891D01*
G01X389441Y1071655D02*
X387603Y1072702D01*
G01X385740Y1071655D02*
X383902Y1072702D01*
G01X396842Y1071655D02*
X395004Y1072702D01*
G01X383889Y1087600D02*
X382051Y1088647D01*
G01X383889Y1081222D02*
X382051Y1082269D01*
G01X389441Y1078033D02*
X387603Y1079080D01*
G01X385740Y1078033D02*
X383902Y1079080D01*
G01X393141Y1078033D02*
X391303Y1079080D01*
G01X396842Y1078033D02*
X395004Y1079080D01*
G01X394992Y1081222D02*
X393154Y1082269D01*
G01X393141Y1084411D02*
X391303Y1085458D01*
G01X394992Y1087600D02*
X393154Y1088647D01*
G01X389441Y1084411D02*
X387603Y1085458D01*
G01X385740Y1084411D02*
X383902Y1085458D01*
G01X396842Y1084411D02*
X395004Y1085458D01*
G01X383889Y1093978D02*
X382051Y1095025D01*
G01X385740Y1090789D02*
X383902Y1091836D01*
G01X394992Y1093978D02*
X393154Y1095025D01*
G01X393141Y1090789D02*
X391303Y1091836D01*
G01X396842Y1090789D02*
X395004Y1091836D01*
G01X389441Y1090789D02*
X387603Y1091836D01*
G01X393141Y1097167D02*
X391303Y1098214D01*
G01X393141Y1103545D02*
X391303Y1104592D01*
G01X396842Y1103545D02*
X395004Y1104592D01*
G01X389441Y1103545D02*
X387603Y1104592D01*
G01X385740Y1103545D02*
X383902Y1104592D01*
G01X389441Y1097167D02*
X387603Y1098214D01*
G01X385740Y1097167D02*
X383902Y1098214D01*
G01X396842Y1097167D02*
X395004Y1098214D01*
G01X383889Y1100356D02*
X382051Y1101403D01*
G01X383889Y1106734D02*
X382051Y1107781D01*
G01X383889Y1113112D02*
X382051Y1114159D01*
G01X385740Y1109923D02*
X383902Y1110970D01*
G01X389441Y1109923D02*
X387603Y1110970D01*
G01X394992Y1106734D02*
X393154Y1107781D01*
G01X393141Y1109923D02*
X391303Y1110970D01*
G01X396842Y1109923D02*
X395004Y1110970D01*
G01X393141Y1116301D02*
X391303Y1117348D01*
G01X394992Y1113112D02*
X393154Y1114159D01*
G01X383889Y1119490D02*
X382051Y1120537D01*
G01X394992Y1119490D02*
X393154Y1120537D01*
G01X385740Y1116301D02*
X383902Y1117348D01*
G01X389441Y1116301D02*
X387603Y1117348D01*
G01X396842Y1116301D02*
X395004Y1117348D01*
G01X383889Y1125868D02*
X382051Y1126915D01*
G01X383889Y1132246D02*
X382051Y1133293D01*
G01X385740Y1122679D02*
X383902Y1123726D01*
G01X389441Y1122679D02*
X387603Y1123726D01*
G01X394992Y1125868D02*
X393154Y1126915D01*
G01X393141Y1122679D02*
X391303Y1123726D01*
G01X396842Y1122679D02*
X395004Y1123726D01*
G01X394992Y1132246D02*
X393154Y1133293D01*
G01X393141Y1129057D02*
X391305Y1130102D01*
X391304Y1130105D01*
G01X385740Y1129057D02*
X383902Y1130103D01*
G01X389441Y1129057D02*
X387603Y1130103D01*
G01X396842Y1129057D02*
X395004Y1130103D01*
G01X383889Y1138623D02*
X382051Y1139670D01*
G01X383889Y1145001D02*
X382051Y1146048D01*
G01X394992Y1138623D02*
X393154Y1139670D01*
G01X396842Y1135434D02*
X395004Y1136481D01*
G01X393141Y1135434D02*
X391303Y1136481D01*
G01X385740Y1135434D02*
X383902Y1136481D01*
G01X389441Y1135434D02*
X387603Y1136481D01*
G01X393141Y1141812D02*
X391303Y1142859D01*
G01X394992Y1145001D02*
X393154Y1146048D01*
G01X396842Y1148190D02*
X395004Y1149237D01*
G01X385740Y1148190D02*
X383902Y1149237D01*
G01X389441Y1148190D02*
X387603Y1149237D01*
G01X393141Y1148190D02*
X391303Y1149237D01*
G01X385740Y1141812D02*
X383902Y1142859D01*
G01X389441Y1141812D02*
X387603Y1142859D01*
G01X396842Y1141812D02*
X395004Y1142859D01*
G01X391291Y1157757D02*
X389453Y1158804D01*
G01X393141Y1154568D02*
X391303Y1155615D01*
G01X396842Y1154568D02*
X395004Y1155615D01*
G01X385740Y1154568D02*
X383902Y1155615D01*
G01X389441Y1154568D02*
X387603Y1155615D01*
G01X389441Y1160946D02*
X387603Y1161993D01*
G01X394992Y1151379D02*
X393154Y1152426D01*
G01X383889Y1151379D02*
X382051Y1152426D01*
G01X385740Y1160946D02*
X383902Y1161993D01*
G01X396842Y1160946D02*
X395004Y1161993D01*
G01X393141Y1160946D02*
X391303Y1161993D01*
G01X408614Y874293D02*
X410477Y873246D01*
G01X399362Y877482D02*
X397524Y876435D01*
G01X401212Y874293D02*
X399374Y873246D01*
G01X401212Y880671D02*
X399374Y879624D01*
G01X406763Y877482D02*
X404925Y876435D01*
G01X403063Y877482D02*
X401225Y876435D01*
G01X399362Y883860D02*
X397524Y882813D01*
G01X399362Y890238D02*
X397524Y889191D01*
G01X403063Y883860D02*
X401225Y882813D01*
G01X410464Y883860D02*
X408626Y882813D01*
G01X406763Y883860D02*
X404925Y882813D01*
G01X403063Y896616D02*
X401225Y895569D01*
G01X410464Y890238D02*
X408626Y889191D01*
G01X406763Y890238D02*
X404925Y889191D01*
G01X404913Y893427D02*
X403075Y892380D01*
G01X399362Y896616D02*
X397524Y895569D01*
G01X404913Y887049D02*
X403075Y886002D01*
G01X403063Y890238D02*
X401225Y889191D01*
G01X410464Y896616D02*
X408626Y895569D01*
G01X406763Y896616D02*
X404925Y895569D01*
G01X399362Y902994D02*
X397524Y901947D01*
G01X403063Y902994D02*
X401225Y901947D01*
G01X410464Y902994D02*
X408626Y901947D01*
G01X406763Y902994D02*
X404925Y901947D01*
G01X404913Y899805D02*
X403075Y898758D01*
G01X404913Y906182D02*
X403075Y905135D01*
G01X404913Y912560D02*
X403075Y911513D01*
G01X403063Y909371D02*
X401225Y908324D01*
G01X399362Y909371D02*
X397524Y908325D01*
G01X410464Y909371D02*
X408626Y908325D01*
G01X406763Y909371D02*
X404925Y908324D01*
G01X399362Y915749D02*
X397524Y914702D01*
G01X403063Y915749D02*
X401225Y914702D01*
G01X410464Y915749D02*
X408626Y914702D01*
G01X404913Y918938D02*
X403075Y917891D01*
G01X406763Y915749D02*
X404925Y914702D01*
G01X403063Y922127D02*
X401225Y921080D01*
G01X404913Y925316D02*
X403075Y924269D01*
G01X399362Y922127D02*
X397524Y921080D01*
G01X410464Y922127D02*
X408626Y921080D01*
G01X406763Y922127D02*
X404925Y921080D01*
G01X403063Y934883D02*
X401225Y933836D01*
G01X410464Y928505D02*
X408626Y927458D01*
G01X406763Y928505D02*
X404925Y927458D01*
G01X404913Y931694D02*
X403075Y930647D01*
G01X403063Y941261D02*
X401225Y940214D01*
G01X399362Y928505D02*
X397524Y927458D01*
G01X399362Y934883D02*
X397524Y933836D01*
G01X403063Y928505D02*
X401225Y927458D01*
G01X399362Y941261D02*
X397524Y940214D01*
G01X408614Y931694D02*
X406776Y930647D01*
G01X410464Y941261D02*
X408626Y940214D01*
G01X406763Y941261D02*
X404925Y940214D01*
G01X399362Y947639D02*
X397524Y946592D01*
G01X403063Y947639D02*
X401225Y946592D01*
G01X404913Y944450D02*
X403075Y943403D01*
G01X410464Y947639D02*
X408626Y946592D01*
G01X404913Y950828D02*
X403075Y949781D01*
G01X406763Y947639D02*
X404925Y946592D01*
G01X403063Y954017D02*
X401225Y952970D01*
G01X404913Y957206D02*
X403075Y956159D01*
G01X399362Y954017D02*
X397524Y952970D01*
G01X410464Y954017D02*
X408626Y952970D01*
G01X406763Y954017D02*
X404925Y952970D01*
G01X399362Y960395D02*
X397524Y959348D01*
G01X403063Y966773D02*
X401225Y965726D01*
G01X403063Y960395D02*
X401225Y959348D01*
G01X410464Y960395D02*
X408626Y959348D01*
G01X406763Y960395D02*
X404925Y959348D01*
G01X404913Y963584D02*
X403075Y962537D01*
G01X404913Y969962D02*
X403075Y968915D01*
G01X399362Y966773D02*
X397524Y965726D01*
G01X410464Y966773D02*
X408626Y965726D01*
G01X406763Y966773D02*
X404925Y965726D01*
G01X399362Y973151D02*
X397524Y972104D01*
G01X403063Y973151D02*
X401225Y972104D01*
G01X410464Y973151D02*
X408626Y972104D01*
G01X406763Y973151D02*
X404925Y972104D01*
G01X401212Y982718D02*
X399374Y981671D01*
G01X408614Y982718D02*
X406776Y981671D01*
G01X403063Y979529D02*
X401225Y978482D01*
G01X404913Y976340D02*
X403075Y975293D01*
G01X403063Y985907D02*
X401225Y984860D01*
G01X410464Y985907D02*
X408626Y984860D01*
G01X397511Y982718D02*
X395673Y981671D01*
G01X399362Y979529D02*
X397524Y978482D01*
G01X399362Y985907D02*
X397524Y984860D01*
G01X406763Y979529D02*
X404925Y978482D01*
G01X410464Y979529D02*
X408626Y978482D01*
G01X404913Y982718D02*
X403075Y981671D01*
G01X406763Y985907D02*
X404925Y984860D01*
G01X410464Y992285D02*
X408626Y991238D01*
G01X401212Y989096D02*
X399374Y988049D01*
G01X401212Y995474D02*
X399374Y994427D01*
G01X408614Y989096D02*
X406776Y988049D01*
G01X403063Y992285D02*
X401225Y991238D01*
G01X403063Y998663D02*
X401225Y997616D01*
G01X401212Y1001852D02*
X399374Y1000805D01*
G01X397511Y1001852D02*
X395673Y1000805D01*
G01X397511Y989096D02*
X395673Y988049D01*
G01X397511Y995474D02*
X395673Y994427D01*
G01X399362Y992285D02*
X397524Y991238D01*
G01X404913Y989096D02*
X403075Y988049D01*
G01X406763Y992285D02*
X404925Y991238D01*
G01X399362Y998663D02*
X397524Y997616D01*
G01X404913Y995474D02*
X403075Y994427D01*
G01X404913Y1001852D02*
X403075Y1000805D01*
G01X397511Y1008230D02*
X395673Y1007183D01*
G01X399362Y1011419D02*
X397524Y1010372D01*
G01X401212Y1008230D02*
X399374Y1007183D01*
G01X403063Y1005041D02*
X401225Y1003994D01*
G01X403063Y1011419D02*
X401225Y1010372D01*
G01X399362Y1005041D02*
X397524Y1003994D01*
G01X404913Y1008230D02*
X403075Y1007183D01*
G01X400543Y1027009D02*
X398705Y1028056D01*
G01X402393Y1030198D02*
X400555Y1031245D01*
G01X404244Y1027009D02*
X402406Y1028056D01*
G01X406094Y1030198D02*
X404256Y1031245D01*
G01X398693Y1030198D02*
X396855Y1031245D01*
G01X400543Y1033387D02*
X398705Y1034434D01*
G01X404244Y1039765D02*
X402406Y1040812D01*
G01X402393Y1036576D02*
X400555Y1037623D01*
G01X402393Y1042954D02*
X400555Y1044001D01*
G01X400543Y1039765D02*
X398705Y1040812D01*
G01X406094Y1042954D02*
X404256Y1044001D01*
G01X406094Y1036576D02*
X404256Y1037623D01*
G01X404244Y1033387D02*
X402406Y1034434D01*
G01X398693Y1036576D02*
X396855Y1037623D01*
G01X398693Y1042954D02*
X396855Y1044001D01*
G01X404244Y1046143D02*
X402406Y1047190D01*
G01X411645Y1046143D02*
X409807Y1047190D01*
G01X404244Y1052521D02*
X402406Y1053568D01*
G01X409795Y1055710D02*
X407957Y1056757D01*
G01X404244Y1058899D02*
X402406Y1059946D01*
G01X411645Y1052521D02*
X409807Y1053568D01*
G01X402393Y1055710D02*
X400555Y1056757D01*
G01X402393Y1049332D02*
X400555Y1050379D01*
G01X409795Y1049332D02*
X407957Y1050379D01*
G01X406094Y1049332D02*
X404256Y1050379D01*
G01X407944Y1046143D02*
X406107Y1047190D01*
G01X400543Y1046143D02*
X398705Y1047190D01*
G01X406094Y1055710D02*
X404256Y1056757D01*
G01X407944Y1052521D02*
X406107Y1053568D01*
G01X407944Y1058899D02*
X406107Y1059946D01*
G01X411645Y1058899D02*
X409807Y1059946D01*
G01X398693Y1055710D02*
X396855Y1056757D01*
G01X400543Y1052521D02*
X398705Y1053568D01*
G01X400543Y1058899D02*
X398705Y1059946D01*
G01X398693Y1049332D02*
X396855Y1050379D01*
G01X400543Y1065277D02*
X398705Y1066324D01*
G01X406094Y1062088D02*
X404256Y1063135D01*
G01X404244Y1071655D02*
X402406Y1072702D01*
G01X406094Y1068466D02*
X404256Y1069513D01*
G01X407944Y1065277D02*
X406107Y1066324D01*
G01X411645Y1065277D02*
X409807Y1066324D01*
G01X404244Y1065277D02*
X402406Y1066324D01*
G01X406094Y1074844D02*
X404256Y1075891D01*
G01X411645Y1071655D02*
X409807Y1072702D01*
G01X407944Y1071655D02*
X406107Y1072702D01*
G01X400543Y1071655D02*
X398705Y1072702D01*
G01X400543Y1078033D02*
X398705Y1079080D01*
G01X407944Y1078033D02*
X406107Y1079080D01*
G01X411645Y1078033D02*
X409807Y1079080D01*
G01X404244Y1078033D02*
X402406Y1079080D01*
G01X406094Y1087600D02*
X404256Y1088647D01*
G01X404244Y1084411D02*
X402406Y1085458D01*
G01X406094Y1081222D02*
X404256Y1082269D01*
G01X411645Y1084411D02*
X409807Y1085458D01*
G01X407944Y1084411D02*
X406107Y1085458D01*
G01X400543Y1084411D02*
X398705Y1085458D01*
G01X400543Y1090789D02*
X398705Y1091836D01*
G01X400543Y1103545D02*
X398705Y1104592D01*
G01X406094Y1093978D02*
X404256Y1095025D01*
G01X407944Y1090789D02*
X406107Y1091836D01*
G01X411645Y1090789D02*
X409807Y1091836D01*
G01X404244Y1090789D02*
X402406Y1091836D01*
G01X404244Y1097167D02*
X402406Y1098214D01*
G01X404244Y1103545D02*
X402406Y1104592D01*
G01X411645Y1097167D02*
X409807Y1098214D01*
G01X407944Y1097167D02*
X406107Y1098214D01*
G01X400543Y1097167D02*
X398705Y1098214D01*
G01X400543Y1109923D02*
X398705Y1110970D01*
G01X406094Y1106734D02*
X404256Y1107781D01*
G01X407944Y1109923D02*
X406107Y1110970D01*
G01X411645Y1109923D02*
X409807Y1110970D01*
G01X404244Y1109923D02*
X402406Y1110970D01*
G01X406094Y1113112D02*
X404256Y1114159D01*
G01X404244Y1116301D02*
X402406Y1117348D01*
G01X406094Y1119490D02*
X404256Y1120537D01*
G01X411645Y1116301D02*
X409807Y1117348D01*
G01X407944Y1116301D02*
X406107Y1117348D01*
G01X409795Y1106734D02*
X407957Y1107781D01*
G01X400543Y1116301D02*
X398705Y1117348D01*
G01X400543Y1122679D02*
X398705Y1123726D01*
G01X407944Y1122679D02*
X406107Y1123726D01*
G01X411645Y1122679D02*
X409807Y1123726D01*
G01X404244Y1122679D02*
X402406Y1123726D01*
G01X406094Y1125868D02*
X404256Y1126915D01*
G01X406094Y1132246D02*
X404256Y1133293D01*
G01X404244Y1129057D02*
X402406Y1130103D01*
G01X411645Y1129057D02*
X409807Y1130103D01*
G01X407944Y1129057D02*
X406107Y1130103D01*
G01X400543Y1129057D02*
X398705Y1130103D01*
G01X400543Y1135434D02*
X398705Y1136481D01*
G01X400543Y1148190D02*
X398705Y1149237D01*
G01X404244Y1141812D02*
X402406Y1142859D01*
G01X406094Y1138623D02*
X404256Y1139670D01*
G01X407944Y1135434D02*
X406107Y1136481D01*
G01X411645Y1135434D02*
X409807Y1136481D01*
G01X404244Y1135434D02*
X402406Y1136481D01*
G01X406094Y1145001D02*
X404256Y1146048D01*
G01X407944Y1148190D02*
X406107Y1149237D01*
G01X411645Y1148190D02*
X409807Y1149237D01*
G01X404244Y1148190D02*
X402406Y1149237D01*
G01X411645Y1141812D02*
X409807Y1142859D01*
G01X407944Y1141812D02*
X406107Y1142859D01*
G01X400543Y1141812D02*
X398705Y1142859D01*
G01X400543Y1154568D02*
X398705Y1155615D01*
G01X400543Y1160946D02*
X398705Y1161993D01*
G01X407944Y1154568D02*
X406107Y1155615D01*
G01X411645Y1154568D02*
X409807Y1155615D01*
G01X404244Y1154568D02*
X402406Y1155615D01*
G01X402393Y1157757D02*
X400555Y1158804D01*
G01X411645Y1160946D02*
X409807Y1161993D01*
G01X402393Y1164135D02*
X400555Y1165182D01*
G01X406094Y1151379D02*
X404256Y1152426D01*
G01X404244Y1160946D02*
X402406Y1161993D01*
G01X407944Y1160946D02*
X406107Y1161993D01*
G01X423417Y874293D02*
X421579Y873246D01*
G01D02*
X419716Y874293D01*
G01X412315Y880671D02*
X412327Y882813D01*
G01X417866Y877482D02*
X416028Y876435D01*
G01X414165Y877482D02*
X412327Y876435D01*
G01X425267Y877482D02*
X423429Y876435D01*
G01X412327Y882813D02*
X414165Y883860D01*
G01Y896616D02*
X412327Y895569D01*
G01X416015Y893427D02*
X414177Y892380D01*
G01X421567Y883860D02*
X419729Y882813D01*
G01X417866Y883860D02*
X416028Y882813D01*
G01X425267Y896616D02*
X423429Y895569D01*
G01X417866Y890238D02*
X416028Y889191D01*
G01X421567Y890238D02*
X419729Y889191D01*
G01X414165Y890238D02*
X412327Y889191D01*
G01X425267Y890238D02*
X423429Y889191D01*
G01X421567Y896616D02*
X419729Y895569D01*
G01X417866Y896616D02*
X416028Y895569D01*
G01X416015Y887049D02*
X414177Y886002D01*
G01X414165Y902994D02*
X412327Y901947D01*
G01X416015Y899805D02*
X414177Y898758D01*
G01X416015Y906182D02*
X414177Y905135D01*
G01X416015Y912560D02*
X414177Y911513D01*
G01X414165Y909371D02*
X412327Y908325D01*
G01X425267Y902994D02*
X423429Y901947D01*
G01X421567Y902994D02*
X419729Y901947D01*
G01X417866Y902994D02*
X416028Y901947D01*
G01X425267Y909371D02*
X423429Y908324D01*
G01X421567Y909371D02*
X419729Y908325D01*
G01X417866Y909371D02*
X416028Y908325D01*
G01X416015Y918938D02*
X414177Y917891D01*
G01X414165Y915749D02*
X412327Y914702D01*
G01X416015Y925316D02*
X414177Y924269D01*
G01X414165Y922127D02*
X412327Y921080D01*
G01X425267Y915749D02*
X423429Y914702D01*
G01X421567Y915749D02*
X419729Y914702D01*
G01X417866Y915749D02*
X416028Y914702D01*
G01X425267Y922127D02*
X423429Y921080D01*
G01X417866Y922127D02*
X416028Y921080D01*
G01X421567Y922127D02*
X419729Y921080D01*
G01X414165Y928505D02*
X412327Y927458D01*
G01X414165Y934883D02*
X412327Y933836D01*
G01X416015Y931694D02*
X414177Y930647D01*
G01X414165Y941261D02*
X412327Y940214D01*
G01X416015Y938072D02*
X414177Y937025D01*
G01X425267Y928505D02*
X423429Y927458D01*
G01X421567Y928505D02*
X419729Y927458D01*
G01X425267Y934883D02*
X423429Y933836D01*
G01X421567Y934883D02*
X419729Y933836D01*
G01X417866Y928505D02*
X416028Y927458D01*
G01X417866Y934883D02*
X416028Y933836D01*
G01X425267Y941261D02*
X423429Y940214D01*
G01X412315Y931694D02*
X410477Y930647D01*
G01X419716Y931694D02*
X417878Y930647D01*
G01X423417Y931694D02*
X421579Y930647D01*
G01X417866Y941261D02*
X416028Y940214D01*
G01X421567Y941261D02*
X419729Y940214D01*
G01X416015Y950828D02*
X414177Y949781D01*
G01X414165Y947639D02*
X412327Y946592D01*
G01X416015Y944450D02*
X414177Y943403D01*
G01X414165Y954017D02*
X412327Y952970D01*
G01X416015Y957206D02*
X414177Y956159D01*
G01X417866Y947639D02*
X416028Y946592D01*
G01X425267Y947639D02*
X423429Y946592D01*
G01X421567Y947639D02*
X419729Y946592D01*
G01X425267Y954017D02*
X423429Y952970D01*
G01X417866Y954017D02*
X416028Y952970D01*
G01X421567Y954017D02*
X419729Y952970D01*
G01X414165Y966773D02*
X412327Y965726D01*
G01X414165Y960395D02*
X412327Y959348D01*
G01X416015Y963584D02*
X414177Y962537D01*
G01X416015Y969962D02*
X414177Y968915D01*
G01X425267Y966773D02*
X423429Y965726D01*
G01X417866Y960395D02*
X416028Y959348D01*
G01X425267Y960395D02*
X423429Y959348D01*
G01X421567Y960395D02*
X419729Y959348D01*
G01X421567Y966773D02*
X419729Y965726D01*
G01X417866Y966773D02*
X416028Y965726D01*
G01X417866Y973151D02*
X416028Y972104D01*
G01X425267Y973151D02*
X423429Y972104D01*
G01X421567Y973151D02*
X419729Y972104D01*
G01X417866Y985907D02*
X416028Y984860D01*
G01X425267Y985907D02*
X423429Y984860D01*
G01X414165Y979529D02*
X412327Y978482D01*
G01X416015Y982718D02*
X414177Y981671D01*
G01X416015Y976340D02*
X414177Y975293D01*
G01X414165Y973151D02*
X412327Y972104D01*
G01X425267Y979529D02*
X423429Y978482D01*
G01X423417Y982718D02*
X421579Y981671D01*
G01X412315Y982718D02*
X410477Y981671D01*
G01X414165Y985907D02*
X412327Y984860D01*
G01X417866Y979529D02*
X416028Y978482D01*
G01X421567Y979529D02*
X419729Y978482D01*
G01X419716Y982718D02*
X417878Y981671D01*
G01X421567Y985907D02*
X419729Y984860D01*
G01X416015Y989096D02*
X414177Y988049D01*
G01X423417Y989096D02*
X421579Y988049D01*
G01X425267Y992285D02*
X423429Y991238D01*
G01X417866Y992285D02*
X416028Y991238D01*
G01X412315Y989096D02*
X410477Y988049D01*
G01X419716Y989096D02*
X417878Y988049D01*
G01X414165Y992285D02*
X412327Y991238D01*
G01X421567Y992285D02*
X419729Y991238D01*
G01X415346Y1058899D02*
X413508Y1059946D01*
G01X419047Y1046143D02*
X417209Y1047190D01*
G01X426448Y1046143D02*
X424610Y1047190D01*
G01X426448Y1052521D02*
X424610Y1053568D01*
G01X424598Y1055710D02*
X422760Y1056757D01*
G01X426448Y1058899D02*
X424610Y1059946D01*
G01X419047Y1052521D02*
X417209Y1053568D01*
G01X417196Y1055710D02*
X415358Y1056757D01*
G01X417196Y1049332D02*
X415358Y1050379D01*
G01X424598Y1049332D02*
X422760Y1050379D01*
G01X420897Y1049332D02*
X419059Y1050379D01*
G01X422748Y1046143D02*
X420910Y1047190D01*
G01X415346Y1046143D02*
X413508Y1047190D01*
G01X422748Y1058899D02*
X420910Y1059946D01*
G01X419047Y1058899D02*
X417209Y1059946D01*
G01X420897Y1055710D02*
X419059Y1056757D01*
G01X422748Y1052521D02*
X420910Y1053568D01*
G01X413496Y1055710D02*
X411658Y1056757D01*
G01X415346Y1052521D02*
X413508Y1053568D01*
G01X413496Y1049332D02*
X411658Y1050379D01*
G01X415346Y1071655D02*
X413508Y1072702D01*
G01X415346Y1065277D02*
X413508Y1066324D01*
G01X417196Y1062088D02*
X415358Y1063135D01*
G01X426448Y1071655D02*
X424610Y1072702D01*
G01X426448Y1065277D02*
X424610Y1066324D01*
G01X422748Y1065277D02*
X420910Y1066324D01*
G01X419047Y1065277D02*
X417209Y1066324D01*
G01X417196Y1068466D02*
X415358Y1069513D01*
G01X417196Y1074844D02*
X415358Y1075891D01*
G01X422748Y1071655D02*
X420910Y1072702D01*
G01X419047Y1071655D02*
X417209Y1072702D01*
G01X415346Y1078033D02*
X413508Y1079080D01*
G01X415346Y1084411D02*
X413508Y1085458D01*
G01X422748Y1078033D02*
X420910Y1079080D01*
G01X426448Y1078033D02*
X424610Y1079080D01*
G01X419047Y1078033D02*
X417209Y1079080D01*
G01X426448Y1084411D02*
X424610Y1085458D01*
G01X417196Y1087600D02*
X415358Y1088647D01*
G01X417196Y1081222D02*
X415358Y1082269D01*
G01X422748Y1084411D02*
X420910Y1085458D01*
G01X419047Y1084411D02*
X417209Y1085458D01*
G01X415346Y1090789D02*
X413508Y1091836D01*
G01X415346Y1097167D02*
X413508Y1098214D01*
G01X415346Y1103545D02*
X413508Y1104592D01*
G01X417196Y1093978D02*
X415358Y1095025D01*
G01X422748Y1090789D02*
X420910Y1091836D01*
G01X426448Y1090789D02*
X424610Y1091836D01*
G01X419047Y1090789D02*
X417209Y1091836D01*
G01X422748Y1103545D02*
X420910Y1104592D01*
G01X426448Y1103545D02*
X424610Y1104592D01*
G01X426448Y1097167D02*
X424610Y1098214D01*
G01X419047Y1103545D02*
X417209Y1104592D01*
G01X417196Y1100356D02*
X415358Y1101403D01*
G01X419047Y1097167D02*
X417209Y1098214D01*
G01X422748Y1097167D02*
X420910Y1098214D01*
G01X415346Y1109923D02*
X413508Y1110970D01*
G01X415346Y1116301D02*
X413508Y1117348D01*
G01X417196Y1106734D02*
X415358Y1107781D01*
G01X426448Y1109923D02*
X424610Y1110970D01*
G01X422748Y1109923D02*
X420910Y1110970D01*
G01X419047Y1109923D02*
X417209Y1110970D01*
G01X426448Y1116301D02*
X424610Y1117348D01*
G01X417196Y1113112D02*
X415358Y1114159D01*
G01X417196Y1119490D02*
X415358Y1120537D01*
G01X419047Y1116301D02*
X417209Y1117348D01*
G01X422748Y1116301D02*
X420910Y1117348D01*
G01X420897Y1106734D02*
X419059Y1107781D01*
G01X424598Y1106734D02*
X422760Y1107781D01*
G01X413496Y1106734D02*
X411658Y1107781D01*
G01X417196Y1125868D02*
X415358Y1126915D01*
G01X426448Y1122679D02*
X424610Y1123726D01*
G01X422748Y1122679D02*
X420910Y1123726D01*
G01X419047Y1122679D02*
X417209Y1123726D01*
G01X417196Y1132246D02*
X415358Y1133293D01*
G01X415346Y1122679D02*
X413508Y1123726D01*
G01X415346Y1129057D02*
X413508Y1130103D01*
G01X426448Y1129057D02*
X424612Y1130102D01*
X424611Y1130105D01*
G01X419047Y1129057D02*
X417209Y1130103D01*
G01X422748Y1129057D02*
X420910Y1130103D01*
G01X415346Y1141812D02*
X413508Y1142859D01*
G01X415346Y1135434D02*
X413508Y1136481D01*
G01X426448Y1141812D02*
X424610Y1142859D01*
G01X426448Y1135434D02*
X424610Y1136481D01*
G01X422748Y1135434D02*
X420910Y1136481D01*
G01X417196Y1138623D02*
X415358Y1139670D01*
G01X419047Y1135434D02*
X417209Y1136481D01*
G01X422748Y1148190D02*
X420910Y1149237D01*
G01X419047Y1148190D02*
X417209Y1149237D01*
G01X417196Y1145001D02*
X415358Y1146048D01*
G01X426448Y1148190D02*
X424610Y1149237D01*
G01X422748Y1141812D02*
X420910Y1142859D01*
G01X419047Y1141812D02*
X417209Y1142859D01*
G01X415346Y1148190D02*
X413508Y1149237D01*
G01X415346Y1154568D02*
X413508Y1155615D01*
G01X413496Y1157757D02*
X411658Y1158804D01*
G01X426448Y1154568D02*
X424610Y1155615D01*
G01X422748Y1154568D02*
X420910Y1155615D01*
G01X419047Y1154568D02*
X417209Y1155615D01*
G01X424598Y1157757D02*
X422760Y1158804D01*
G01X424598Y1164135D02*
X422760Y1165182D01*
G01X422748Y1160946D02*
X420910Y1161993D01*
G01X417196Y1151379D02*
X415358Y1152426D01*
G01X426448Y1160946D02*
X424610Y1161993D01*
G01X415346Y1160946D02*
X413508Y1161993D01*
G01X419047Y1160946D02*
X417209Y1161993D01*
G01X436370Y877482D02*
X434532Y876435D01*
G01X434519Y880671D02*
X432681Y879624D01*
G01X428968Y877482D02*
X427130Y876435D01*
G01X427118Y893427D02*
X425280Y892380D01*
G01X430831Y882813D02*
X432669Y883860D01*
G01X428968D02*
X427130Y882813D01*
G01D02*
X425267Y883860D01*
G01X432669Y890238D02*
X430831Y889191D01*
G01X428968Y890238D02*
X427130Y889191D01*
G01X436370Y896616D02*
X434532Y895569D01*
G01X436370Y890238D02*
X434532Y889191D01*
G01X432669Y883860D02*
X433167Y883362D01*
X435872D01*
X436370Y883860D01*
G01X427118Y887049D02*
X425280Y886002D01*
G01X430818Y893427D02*
X428981Y892380D01*
G01X434519Y893427D02*
X432681Y892380D01*
G01X427118Y899805D02*
X425280Y898758D01*
G01X427118Y906182D02*
X425280Y905135D01*
G01X427118Y912560D02*
X425280Y911513D01*
G01X430818Y906182D02*
X428981Y905135D01*
G01X436370Y902994D02*
X434532Y901947D01*
G01X434519Y906182D02*
X432681Y905135D01*
G01X436370Y909371D02*
X434532Y908325D01*
G01X430818Y912560D02*
X428981Y911513D01*
G01X434519Y912560D02*
X432681Y911513D01*
G01X430818Y899805D02*
X428981Y898758D01*
G01X434519Y899805D02*
X432681Y898758D01*
G01X427118Y918938D02*
X425280Y917891D01*
G01X427118Y925316D02*
X425280Y924269D01*
G01X430818Y918938D02*
X428981Y917891D01*
G01X434519Y918938D02*
X432681Y917891D01*
G01X436370Y915749D02*
X434532Y914702D01*
G01X436370Y922127D02*
X434532Y921080D01*
G01X430818Y925316D02*
X428981Y924269D01*
G01X434519Y925316D02*
X432681Y924269D01*
G01X427118Y931694D02*
X425280Y930647D01*
G01X427118Y938072D02*
X425280Y937025D01*
G01X430818Y931694D02*
X428981Y930647D01*
G01X430818Y938072D02*
X428981Y937025D01*
G01X434519Y931694D02*
X432681Y930647D01*
G01X436370Y928505D02*
X434532Y927458D01*
G01X436370Y934883D02*
X434532Y933836D01*
G01X434519Y938072D02*
X432681Y937025D01*
G01X436370Y941261D02*
X434532Y940214D01*
G01X428968Y934883D02*
X427130Y933836D01*
G01X432669Y934883D02*
X430831Y933836D01*
G01X427118Y944450D02*
X425280Y943403D01*
G01X427118Y950828D02*
X425280Y949781D01*
G01X427118Y957206D02*
X425280Y956159D01*
G01X430818Y950828D02*
X428981Y949781D01*
G01X434519Y950828D02*
X432681Y949781D01*
G01X436370Y947639D02*
X434532Y946592D01*
G01X436370Y954017D02*
X434532Y952970D01*
G01X430818Y944450D02*
X428981Y943403D01*
G01X430818Y957206D02*
X428981Y956159D01*
G01X434519Y944450D02*
X432681Y943403D01*
G01X434519Y957206D02*
X432681Y956159D01*
G01X427118Y963584D02*
X425280Y962537D01*
G01X427118Y969962D02*
X425280Y968915D01*
G01X430818Y963584D02*
X428981Y962537D01*
G01X434519Y963584D02*
X432681Y962537D01*
G01X436370Y960395D02*
X434532Y959348D01*
G01X436370Y966773D02*
X434532Y965726D01*
G01X430818Y969962D02*
X428981Y968915D01*
G01X434519Y969962D02*
X432681Y968915D01*
G01X427118Y976340D02*
X425280Y975293D01*
G01X430818Y982718D02*
X428981Y981671D01*
G01X430818Y976340D02*
X428981Y975293D01*
G01X432669Y985907D02*
X430831Y984860D01*
G01X436370Y973151D02*
X434532Y972104D01*
G01X434519Y976340D02*
X432681Y975293D01*
G01X436370Y979529D02*
X434532Y978482D01*
G01X427118Y982718D02*
X425280Y981671D01*
G01X428968Y985907D02*
X427130Y984860D01*
G01X434519Y982718D02*
X432681Y981671D01*
G01X436370Y985907D02*
X434532Y984860D01*
G01X432669Y992285D02*
X430831Y991238D01*
G01X430818Y989096D02*
X428981Y988049D01*
G01X427118Y989096D02*
X425280Y988049D01*
G01X434519Y989096D02*
X432681Y988049D01*
G01X436370Y992285D02*
X434532Y991238D01*
G01X428968Y992285D02*
X427130Y991238D01*
G01X432000Y1055710D02*
X430162Y1056757D01*
G01X432000Y1049332D02*
X430162Y1050379D01*
G01X433850Y1046143D02*
X432012Y1047190D01*
G01X433850Y1052521D02*
X432012Y1053568D01*
G01X437551Y1058899D02*
X435713Y1059946D01*
G01X435700Y1049332D02*
X433862Y1050379D01*
G01X437551Y1046143D02*
X435713Y1047190D01*
G01X430149Y1046143D02*
X428311Y1047190D01*
G01X437551Y1052521D02*
X435713Y1053568D01*
G01X435700Y1055710D02*
X433862Y1056757D01*
G01X430149Y1052521D02*
X428311Y1053568D01*
G01X428299Y1055710D02*
X426461Y1056757D01*
G01X428299Y1049332D02*
X426461Y1050379D01*
G01X428299Y1062088D02*
X426461Y1063135D01*
G01X432000Y1062088D02*
X430162Y1063135D01*
G01X428299Y1068466D02*
X426461Y1069513D01*
G01X435700Y1062088D02*
X433862Y1063135D01*
G01X437551Y1071655D02*
X435713Y1072702D01*
G01X437551Y1065277D02*
X435713Y1066324D01*
G01X432000Y1074844D02*
X430162Y1075891D01*
G01X428299Y1074844D02*
X426461Y1075891D01*
G01X435700Y1074844D02*
X433862Y1075891D01*
G01X435700Y1068466D02*
X433862Y1069513D01*
G01X432000Y1068466D02*
X430162Y1069513D01*
G01X432000Y1087600D02*
X430162Y1088647D01*
G01X428299Y1087600D02*
X426461Y1088647D01*
G01X428299Y1081222D02*
X426461Y1082269D01*
G01X437551Y1078033D02*
X435713Y1079080D01*
G01X437551Y1084411D02*
X435713Y1085458D01*
G01X435700Y1087600D02*
X433862Y1088647D01*
G01X435700Y1081222D02*
X433862Y1082269D01*
G01X432000Y1081222D02*
X430162Y1082269D01*
G01X428299Y1093978D02*
X426461Y1095025D01*
G01X432000Y1100356D02*
X430162Y1101403D01*
G01X428299Y1100356D02*
X426461Y1101403D01*
G01X437551Y1090789D02*
X435713Y1091836D01*
G01X437551Y1097167D02*
X435713Y1098214D01*
G01X437551Y1103545D02*
X435713Y1104592D01*
G01X435700Y1100356D02*
X433862Y1101403D01*
G01X433850Y1103545D02*
X432012Y1104592D01*
G01X435700Y1093978D02*
X433862Y1095025D01*
G01X430149Y1103545D02*
X428311Y1104592D01*
G01X432000Y1093978D02*
X430162Y1095025D01*
G01X432000Y1106734D02*
X430162Y1107781D01*
G01X428299Y1106734D02*
X426461Y1107781D01*
G01X428299Y1113112D02*
X426461Y1114159D01*
G01X435700Y1106734D02*
X433862Y1107781D01*
G01X437551Y1109923D02*
X435713Y1110970D01*
G01X437551Y1116301D02*
X435713Y1117348D01*
G01X432000Y1119490D02*
X430162Y1120537D01*
G01X428299Y1119490D02*
X426461Y1120537D01*
G01X435700Y1119490D02*
X433862Y1120537D01*
G01X435700Y1113112D02*
X433862Y1114159D01*
G01X432000Y1113112D02*
X430162Y1114159D01*
G01X428299Y1125868D02*
X426461Y1126915D01*
G01X432000Y1132246D02*
X430162Y1133293D01*
G01X428299Y1132246D02*
X426461Y1133293D01*
G01X437551Y1122679D02*
X435713Y1123726D01*
G01X437551Y1129057D02*
X435713Y1130103D01*
G01X435700Y1132246D02*
X433862Y1133293D01*
G01X435700Y1125868D02*
X433862Y1126915D01*
G01X432000Y1125868D02*
X430162Y1126915D01*
G01X428299Y1138623D02*
X426461Y1139670D01*
G01X428299Y1145001D02*
X426461Y1146048D01*
G01X430149Y1148190D02*
X428311Y1149237D01*
G01X437551Y1135434D02*
X435713Y1136481D01*
G01X437551Y1141812D02*
X435713Y1142859D01*
G01X437551Y1148190D02*
X435713Y1149237D01*
G01X433850Y1148190D02*
X432012Y1149237D01*
G01X435700Y1145001D02*
X433862Y1146048D01*
G01X435700Y1138623D02*
X433862Y1139670D01*
G01X432000Y1145001D02*
X430162Y1146048D01*
G01X432000Y1138623D02*
X430162Y1139670D01*
G01X432000Y1157757D02*
X430162Y1158804D01*
G01X437551Y1154568D02*
X435713Y1155615D01*
G01X437551Y1160946D02*
X435713Y1161993D01*
G01X432000Y1151379D02*
X430162Y1152426D01*
G01X428299Y1151379D02*
X426461Y1152426D01*
G01X430149Y1160946D02*
X428311Y1161993D01*
G01X443771Y877482D02*
X445609Y876435D01*
G01X445622Y880671D02*
X447460Y879624D01*
G01X454874Y877482D02*
X456712Y876435D01*
G01X451173Y877482D02*
X453011Y876435D01*
G01X443771Y883860D02*
X445609Y882813D01*
G01X443771Y890238D02*
X445609Y889191D01*
G01X443771Y896616D02*
X445609Y895569D01*
G01X451173Y883860D02*
X453011Y882813D01*
G01X447472Y890238D02*
X449310Y889191D01*
G01X451173Y890238D02*
X453011Y889191D01*
G01X453023Y893427D02*
X454861Y892380D01*
G01X454874Y890238D02*
X456712Y889191D01*
G01X449322Y887049D02*
X451160Y886002D01*
G01X453023Y887049D02*
X454861Y886002D01*
G01X449322Y893427D02*
X451160Y892380D01*
G01X445622Y893427D02*
X447460Y892380D01*
G01X454874Y896616D02*
X456712Y895569D01*
G01X443771Y902994D02*
X445609Y901947D01*
G01X443771Y909371D02*
X445609Y908325D01*
G01X453023Y899805D02*
X454861Y898758D01*
G01X449322Y906182D02*
X451160Y905135D01*
G01X453023Y906182D02*
X454861Y905135D01*
G01X445622Y906182D02*
X447460Y905135D01*
G01X454874Y902994D02*
X456712Y901947D01*
G01X454874Y909371D02*
X456712Y908324D01*
G01X449322Y912560D02*
X451160Y911513D01*
G01X445622Y912560D02*
X447460Y911513D01*
G01X449322Y899805D02*
X451160Y898758D01*
G01X445622Y899805D02*
X447460Y898758D01*
G01X453023Y912560D02*
X454861Y911513D01*
G01X443771Y915749D02*
X445609Y914702D01*
G01X443771Y922127D02*
X445609Y921080D01*
G01X445622Y918938D02*
X447460Y917891D01*
G01X449322Y918938D02*
X451160Y917891D01*
G01X453023Y918938D02*
X454861Y917891D01*
G01X453023Y925316D02*
X454861Y924269D01*
G01X454874Y915749D02*
X456712Y914702D01*
G01X454874Y922127D02*
X456712Y921080D01*
G01X449322Y925316D02*
X451160Y924269D01*
G01X445622Y925316D02*
X447460Y924269D01*
G01X453023Y931694D02*
X454861Y930647D01*
G01X445622Y938072D02*
X447460Y937025D01*
G01X449322Y938072D02*
X451160Y937025D01*
G01X453023Y938072D02*
X454861Y937025D01*
G01X443771Y928505D02*
X445609Y927458D01*
G01X443771Y934883D02*
X445609Y933836D01*
G01X443771Y941261D02*
X445609Y940214D01*
G01X445622Y931694D02*
X447460Y930647D01*
G01X449322Y931694D02*
X451160Y930647D01*
G01X454874Y928505D02*
X456712Y927458D01*
G01X454874Y934883D02*
X456712Y933836D01*
G01X447472Y934883D02*
X449310Y933836D01*
G01X451173Y934883D02*
X453011Y933836D01*
G01X454874Y941261D02*
X456712Y940214D01*
G01X443771Y947639D02*
X445609Y946592D01*
G01X443771Y954017D02*
X445609Y952970D01*
G01X445622Y950828D02*
X447460Y949781D01*
G01X453023Y944450D02*
X454861Y943403D01*
G01X449322Y950828D02*
X451160Y949781D01*
G01X453023Y950828D02*
X454861Y949781D01*
G01X454874Y947639D02*
X456712Y946592D01*
G01X454874Y954017D02*
X456712Y952970D01*
G01X449322Y944450D02*
X451160Y943403D01*
G01X449322Y957206D02*
X451160Y956159D01*
G01X445622Y944450D02*
X447460Y943403D01*
G01X445622Y957206D02*
X447460Y956159D01*
G01X453023Y957206D02*
X454861Y956159D01*
G01X443771Y960395D02*
X445609Y959348D01*
G01X443771Y966773D02*
X445609Y965726D01*
G01X453023Y963584D02*
X454861Y962537D01*
G01X449322Y963584D02*
X451160Y962537D01*
G01X445622Y963584D02*
X447460Y962537D01*
G01X453023Y969962D02*
X454861Y968915D01*
G01X454874Y966773D02*
X456712Y965726D01*
G01X454874Y960395D02*
X456712Y959348D01*
G01X449322Y969962D02*
X451160Y968915D01*
G01X445622Y969962D02*
X447460Y968915D01*
G01X443771Y973151D02*
X445609Y972104D01*
G01X443771Y979529D02*
X445609Y978482D01*
G01X443771Y985907D02*
X445609Y984860D01*
G01X445622Y982718D02*
X447460Y981671D01*
G01X453023Y982718D02*
X454861Y981671D01*
G01X449322Y976340D02*
X451160Y975293D01*
G01X445622Y976340D02*
X447460Y975293D01*
G01X453023Y976340D02*
X454861Y975293D01*
G01X451173Y985907D02*
X453011Y984860D01*
G01X454874Y973151D02*
X456712Y972104D01*
G01X454874Y979529D02*
X456712Y978482D01*
G01X449322Y982718D02*
X451160Y981671D01*
G01X447472Y985907D02*
X449310Y984860D01*
G01X443771Y992285D02*
X445609Y991238D01*
G01X451173Y992285D02*
X453011Y991238D01*
G01X453023Y989096D02*
X454861Y988049D01*
G01X445622Y989096D02*
X447460Y988049D01*
G01X454874Y985907D02*
X456712Y984860D01*
G01X454874Y992285D02*
X456712Y991238D01*
G01X449322Y989096D02*
X451160Y988049D01*
G01X447472Y992285D02*
X449310Y991238D01*
G01X444952Y1046143D02*
X446790Y1047190D01*
G01X444952Y1052521D02*
X446790Y1053568D01*
G01X444952Y1058899D02*
X446790Y1059946D01*
G01X452354Y1046143D02*
X454192Y1047190D01*
G01X446803Y1055710D02*
X448641Y1056757D01*
G01X452354Y1052521D02*
X454192Y1053568D01*
G01X446803Y1049332D02*
X448641Y1050379D01*
G01X454204Y1055710D02*
X456042Y1056757D01*
G01X454204Y1049332D02*
X456042Y1050379D01*
G01X448653Y1046143D02*
X450491Y1047190D01*
G01X450504Y1049332D02*
X452341Y1050379D01*
G01X448653Y1052521D02*
X450491Y1053568D01*
G01X450504Y1055710D02*
X452341Y1056757D01*
G01X444952Y1065277D02*
X446790Y1066324D01*
G01X444952Y1071655D02*
X446790Y1072702D01*
G01X450504Y1062088D02*
X452341Y1063135D01*
G01X446803Y1062088D02*
X448641Y1063135D01*
G01X454204Y1062088D02*
X456042Y1063135D01*
G01X454204Y1068466D02*
X456042Y1069513D01*
G01X450504Y1074844D02*
X452341Y1075891D01*
G01X446803Y1074844D02*
X448641Y1075891D01*
G01X454204Y1074844D02*
X456042Y1075891D01*
G01X450504Y1068466D02*
X452341Y1069513D01*
G01X446803Y1068466D02*
X448641Y1069513D01*
G01X444952Y1078033D02*
X446790Y1079080D01*
G01X444952Y1084411D02*
X446790Y1085458D01*
G01X450504Y1087600D02*
X452341Y1088647D01*
G01X446803Y1087600D02*
X448641Y1088647D01*
G01X454204Y1087600D02*
X456042Y1088647D01*
G01X454204Y1081222D02*
X456042Y1082269D01*
G01X450504Y1081222D02*
X452341Y1082269D01*
G01X446803Y1081222D02*
X448641Y1082269D01*
G01X444952Y1090789D02*
X446790Y1091836D01*
G01X444952Y1097167D02*
X446790Y1098214D01*
G01X444952Y1103545D02*
X446790Y1104592D01*
G01X450504Y1100356D02*
X452341Y1101403D01*
G01X446803Y1100356D02*
X448641Y1101403D01*
G01X454204Y1093978D02*
X456042Y1095025D01*
G01X454204Y1100356D02*
X456042Y1101403D01*
G01X452354Y1103545D02*
X454192Y1104592D01*
G01X448653Y1103545D02*
X450491Y1104592D01*
G01X450504Y1093978D02*
X452341Y1095025D01*
G01X446803Y1093978D02*
X448641Y1095025D01*
G01X444952Y1109923D02*
X446790Y1110970D01*
G01X444952Y1116301D02*
X446790Y1117348D01*
G01X450504Y1106734D02*
X452341Y1107781D01*
G01X446803Y1106734D02*
X448641Y1107781D01*
G01X454204Y1106734D02*
X456042Y1107781D01*
G01X454204Y1113112D02*
X456042Y1114159D01*
G01X446803Y1119490D02*
X448641Y1120537D01*
G01X450504Y1119490D02*
X452341Y1120537D01*
G01X454204Y1119490D02*
X456042Y1120537D01*
G01X450504Y1113112D02*
X452341Y1114159D01*
G01X446803Y1113112D02*
X448641Y1114159D01*
G01X444952Y1122679D02*
X446790Y1123726D01*
G01X444952Y1129057D02*
X446790Y1130103D01*
G01X450504Y1132246D02*
X452341Y1133293D01*
G01X446803Y1132246D02*
X448641Y1133293D01*
G01X454204Y1125868D02*
X456042Y1126915D01*
G01X454204Y1132246D02*
X456042Y1133293D01*
G01X450504Y1125868D02*
X452341Y1126915D01*
G01X446803Y1125868D02*
X448641Y1126915D01*
G01X444952Y1135434D02*
X446790Y1136481D01*
G01X444952Y1141812D02*
X446790Y1142859D01*
G01X444952Y1148190D02*
X446790Y1149237D01*
G01X452354Y1148190D02*
X454192Y1149237D01*
G01X448653Y1148190D02*
X450491Y1149237D01*
G01X454204Y1138623D02*
X456042Y1139670D01*
G01X454204Y1145001D02*
X456042Y1146048D01*
G01X450504Y1145001D02*
X452341Y1146048D01*
G01X446803Y1145001D02*
X448641Y1146048D01*
G01X450504Y1138623D02*
X452341Y1139670D01*
G01X446803Y1138623D02*
X448641Y1139670D01*
G01X444952Y1154568D02*
X446790Y1155615D01*
G01X444952Y1160946D02*
X446790Y1161993D01*
G01X452354Y1154568D02*
X454192Y1155615D01*
G01X450504Y1151379D02*
X452341Y1152426D01*
G01X452354Y1160946D02*
X454192Y1161993D01*
G01X454204Y1151379D02*
X456042Y1152426D01*
G01X458574Y877482D02*
X460412Y876435D01*
G01X467826Y880671D02*
X469664Y879624D01*
G01X469677Y877482D02*
X471515Y876435D01*
G01X465976Y877482D02*
X467814Y876435D01*
G01X462275Y877482D02*
X464113Y876435D01*
G01X458574Y890238D02*
X460412Y889191D01*
G01X465976Y883860D02*
X467814Y882813D01*
G01X464126Y893427D02*
X465964Y892380D01*
G01X465976Y896616D02*
X467814Y895569D01*
G01X462275Y890238D02*
X464113Y889191D01*
G01X469677Y883860D02*
X471515Y882813D01*
G01X469677Y890238D02*
X471515Y889191D01*
G01X458574Y896616D02*
X460412Y895569D01*
G01X464126Y887049D02*
X465964Y886002D01*
G01X465976Y890238D02*
X467814Y889191D01*
G01X462275Y896616D02*
X464113Y895569D01*
G01X464126Y912560D02*
X465964Y911513D01*
G01X458574Y902994D02*
X460412Y901947D01*
G01X464126Y899805D02*
X465964Y898758D01*
G01X465976Y902994D02*
X467814Y901947D01*
G01X462275Y902994D02*
X464113Y901947D01*
G01X465976Y909371D02*
X467814Y908325D01*
G01X464126Y906182D02*
X465964Y905135D01*
G01X469677Y902994D02*
X471515Y901947D01*
G01X469677Y909371D02*
X471515Y908325D01*
G01X469677Y896616D02*
X471515Y895569D01*
G01X458574Y909371D02*
X460412Y908325D01*
G01X462275Y909371D02*
X464113Y908325D01*
G01X458574Y915749D02*
X460412Y914702D01*
G01X465976Y915749D02*
X467814Y914702D01*
G01X462275Y915749D02*
X464113Y914702D01*
G01X464126Y918938D02*
X465964Y917891D01*
G01X465976Y922127D02*
X467814Y921080D01*
G01X464126Y925316D02*
X465964Y924269D01*
G01X469677Y915749D02*
X471515Y914702D01*
G01X469677Y922127D02*
X471515Y921080D01*
G01X458574Y922127D02*
X460412Y921080D01*
G01X462275Y922127D02*
X464113Y921080D01*
G01X458574Y928505D02*
X460412Y927458D01*
G01X458574Y934883D02*
X460412Y933836D01*
G01X465976Y928505D02*
X467814Y927458D01*
G01X465976Y934883D02*
X467814Y933836D01*
G01X462275Y928505D02*
X464113Y927458D01*
G01X462275Y934883D02*
X464113Y933836D01*
G01X465976Y941261D02*
X467814Y940214D01*
G01X464126Y938072D02*
X465964Y937025D01*
G01X469677Y928505D02*
X471515Y927458D01*
G01X460425Y931694D02*
X462263Y930647D01*
G01X456724Y931694D02*
X458562Y930647D01*
G01X458574Y941261D02*
X460412Y940214D01*
G01X467826Y931694D02*
X469664Y930647D01*
G01X462275Y941261D02*
X464113Y940214D01*
G01X458574Y947639D02*
X460412Y946592D01*
G01X465976Y947639D02*
X467814Y946592D01*
G01X462275Y947639D02*
X464113Y946592D01*
G01X464126Y944450D02*
X465964Y943403D01*
G01X464126Y950828D02*
X465964Y949781D01*
G01X465976Y954017D02*
X467814Y952970D01*
G01X464126Y957206D02*
X465964Y956159D01*
G01X469677Y947639D02*
X471515Y946592D01*
G01X469677Y954017D02*
X471515Y952970D01*
G01X469677Y941261D02*
X471515Y940214D01*
G01X458574Y954017D02*
X460412Y952970D01*
G01X462275Y954017D02*
X464113Y952970D01*
G01X458574Y960395D02*
X460412Y959348D01*
G01X465976Y966773D02*
X467814Y965726D01*
G01X465976Y960395D02*
X467814Y959348D01*
G01X464126Y963584D02*
X465964Y962537D01*
G01X462275Y960395D02*
X464113Y959348D01*
G01X464126Y969962D02*
X465964Y968915D01*
G01X469677Y960395D02*
X471515Y959348D01*
G01X469677Y966773D02*
X471515Y965726D01*
G01X458574Y966773D02*
X460412Y965726D01*
G01X462275Y966773D02*
X464113Y965726D01*
G01X460425Y982718D02*
X462263Y981671D01*
G01X458574Y973151D02*
X460412Y972104D01*
G01X458574Y985907D02*
X460412Y984860D01*
G01X467826Y982718D02*
X469664Y981671D01*
G01X465976Y979529D02*
X467814Y978482D01*
G01X465976Y973151D02*
X467814Y972104D01*
G01X464126Y976340D02*
X465964Y975293D01*
G01X462275Y973151D02*
X464113Y972104D01*
G01X465976Y985907D02*
X467814Y984860D01*
G01X469677Y973151D02*
X471515Y972104D01*
G01X469677Y979529D02*
X471515Y978482D01*
G01X458574Y979529D02*
X460412Y978482D01*
G01X456724Y982718D02*
X458562Y981671D01*
G01X462275Y979529D02*
X464113Y978482D01*
G01X464126Y982718D02*
X465964Y981671D01*
G01X462275Y985907D02*
X464113Y984860D01*
G01X458574Y992285D02*
X460412Y991238D01*
G01X460425Y989096D02*
X462263Y988049D01*
G01X467826Y989096D02*
X469664Y988049D01*
G01X465976Y992285D02*
X467814Y991238D01*
G01X469677Y985907D02*
X471515Y984860D01*
G01X456724Y989096D02*
X458562Y988049D01*
G01X469677Y992285D02*
X471515Y991238D01*
G01X464126Y989096D02*
X465964Y988049D01*
G01X462275Y992285D02*
X464113Y991238D01*
G01X459755Y1046143D02*
X461593Y1047190D01*
G01X459755Y1052521D02*
X461593Y1053568D01*
G01X456055Y1058899D02*
X457893Y1059946D01*
G01X467157Y1046143D02*
X468995Y1047190D01*
G01X467157Y1052521D02*
X468995Y1053568D01*
G01X467157Y1058899D02*
X468995Y1059946D01*
G01X461606Y1055710D02*
X463444Y1056757D01*
G01X461606Y1049332D02*
X463444Y1050379D01*
G01X469007Y1055710D02*
X470845Y1056757D01*
G01X469007Y1049332D02*
X470845Y1050379D01*
G01X457905Y1049332D02*
X459743Y1050379D01*
G01X463456Y1046143D02*
X465294Y1047190D01*
G01X456055Y1046143D02*
X457893Y1047190D01*
G01X463456Y1058899D02*
X465294Y1059946D01*
G01X457905Y1055710D02*
X459743Y1056757D01*
G01X459755Y1058899D02*
X461593Y1059946D01*
G01X456055Y1052521D02*
X457893Y1053568D01*
G01X465307Y1049332D02*
X467145Y1050379D01*
G01X465307Y1055710D02*
X467145Y1056757D01*
G01X463456Y1052521D02*
X465294Y1053568D01*
G01X456055Y1071655D02*
X457893Y1072702D01*
G01X456055Y1065277D02*
X457893Y1066324D01*
G01X459755Y1065277D02*
X461593Y1066324D01*
G01X465307Y1062088D02*
X467145Y1063135D01*
G01X467157Y1071655D02*
X468995Y1072702D01*
G01X467157Y1065277D02*
X468995Y1066324D01*
G01X465307Y1068466D02*
X467145Y1069513D01*
G01X463456Y1065277D02*
X465294Y1066324D01*
G01X465307Y1074844D02*
X467145Y1075891D01*
G01X463456Y1071655D02*
X465294Y1072702D01*
G01X459755Y1071655D02*
X461593Y1072702D01*
G01X459755Y1078033D02*
X461593Y1079080D01*
G01X456055Y1078033D02*
X457893Y1079080D01*
G01X456055Y1084411D02*
X457893Y1085458D01*
G01X467157Y1078033D02*
X468995Y1079080D01*
G01X463456Y1078033D02*
X465294Y1079080D01*
G01X467157Y1084411D02*
X468995Y1085458D01*
G01X465307Y1087600D02*
X467145Y1088647D01*
G01X465307Y1081222D02*
X467145Y1082269D01*
G01X463456Y1084411D02*
X465294Y1085458D01*
G01X459755Y1084411D02*
X461593Y1085458D01*
G01X456055Y1090789D02*
X457893Y1091836D01*
G01X459755Y1090789D02*
X461593Y1091836D01*
G01X456055Y1097167D02*
X457893Y1098214D01*
G01X456055Y1103545D02*
X457893Y1104592D01*
G01X459755Y1103545D02*
X461593Y1104592D01*
G01X465307Y1093978D02*
X467145Y1095025D01*
G01X467157Y1090789D02*
X468995Y1091836D01*
G01X463456Y1090789D02*
X465294Y1091836D01*
G01X467157Y1103545D02*
X468995Y1104592D01*
G01X463456Y1103545D02*
X465294Y1104592D01*
G01X467157Y1097167D02*
X468995Y1098214D01*
G01X465307Y1100356D02*
X467145Y1101403D01*
G01X463456Y1097167D02*
X465294Y1098214D01*
G01X459755Y1097167D02*
X461593Y1098214D01*
G01X456055Y1109923D02*
X457893Y1110970D01*
G01X459755Y1109923D02*
X461593Y1110970D01*
G01X456055Y1116301D02*
X457893Y1117348D01*
G01X467157Y1109923D02*
X468995Y1110970D01*
G01X463456Y1109923D02*
X465294Y1110970D01*
G01X465307Y1106734D02*
X467145Y1107781D01*
G01X465307Y1113112D02*
X467145Y1114159D01*
G01X467157Y1116301D02*
X468995Y1117348D01*
G01X465307Y1119490D02*
X467145Y1120537D01*
G01X461606Y1106734D02*
X463444Y1107781D01*
G01X457905Y1106734D02*
X459743Y1107781D01*
G01X469007Y1106734D02*
X470845Y1107781D01*
G01X463456Y1116301D02*
X465294Y1117348D01*
G01X459755Y1116301D02*
X461593Y1117348D01*
G01X459755Y1122679D02*
X461593Y1123726D01*
G01X456055Y1122679D02*
X457893Y1123726D01*
G01X467157Y1122679D02*
X468995Y1123726D01*
G01X463456Y1122679D02*
X465294Y1123726D01*
G01X465307Y1125868D02*
X467145Y1126915D01*
G01X467157Y1129057D02*
X468995Y1130103D01*
G01X465307Y1132246D02*
X467145Y1133293D01*
G01X456055Y1129057D02*
X457893Y1130104D01*
G01X463456Y1129057D02*
X465294Y1130103D01*
G01X459755Y1129057D02*
X461593Y1130103D01*
G01X459755Y1135434D02*
X461593Y1136481D01*
G01X456055Y1135434D02*
X457893Y1136481D01*
G01X456055Y1141812D02*
X457893Y1142859D01*
G01X459755Y1148190D02*
X461593Y1149237D01*
G01X467157Y1141812D02*
X468995Y1142859D01*
G01X465307Y1138623D02*
X467145Y1139670D01*
G01X467157Y1135434D02*
X468995Y1136481D01*
G01X463456Y1135434D02*
X465294Y1136481D01*
G01X465307Y1145001D02*
X467145Y1146048D01*
G01X463456Y1148190D02*
X465294Y1149237D01*
G01X467157Y1148190D02*
X468995Y1149237D01*
G01X463456Y1141812D02*
X465294Y1142859D01*
G01X456055Y1148190D02*
X457893Y1149237D01*
G01X459755Y1141812D02*
X461593Y1142859D01*
G01X457905Y1157757D02*
X459743Y1158804D01*
G01X457905Y1151379D02*
X459743Y1152426D01*
G01X463456Y1154568D02*
X465294Y1155615D01*
G01X469007Y1157757D02*
X470845Y1158804D01*
G01X456055Y1160946D02*
X457893Y1161993D01*
G01X465307Y1151379D02*
X467145Y1152426D01*
G01X463456Y1160946D02*
X465294Y1161993D01*
G01X467157Y1160946D02*
X468995Y1161993D01*
G01X478929Y874293D02*
X480767Y873246D01*
G01X478929Y880671D02*
X480767Y879624D01*
G01X480779Y877482D02*
X482617Y876435D01*
G01X484480Y877482D02*
X486318Y876435D01*
G01X473378Y877482D02*
X475215Y876435D01*
G01X477078Y877482D02*
X478916Y876435D01*
G01X477078Y883860D02*
X478916Y882813D01*
G01X473378Y883860D02*
X475215Y882813D01*
G01X477078Y896616D02*
X478916Y895569D01*
G01X475228Y893427D02*
X477066Y892380D01*
G01X473378Y890238D02*
X475215Y889191D01*
G01X480779Y883860D02*
X482617Y882813D01*
G01X480779Y890238D02*
X482617Y889191D01*
G01X484480Y883860D02*
X486318Y882813D01*
G01X484480Y890238D02*
X486318Y889191D01*
G01X475228Y887049D02*
X477066Y886002D01*
G01X473378Y896616D02*
X475215Y895569D01*
G01X477078Y890238D02*
X478916Y889191D01*
G01X480779Y896616D02*
X482617Y895569D01*
G01X477078Y902994D02*
X478916Y901947D01*
G01X473378Y902994D02*
X475215Y901947D01*
G01X475228Y899805D02*
X477066Y898758D01*
G01X477078Y909371D02*
X478916Y908325D01*
G01X475228Y906182D02*
X477066Y905135D01*
G01X475228Y912560D02*
X477066Y911513D01*
G01X480779Y902994D02*
X482617Y901947D01*
G01X484480Y902994D02*
X486318Y901947D01*
G01X484480Y909371D02*
X486318Y908325D01*
G01X484480Y896616D02*
X486318Y895569D01*
G01X473378Y909371D02*
X475215Y908325D01*
G01X480779Y909371D02*
X482617Y908325D01*
G01X477078Y915749D02*
X478916Y914702D01*
G01X475228Y918938D02*
X477066Y917891D01*
G01X473378Y915749D02*
X475215Y914702D01*
G01X477078Y922127D02*
X478916Y921080D01*
G01X475228Y925316D02*
X477066Y924269D01*
G01X480779Y915749D02*
X482617Y914702D01*
G01X484480Y915749D02*
X486318Y914702D01*
G01X484480Y922127D02*
X486318Y921080D01*
G01X473378Y922127D02*
X475215Y921080D01*
G01X480779Y922127D02*
X482617Y921080D01*
G01X477078Y928505D02*
X478916Y927458D01*
G01X477078Y934883D02*
X478916Y933836D01*
G01X473378Y928505D02*
X475215Y927458D01*
G01X475228Y931694D02*
X477066Y930647D01*
G01X477078Y941261D02*
X478916Y940214D01*
G01X480779Y928505D02*
X482617Y927458D01*
G01X480779Y934883D02*
X482617Y933836D01*
G01X484480Y928505D02*
X486318Y927458D01*
G01X484480Y934883D02*
X486318Y933836D01*
G01X471527Y931694D02*
X473365Y930647D01*
G01X473378Y941261D02*
X475215Y940214D01*
G01X480779Y941261D02*
X482617Y940214D01*
G01X477078Y947639D02*
X478916Y946592D01*
G01X475228Y944450D02*
X477066Y943403D01*
G01X473378Y947639D02*
X475215Y946592D01*
G01X475228Y950828D02*
X477066Y949781D01*
G01X477078Y954017D02*
X478916Y952970D01*
G01X475228Y957206D02*
X477066Y956159D01*
G01X480779Y947639D02*
X482617Y946592D01*
G01X484480Y947639D02*
X486318Y946592D01*
G01X484480Y954017D02*
X486318Y952970D01*
G01X484480Y941261D02*
X486318Y940214D01*
G01X473378Y954017D02*
X475215Y952970D01*
G01X480779Y954017D02*
X482617Y952970D01*
G01X477078Y966773D02*
X478916Y965726D01*
G01X477078Y960395D02*
X478916Y959348D01*
G01X473378Y960395D02*
X475215Y959348D01*
G01X475228Y963584D02*
X477066Y962537D01*
G01X475228Y969962D02*
X477066Y968915D01*
G01X480779Y960395D02*
X482617Y959348D01*
G01X484480Y960395D02*
X486318Y959348D01*
G01X484480Y966773D02*
X486318Y965726D01*
G01X473378Y966773D02*
X475215Y965726D01*
G01X480779Y966773D02*
X482617Y965726D01*
G01X477078Y979529D02*
X478916Y978482D01*
G01X477078Y973151D02*
X478916Y972104D01*
G01X475228Y982718D02*
X477066Y981671D01*
G01X475228Y976340D02*
X477066Y975293D01*
G01X473378Y973151D02*
X475215Y972104D01*
G01X473378Y985907D02*
X475215Y984860D01*
G01X482629Y982718D02*
X484467Y981671D01*
G01X480779Y973151D02*
X482617Y972104D01*
G01X480779Y985907D02*
X482617Y984860D01*
G01X484480Y973151D02*
X486318Y972104D01*
G01X484480Y979529D02*
X486318Y978482D01*
G01X473378Y979529D02*
X475215Y978482D01*
G01X471527Y982718D02*
X473365Y981671D01*
G01X477078Y985907D02*
X478916Y984860D01*
G01X480779Y979529D02*
X482617Y978482D01*
G01X478929Y982718D02*
X480767Y981671D01*
G01X475228Y995474D02*
X477066Y994427D01*
G01X473378Y992285D02*
X475215Y991238D01*
G01X475228Y989096D02*
X477066Y988049D01*
G01X475228Y1001852D02*
X477066Y1000805D01*
G01X482629Y995474D02*
X484467Y994427D01*
G01X482629Y989096D02*
X484467Y988049D01*
G01X480779Y992285D02*
X482617Y991238D01*
G01X480779Y998663D02*
X482617Y997616D01*
G01X484480Y985907D02*
X486318Y984860D01*
G01X471527Y989096D02*
X473365Y988049D01*
G01X484480Y998663D02*
X486318Y997616D01*
G01X484480Y992285D02*
X486318Y991238D01*
G01X477078Y998663D02*
X478916Y997616D01*
G01X477078Y992285D02*
X478916Y991238D01*
G01X478929Y995474D02*
X480767Y994427D01*
G01X478929Y989096D02*
X480767Y988049D01*
G01X478929Y1001852D02*
X480767Y1000805D01*
G01X482629Y1001852D02*
X484467Y1000805D01*
G01X475228Y1008230D02*
X477066Y1007183D01*
G01X482629Y1008230D02*
X484467Y1007183D01*
G01X480779Y1011419D02*
X482617Y1010372D01*
G01X480779Y1005041D02*
X482617Y1003994D01*
G01X484480Y1005041D02*
X486318Y1003994D01*
G01X484480Y1011419D02*
X486318Y1010372D01*
G01X477078Y1005041D02*
X478916Y1003994D01*
G01X477078Y1011419D02*
X478916Y1010372D01*
G01X478929Y1008230D02*
X480767Y1007183D01*
G01X478259Y1027009D02*
X480097Y1028056D01*
G01X480110Y1030198D02*
X481948Y1031245D01*
G01X483811Y1030198D02*
X485649Y1031245D01*
G01X481960Y1027009D02*
X483798Y1028056D01*
G01X476409Y1030198D02*
X478247Y1031245D01*
G01X476409Y1036576D02*
X478247Y1037623D01*
G01X476409Y1042954D02*
X478247Y1044001D01*
G01X478259Y1033387D02*
X480097Y1034434D01*
G01X481960Y1039765D02*
X483798Y1040812D01*
G01X483811Y1042954D02*
X485649Y1044001D01*
G01X483811Y1036576D02*
X485649Y1037623D01*
G01X478259Y1039765D02*
X480097Y1040812D01*
G01X480110Y1036576D02*
X481948Y1037623D01*
G01X480110Y1042954D02*
X481948Y1044001D01*
G01X481960Y1033387D02*
X483798Y1034434D01*
G01X474559Y1046143D02*
X476397Y1047190D01*
G01X474559Y1052521D02*
X476397Y1053568D01*
G01X476409Y1055710D02*
X478247Y1056757D01*
G01X476409Y1049332D02*
X478247Y1050379D01*
G01X481960Y1046143D02*
X483798Y1047190D01*
G01X481960Y1052521D02*
X483798Y1053568D01*
G01X478259Y1058899D02*
X480097Y1059946D01*
G01X483811Y1055710D02*
X485649Y1056757D01*
G01X483811Y1049332D02*
X485649Y1050379D01*
G01X472708Y1049332D02*
X474546Y1050379D01*
G01X478259Y1046143D02*
X480097Y1047190D01*
G01X470858Y1046143D02*
X472696Y1047190D01*
G01X480110Y1049332D02*
X481948Y1050379D01*
G01X478259Y1052521D02*
X480097Y1053568D01*
G01X480110Y1055710D02*
X481948Y1056757D01*
G01X481960Y1058899D02*
X483798Y1059946D01*
G01X474559Y1058899D02*
X476397Y1059946D01*
G01X470858Y1058899D02*
X472696Y1059946D01*
G01X470858Y1052521D02*
X472696Y1053568D01*
G01X472708Y1055710D02*
X474546Y1056757D01*
G01X476409Y1062088D02*
X478247Y1063135D01*
G01X470858Y1065277D02*
X472696Y1066324D01*
G01X474559Y1065277D02*
X476397Y1066324D01*
G01X476409Y1068466D02*
X478247Y1069513D01*
G01X481960Y1065277D02*
X483798Y1066324D01*
G01X478259Y1071655D02*
X480097Y1072702D01*
G01X478259Y1065277D02*
X480097Y1066324D01*
G01X476409Y1074844D02*
X478247Y1075891D01*
G01X481960Y1071655D02*
X483798Y1072702D01*
G01X470858Y1071655D02*
X472696Y1072702D01*
G01X474559Y1071655D02*
X476397Y1072702D01*
G01X474559Y1078033D02*
X476397Y1079080D01*
G01X470858Y1078033D02*
X472696Y1079080D01*
G01X476409Y1087600D02*
X478247Y1088647D01*
G01X476409Y1081222D02*
X478247Y1082269D01*
G01X481960Y1078033D02*
X483798Y1079080D01*
G01X478259Y1078033D02*
X480097Y1079080D01*
G01X478259Y1084411D02*
X480097Y1085458D01*
G01X481960Y1084411D02*
X483798Y1085458D01*
G01X474559Y1084411D02*
X476397Y1085458D01*
G01X470858Y1084411D02*
X472696Y1085458D01*
G01X478259Y1103545D02*
X480097Y1104592D01*
G01X481960Y1103545D02*
X483798Y1104592D01*
G01X478259Y1097167D02*
X480097Y1098214D01*
G01X476409Y1093978D02*
X478247Y1095025D01*
G01X470858Y1090789D02*
X472696Y1091836D01*
G01X474559Y1090789D02*
X476397Y1091836D01*
G01X478259Y1090789D02*
X480097Y1091836D01*
G01X481960Y1090789D02*
X483798Y1091836D01*
G01X481960Y1097167D02*
X483798Y1098214D01*
G01X474559Y1097167D02*
X476397Y1098214D01*
G01X470858Y1097167D02*
X472696Y1098214D01*
G01X470858Y1109923D02*
X472696Y1110970D01*
G01X474559Y1109923D02*
X476397Y1110970D01*
G01X476409Y1106734D02*
X478247Y1107781D01*
G01X476409Y1113112D02*
X478247Y1114159D01*
G01X481960Y1109923D02*
X483798Y1110970D01*
G01X478259Y1109923D02*
X480097Y1110970D01*
G01X478259Y1116301D02*
X480097Y1117348D01*
G01X476409Y1119490D02*
X478247Y1120537D01*
G01X472708Y1106734D02*
X474546Y1107781D01*
G01X481960Y1116301D02*
X483798Y1117348D01*
G01X470858Y1116301D02*
X472696Y1117348D01*
G01X474559Y1116301D02*
X476397Y1117348D01*
G01X474559Y1122679D02*
X476397Y1123726D01*
G01X470858Y1122679D02*
X472696Y1123726D01*
G01X476409Y1125868D02*
X478247Y1126915D01*
G01X476409Y1132246D02*
X478247Y1133293D01*
G01X481960Y1122679D02*
X483798Y1123726D01*
G01X478259Y1122679D02*
X480097Y1123726D01*
G01X478259Y1129057D02*
X480097Y1130103D01*
G01X481960Y1129057D02*
X483798Y1130103D01*
G01X470858Y1129057D02*
X472696Y1130103D01*
G01X474559Y1129057D02*
X476396Y1130103D01*
G01X476409Y1138623D02*
X478247Y1139670D01*
G01X474559Y1135434D02*
X476397Y1136481D01*
G01X470858Y1135434D02*
X472696Y1136481D01*
G01X474559Y1148190D02*
X476397Y1149237D01*
G01X470858Y1148190D02*
X472696Y1149237D01*
G01X476409Y1145001D02*
X478247Y1146048D01*
G01X481960Y1135434D02*
X483798Y1136481D01*
G01X478259Y1135434D02*
X480097Y1136481D01*
G01X478259Y1141812D02*
X480097Y1142859D01*
G01X481960Y1148190D02*
X483798Y1149237D01*
G01X478259Y1148190D02*
X480097Y1149237D01*
G01X481960Y1141812D02*
X483798Y1142859D01*
G01X474559Y1141812D02*
X476397Y1142859D01*
G01X470858Y1141812D02*
X472696Y1142859D01*
G01X474559Y1154568D02*
X476397Y1155615D01*
G01X472708Y1151379D02*
X474546Y1152426D01*
G01X480110Y1157757D02*
X481948Y1158804D01*
G01X483811Y1151379D02*
X485649Y1152426D01*
G01X476409Y1151379D02*
X478247Y1152426D01*
G01X474559Y1160946D02*
X476397Y1161993D01*
G01X478259Y1160946D02*
X480097Y1161993D01*
G01X491881Y877482D02*
X493719Y876435D01*
G01X490031Y880671D02*
X491869Y879624D01*
G01X499283Y877482D02*
X501121Y876435D01*
G01X488181Y877482D02*
X490019Y876435D01*
G01X495582Y877482D02*
X497420Y876435D01*
G01X491881Y883860D02*
X493719Y882813D01*
G01X488181Y883860D02*
X490019Y882813D01*
G01X491881Y890238D02*
X493719Y889191D01*
G01X488181Y896616D02*
X490019Y895569D01*
G01X486330Y893427D02*
X488168Y892380D01*
G01X495582Y890238D02*
X497420Y889191D01*
G01X497433Y893427D02*
X499271Y892380D01*
G01X499283Y890238D02*
X501121Y889191D01*
G01X486330Y887049D02*
X488168Y886002D01*
G01X488181Y890238D02*
X490019Y889191D01*
G01X491881Y896616D02*
X493719Y895569D01*
G01X497433Y887049D02*
X499271Y886002D01*
G01X495582Y896616D02*
X497420Y895569D01*
G01X499283Y896616D02*
X501121Y895569D01*
G01X491881Y902994D02*
X493719Y901947D01*
G01X488181Y902994D02*
X490019Y901947D01*
G01X486330Y899805D02*
X488168Y898758D01*
G01X486330Y906182D02*
X488168Y905135D01*
G01X486330Y912560D02*
X488168Y911513D01*
G01X495582Y902994D02*
X497420Y901947D01*
G01X497433Y899805D02*
X499271Y898758D01*
G01X497433Y906182D02*
X499271Y905135D01*
G01X499283Y909371D02*
X501121Y908325D01*
G01X488181Y909371D02*
X490019Y908324D01*
G01X491881Y909371D02*
X493719Y908325D01*
G01X495582Y909371D02*
X497420Y908325D01*
G01X499283Y902994D02*
X501121Y901947D01*
G01X497433Y912560D02*
X499271Y911513D01*
G01X491881Y915749D02*
X493719Y914702D01*
G01X486330Y918938D02*
X488168Y917891D01*
G01X488181Y915749D02*
X490019Y914702D01*
G01X488181Y922127D02*
X490019Y921080D01*
G01X486330Y925316D02*
X488168Y924269D01*
G01X497433Y918938D02*
X499271Y917891D01*
G01X495582Y915749D02*
X497420Y914702D01*
G01X497433Y925316D02*
X499271Y924269D01*
G01X499283Y922127D02*
X501121Y921080D01*
G01X491881Y922127D02*
X493719Y921080D01*
G01X495582Y922127D02*
X497420Y921080D01*
G01X499283Y915749D02*
X501121Y914702D01*
G01X491881Y928505D02*
X493719Y927458D01*
G01X488181Y928505D02*
X490019Y927458D01*
G01X491881Y934883D02*
X493719Y933836D01*
G01X488181Y934883D02*
X490019Y933836D01*
G01X486330Y931694D02*
X488168Y930647D01*
G01X488181Y941261D02*
X490019Y940214D01*
G01X495582Y928505D02*
X497420Y927458D01*
G01X495582Y934883D02*
X497420Y933836D01*
G01X497433Y931694D02*
X499271Y930647D01*
G01X499283Y934883D02*
X501121Y933836D01*
G01X491881Y941261D02*
X493719Y940214D01*
G01X495582Y941261D02*
X497420Y940214D01*
G01X499283Y928505D02*
X501121Y927458D01*
G01X497433Y938072D02*
X499271Y937025D01*
G01X499283Y941261D02*
X501121Y940214D01*
G01X486330Y944450D02*
X488168Y943403D01*
G01X491881Y947639D02*
X493719Y946592D01*
G01X488181Y947639D02*
X490019Y946592D01*
G01X486330Y950828D02*
X488168Y949781D01*
G01X488181Y954017D02*
X490019Y952970D01*
G01X486330Y957206D02*
X488168Y956159D01*
G01X495582Y947639D02*
X497420Y946592D01*
G01X497433Y944450D02*
X499271Y943403D01*
G01X497433Y950828D02*
X499271Y949781D01*
G01X499283Y954017D02*
X501121Y952970D01*
G01X491881Y954017D02*
X493719Y952970D01*
G01X495582Y954017D02*
X497420Y952970D01*
G01X499283Y947639D02*
X501121Y946592D01*
G01X497433Y957206D02*
X499271Y956159D01*
G01X488181Y966773D02*
X490019Y965726D01*
G01X491881Y960395D02*
X493719Y959348D01*
G01X488181Y960395D02*
X490019Y959348D01*
G01X486330Y963584D02*
X488168Y962537D01*
G01X486330Y969962D02*
X488168Y968915D01*
G01X497433Y963584D02*
X499271Y962537D01*
G01X495582Y960395D02*
X497420Y959348D01*
G01X497433Y969962D02*
X499271Y968915D01*
G01X499283Y966773D02*
X501121Y965726D01*
G01X491881Y966773D02*
X493719Y965726D01*
G01X495582Y966773D02*
X497420Y965726D01*
G01X499283Y960395D02*
X501121Y959348D01*
G01X490031Y982718D02*
X491869Y981671D01*
G01X488181Y979529D02*
X490019Y978482D01*
G01X491881Y973151D02*
X493719Y972104D01*
G01X486330Y976340D02*
X488168Y975293D01*
G01X488181Y973151D02*
X490019Y972104D01*
G01X488181Y985907D02*
X490019Y984860D01*
G01X495582Y973151D02*
X497420Y972104D01*
G01X497433Y976340D02*
X499271Y975293D01*
G01X497433Y982718D02*
X499271Y981671D01*
G01X495582Y985907D02*
X497420Y984860D01*
G01X499283Y979529D02*
X501121Y978482D01*
G01X491881Y979529D02*
X493719Y978482D01*
G01X486330Y982718D02*
X488168Y981671D01*
G01X491881Y985907D02*
X493719Y984860D01*
G01X493732Y982718D02*
X495570Y981671D01*
G01X495582Y979529D02*
X497420Y978482D01*
G01X499283Y973151D02*
X501121Y972104D01*
G01X490031Y995474D02*
X491869Y994427D01*
G01X490031Y989096D02*
X491869Y988049D01*
G01X488181Y998663D02*
X490019Y997616D01*
G01X488181Y992285D02*
X490019Y991238D01*
G01X490031Y1001852D02*
X491869Y1000805D01*
G01X495582Y992285D02*
X497420Y991238D01*
G01X495582Y998663D02*
X497420Y997616D01*
G01X497433Y989096D02*
X499271Y988049D01*
G01X497433Y995474D02*
X499271Y994427D01*
G01X486330Y989096D02*
X488168Y988049D01*
G01X499283Y998663D02*
X501121Y997616D01*
G01X499283Y992285D02*
X501121Y991238D01*
G01X499283Y985907D02*
X501121Y984860D01*
G01X486330Y995474D02*
X488168Y994427D01*
G01X491881Y998663D02*
X493719Y997616D01*
G01X491881Y992285D02*
X493719Y991238D01*
G01X486330Y1001852D02*
X488168Y1000805D01*
G01X493732Y995474D02*
X495570Y994427D01*
G01X493732Y989096D02*
X495570Y988049D01*
G01X493732Y1001852D02*
X495570Y1000805D01*
G01X497433Y1001852D02*
X499271Y1000805D01*
G01X490031Y1008230D02*
X491869Y1007183D01*
G01X488181Y1011419D02*
X490019Y1010372D01*
G01X488181Y1005041D02*
X490019Y1003994D01*
G01X495582Y1011419D02*
X497420Y1010372D01*
G01X495582Y1005041D02*
X497420Y1003994D01*
G01X497433Y1008230D02*
X499271Y1007183D01*
G01X499283Y1011419D02*
X501121Y1010372D01*
G01X499283Y1005041D02*
X501121Y1003994D01*
G01X486330Y1008230D02*
X488168Y1007183D01*
G01X491881Y1005041D02*
X493719Y1003994D01*
G01X491881Y1011419D02*
X493719Y1010372D01*
G01X493732Y1008230D02*
X495570Y1007183D01*
G01X493063Y1027009D02*
X494901Y1028056D01*
G01X485661Y1027009D02*
X487499Y1028056D01*
G01X487511Y1030198D02*
X489349Y1031245D01*
G01X494913Y1030198D02*
X496751Y1031245D01*
G01X498614Y1030198D02*
X500452Y1031245D01*
G01X489362Y1027009D02*
X491200Y1028056D01*
G01X496763Y1027009D02*
X498601Y1028056D01*
G01X491212Y1030198D02*
X493050Y1031245D01*
G01X493063Y1033387D02*
X494901Y1034434D01*
G01X489362Y1039765D02*
X491200Y1040812D01*
G01X485661Y1033387D02*
X487499Y1034434D01*
G01X491212Y1036576D02*
X493050Y1037623D01*
G01X491212Y1042954D02*
X493050Y1044001D01*
G01X496763Y1039765D02*
X498601Y1040812D01*
G01X498614Y1036576D02*
X500452Y1037623D01*
G01X498614Y1042954D02*
X500452Y1044001D01*
G01X494913Y1036576D02*
X496751Y1037623D01*
G01X494913Y1042954D02*
X496751Y1044001D01*
G01X487511Y1036576D02*
X489349Y1037623D01*
G01X485661Y1039765D02*
X487499Y1040812D01*
G01X487511Y1042954D02*
X489349Y1044001D01*
G01X493063Y1039765D02*
X494901Y1040812D01*
G01X489362Y1033387D02*
X491200Y1034434D01*
G01X496763Y1033387D02*
X498601Y1034434D01*
G01X489362Y1046143D02*
X491200Y1047190D01*
G01X491212Y1055710D02*
X493050Y1056757D01*
G01X489362Y1058899D02*
X491200Y1059946D01*
G01X489362Y1052521D02*
X491200Y1053568D01*
G01X491212Y1049332D02*
X493050Y1050379D01*
G01X496763Y1046143D02*
X498601Y1047190D01*
G01X496763Y1052521D02*
X498601Y1053568D01*
G01X498614Y1055710D02*
X500452Y1056757D01*
G01X498614Y1049332D02*
X500452Y1050379D01*
G01X487511Y1049332D02*
X489349Y1050379D01*
G01X485661Y1046143D02*
X487499Y1047190D01*
G01X493063Y1046143D02*
X494901Y1047190D01*
G01X496763Y1058899D02*
X498601Y1059946D01*
G01X494913Y1055710D02*
X496751Y1056757D01*
G01X485661Y1052521D02*
X487499Y1053568D01*
G01X487511Y1055710D02*
X489349Y1056757D01*
G01X485661Y1058899D02*
X487499Y1059946D01*
G01X493063Y1052521D02*
X494901Y1053568D01*
G01X493063Y1058899D02*
X494901Y1059946D01*
G01X487511Y1062088D02*
X489349Y1063135D01*
G01X493063Y1065277D02*
X494901Y1066324D01*
G01X489362Y1065277D02*
X491200Y1066324D01*
G01X485661Y1065277D02*
X487499Y1066324D01*
G01X489362Y1071655D02*
X491200Y1072702D01*
G01X487511Y1068466D02*
X489349Y1069513D01*
G01X496763Y1065277D02*
X498601Y1066324D01*
G01X498614Y1062088D02*
X500452Y1063135D01*
G01X498614Y1068466D02*
X500452Y1069513D01*
G01X487511Y1074844D02*
X489349Y1075891D01*
G01X498614Y1074844D02*
X500452Y1075891D01*
G01X496763Y1071655D02*
X498601Y1072702D01*
G01X485661Y1071655D02*
X487499Y1072702D01*
G01X493063Y1071655D02*
X494901Y1072702D01*
G01X487511Y1081222D02*
X489349Y1082269D01*
G01X496763Y1078033D02*
X498601Y1079080D01*
G01X493063Y1078033D02*
X494901Y1079080D01*
G01X485661Y1078033D02*
X487499Y1079080D01*
G01X489362Y1078033D02*
X491200Y1079080D01*
G01X489362Y1084411D02*
X491200Y1085458D01*
G01X487511Y1087600D02*
X489349Y1088647D01*
G01X498614Y1087600D02*
X500452Y1088647D01*
G01X498614Y1081222D02*
X500452Y1082269D01*
G01X496763Y1084411D02*
X498601Y1085458D01*
G01X485661Y1084411D02*
X487499Y1085458D01*
G01X493063Y1084411D02*
X494901Y1085458D01*
G01X493063Y1090789D02*
X494901Y1091836D01*
G01X485661Y1090789D02*
X487499Y1091836D01*
G01X489362Y1090789D02*
X491200Y1091836D01*
G01X487511Y1093978D02*
X489349Y1095025D01*
G01X493063Y1103545D02*
X494901Y1104592D01*
G01X489362Y1097167D02*
X491200Y1098214D01*
G01X489362Y1103545D02*
X491200Y1104592D01*
G01X485661Y1103545D02*
X487499Y1104592D01*
G01X496763Y1090789D02*
X498601Y1091836D01*
G01X496763Y1103545D02*
X498601Y1104592D01*
G01X494913Y1100356D02*
X496751Y1101403D01*
G01X498614Y1093978D02*
X500452Y1095025D01*
G01X498614Y1100356D02*
X500452Y1101403D01*
G01X496763Y1097167D02*
X498601Y1098214D01*
G01X485661Y1097167D02*
X487499Y1098214D01*
G01X493063Y1097167D02*
X494901Y1098214D01*
G01X489362Y1109923D02*
X491200Y1110970D01*
G01X487511Y1113112D02*
X489349Y1114159D01*
G01X489362Y1116301D02*
X491200Y1117348D01*
G01X496763Y1109923D02*
X498601Y1110970D01*
G01X493063Y1109923D02*
X494901Y1110970D01*
G01X487511Y1106734D02*
X489349Y1107781D01*
G01X485661Y1109923D02*
X487499Y1110970D01*
G01X498614Y1106734D02*
X500452Y1107781D01*
G01X498614Y1113112D02*
X500452Y1114159D01*
G01X487511Y1119490D02*
X489349Y1120537D01*
G01X498614Y1119490D02*
X500452Y1120537D01*
G01X496763Y1116301D02*
X498601Y1117348D01*
G01X485661Y1116301D02*
X487499Y1117348D01*
G01X493063Y1116301D02*
X494901Y1117348D01*
G01X493063Y1122679D02*
X494901Y1123726D01*
G01X487511Y1125868D02*
X489349Y1126915D01*
G01X489362Y1122679D02*
X491200Y1123726D01*
G01X485661Y1122679D02*
X487499Y1123726D01*
G01X489362Y1129057D02*
X491200Y1130103D01*
G01X487511Y1132246D02*
X489349Y1133293D01*
G01X496763Y1122679D02*
X498601Y1123726D01*
G01X498614Y1125868D02*
X500452Y1126915D01*
G01X498614Y1132246D02*
X500452Y1133293D01*
G01X496763Y1129057D02*
X498601Y1130103D01*
G01X493063Y1129057D02*
X494901Y1130103D01*
G01X485661Y1129057D02*
X487499Y1130103D01*
G01X493063Y1135434D02*
X494901Y1136481D01*
G01X487511Y1138623D02*
X489349Y1139670D01*
G01X489362Y1135434D02*
X491200Y1136481D01*
G01X485661Y1135434D02*
X487499Y1136481D01*
G01X489362Y1141812D02*
X491200Y1142859D01*
G01X493063Y1148190D02*
X494901Y1149237D01*
G01X487511Y1145001D02*
X489349Y1146048D01*
G01X485661Y1148190D02*
X487499Y1149237D01*
G01X496763Y1135434D02*
X498601Y1136481D01*
G01X496763Y1148190D02*
X498601Y1149237D01*
G01X498614Y1138623D02*
X500452Y1139670D01*
G01X498614Y1145001D02*
X500452Y1146048D01*
G01X496763Y1141812D02*
X498601Y1142859D01*
G01X489362Y1148190D02*
X491200Y1149237D01*
G01X485661Y1141812D02*
X487499Y1142859D01*
G01X493063Y1141812D02*
X494901Y1142859D01*
G01X485661Y1154568D02*
X487499Y1155615D01*
G01X491212Y1157757D02*
X493050Y1158804D01*
G01X496763Y1154568D02*
X498601Y1155615D01*
G01X494913Y1151379D02*
X496751Y1152426D01*
G01X487511Y1151379D02*
X489349Y1152426D01*
G01X489362Y1160946D02*
X491200Y1161993D01*
G01X485661Y1160946D02*
X487499Y1161993D01*
G01X496763Y1160946D02*
X498601Y1161993D01*
G01X498614Y1151379D02*
X500452Y1152426D01*
G01X501133Y880671D02*
X502971Y879624D01*
G01X501133Y874293D02*
Y872118D01*
G01X514086Y877482D02*
X515924Y876435D01*
G01X506685Y877482D02*
X508523Y876435D01*
G01X504834Y880671D02*
X506672Y879624D01*
G01X510385Y877482D02*
X512223Y876435D01*
G01X506685Y883860D02*
X508523Y882813D01*
G01X504834Y887049D02*
X506672Y886002D01*
G01X501133Y887049D02*
X502971Y886002D01*
G01X502984Y883860D02*
X504822Y882813D01*
G01X504834Y893427D02*
X506672Y892380D01*
G01X510385Y883860D02*
X512223Y882813D01*
G01X512236Y887049D02*
X514074Y886002D01*
G01X510385Y890238D02*
X512223Y889191D01*
G01X512236Y893427D02*
X514074Y892380D01*
G01X510385Y896616D02*
X512223Y895569D01*
G01X504834Y899805D02*
X506672Y898758D01*
G01X504834Y906182D02*
X506672Y905135D01*
G01X504834Y912560D02*
X506672Y911513D01*
G01X510385Y902994D02*
X512223Y901947D01*
G01X512236Y899805D02*
X514074Y898758D01*
G01X510385Y909371D02*
X512223Y908325D01*
G01X512236Y906182D02*
X514074Y905135D01*
G01X512236Y912560D02*
X514074Y911513D01*
G01X504834Y918938D02*
X506672Y917891D01*
G01X504834Y925316D02*
X506672Y924269D01*
G01X512236Y918938D02*
X514074Y917891D01*
G01X510385Y922127D02*
X512223Y921080D01*
G01X510385Y915749D02*
X512223Y914702D01*
G01X512236Y925316D02*
X514074Y924269D01*
G01X504834Y931694D02*
X506672Y930647D01*
G01X504834Y938072D02*
X506672Y937025D01*
G01X510385Y928505D02*
X512223Y927458D01*
G01X512236Y931694D02*
X514074Y930647D01*
G01X510385Y941261D02*
X512223Y940214D01*
G01X512236Y938072D02*
X514074Y937025D01*
G01X510385Y934883D02*
X512223Y933836D01*
G01X504834Y944450D02*
X506672Y943403D01*
G01X504834Y950828D02*
X506672Y949781D01*
G01X504834Y957206D02*
X506672Y956159D01*
G01X512236Y950828D02*
X514074Y949781D01*
G01X510385Y947639D02*
X512223Y946592D01*
G01X512236Y944450D02*
X514074Y943403D01*
G01X510385Y954017D02*
X512223Y952970D01*
G01X512236Y957206D02*
X514074Y956159D01*
G01X504834Y963584D02*
X506672Y962537D01*
G01X504834Y969962D02*
X506672Y968915D01*
G01X510385Y960395D02*
X512223Y959348D01*
G01X510385Y966773D02*
X512223Y965726D01*
G01X512236Y969962D02*
X514074Y968915D01*
G01X512236Y963584D02*
X514074Y962537D01*
G01X508535Y982718D02*
X510373Y981671D01*
G01X504834Y976340D02*
X506672Y975293D01*
G01X504834Y982718D02*
X506672Y981671D01*
G01X506685Y985907D02*
X508523Y984860D01*
G01X512236Y976340D02*
X514074Y975293D01*
G01X510385Y979529D02*
X512223Y978482D01*
G01X510385Y985907D02*
X512223Y984860D01*
G01X512236Y982718D02*
X514074Y981671D01*
G01X510385Y973151D02*
X512223Y972104D01*
G01X504834Y989096D02*
X506672Y988049D01*
G01X504834Y995474D02*
X506672Y994427D01*
G01X504834Y1001852D02*
X506672Y1000805D01*
G01X512236Y989096D02*
X514074Y988049D01*
G01X512236Y995474D02*
X514074Y994427D01*
G01X510385Y998663D02*
X512223Y997616D01*
G01X510385Y992285D02*
X512223Y991238D01*
G01X504834Y1008230D02*
X506672Y1007183D01*
G01X512236Y1008230D02*
X514074Y1007183D01*
G01X510385Y1005041D02*
X512223Y1003994D01*
G01X512236Y1001852D02*
X514074Y1000805D01*
G01X510385Y1011419D02*
X512223Y1010372D01*
G01X500464Y1027009D02*
X502302Y1028056D01*
G01X511567Y1027009D02*
X513405Y1028056D01*
G01X506015Y1030198D02*
X507853Y1031245D01*
G01X513417Y1030198D02*
X515255Y1031245D01*
G01X506015Y1036576D02*
X507853Y1037623D01*
G01X500464Y1033387D02*
X502302Y1034434D01*
G01X506015Y1042954D02*
X507853Y1044001D01*
G01X511567Y1033387D02*
X513405Y1034434D01*
G01X511567Y1039765D02*
X513405Y1040812D01*
G01X513417Y1042954D02*
X515255Y1044001D01*
G01X500464Y1039765D02*
X502302Y1040812D01*
G01X513417Y1036576D02*
X515255Y1037623D01*
G01X506015Y1055710D02*
X507853Y1056757D01*
G01X506015Y1049332D02*
X507853Y1050379D01*
G01X502315Y1055710D02*
X504153Y1056757D01*
G01X500464Y1058899D02*
X502302Y1059946D01*
G01X504165Y1058899D02*
X506003Y1059946D01*
G01X511567Y1052521D02*
X513405Y1053568D01*
G01X511567Y1058899D02*
X513405Y1059946D01*
G01X513417Y1049332D02*
X515255Y1050379D01*
G01X511567Y1046143D02*
X513405Y1047190D01*
G01X500464Y1052521D02*
X502302Y1053568D01*
G01X500464Y1046143D02*
X502302Y1047190D01*
G01X513417Y1055710D02*
X515255Y1056757D01*
G01X506015Y1062088D02*
X507853Y1063135D01*
G01X506015Y1068466D02*
X507853Y1069513D01*
G01X500464Y1071655D02*
X502302Y1072702D01*
G01X511567Y1071655D02*
X513405Y1072702D01*
G01X513417Y1062088D02*
X515255Y1063135D01*
G01X513417Y1068466D02*
X515255Y1069513D01*
G01X506015Y1074844D02*
X507853Y1075891D01*
G01X500464Y1065277D02*
X502302Y1066324D01*
G01X511567Y1065277D02*
X513405Y1066324D01*
G01X513417Y1074844D02*
X515255Y1075891D01*
G01X506015Y1087600D02*
X507853Y1088647D01*
G01X500464Y1084411D02*
X502302Y1085458D01*
G01X506015Y1081222D02*
X507853Y1082269D01*
G01X511567Y1078033D02*
X513405Y1079080D01*
G01X513417Y1087600D02*
X515255Y1088647D01*
G01X513417Y1081222D02*
X515255Y1082269D01*
G01X500464Y1078033D02*
X502302Y1079080D01*
G01X511567Y1084411D02*
X513405Y1085458D01*
G01X506015Y1093978D02*
X507853Y1095025D01*
G01X500464Y1097167D02*
X502302Y1098214D01*
G01X506015Y1100356D02*
X507853Y1101403D01*
G01X500464Y1103545D02*
X502302Y1104592D01*
G01X511567Y1090789D02*
X513405Y1091836D01*
G01X511567Y1097167D02*
X513405Y1098214D01*
G01X513417Y1100356D02*
X515255Y1101403D01*
G01X500464Y1090789D02*
X502302Y1091836D01*
G01X511567Y1103545D02*
X513405Y1104592D01*
G01X513417Y1093978D02*
X515255Y1095025D01*
G01X506015Y1106734D02*
X507853Y1107781D01*
G01X506015Y1113112D02*
X507853Y1114159D01*
G01X500464Y1116301D02*
X502302Y1117348D01*
G01X511567Y1109923D02*
X513405Y1110970D01*
G01X511567Y1116301D02*
X513405Y1117348D01*
G01X513417Y1106734D02*
X515255Y1107781D01*
G01X506015Y1119490D02*
X507853Y1120537D01*
G01X513417Y1119490D02*
X515255Y1120537D01*
G01X500464Y1109923D02*
X502302Y1110970D01*
G01X513417Y1113112D02*
X515255Y1114159D01*
G01X506015Y1125868D02*
X507853Y1126915D01*
G01X506015Y1132246D02*
X507853Y1133293D01*
G01X500464Y1129057D02*
X502302Y1130103D01*
G01X513417Y1125868D02*
X515255Y1126915D01*
G01X511567Y1129057D02*
X513405Y1130104D01*
G01X500464Y1122679D02*
X502302Y1123726D01*
G01X511567Y1122679D02*
X513405Y1123726D01*
G01X513417Y1132246D02*
X515255Y1133293D01*
G01X506015Y1138623D02*
X507853Y1139670D01*
G01X500464Y1141812D02*
X502302Y1142859D01*
G01X506015Y1145001D02*
X507853Y1146048D01*
G01X511567Y1135434D02*
X513405Y1136481D01*
G01X511567Y1148190D02*
X513405Y1149237D01*
G01X513417Y1138623D02*
X515255Y1139670D01*
G01X513417Y1145001D02*
X515255Y1146048D01*
G01X500464Y1135434D02*
X502302Y1136481D01*
G01X511567Y1141812D02*
X513405Y1142859D01*
G01X500464Y1148190D02*
X502302Y1149237D01*
G01X509716Y1164135D02*
X511554Y1165182D01*
G01X507866Y1154568D02*
X509704Y1155615D01*
G01X506015Y1151379D02*
X507853Y1152426D01*
G01X500464Y1154568D02*
X502302Y1155615D01*
G01X506015Y1157757D02*
X507853Y1158804D01*
G01X502315Y1157757D02*
X504153Y1158804D01*
G01X511567Y1154568D02*
X513405Y1155615D01*
G01X513417Y1157757D02*
X515255Y1158804D01*
G01X513417Y1151379D02*
X515255Y1152426D01*
G01X500464Y1160946D02*
X502302Y1161993D01*
G01X507866Y1160946D02*
X509704Y1161993D01*
G01X509716Y1157757D02*
X511554Y1158804D01*
G01X511567Y1160946D02*
X513405Y1161993D01*
G01X523338Y880671D02*
X525176Y879624D01*
G01X523338Y874293D02*
X525176Y873246D01*
G01X523338Y887049D02*
X525176Y886002D01*
G01X521488Y883860D02*
X523326Y882813D01*
G01X515937Y887049D02*
X517775Y886002D01*
G01X517787Y883860D02*
X519625Y882813D01*
G01X525189Y896616D02*
X527027Y895569D01*
G01X525189Y890238D02*
X527027Y889191D01*
G01X523338Y893427D02*
X525176Y892380D01*
G01X517787Y890238D02*
X519625Y889191D01*
G01X517787Y896616D02*
X519625Y895569D01*
G01X527039Y887049D02*
X528877Y886002D01*
G01X525189Y902994D02*
X527027Y901947D01*
G01X523338Y899805D02*
X525176Y898758D01*
G01X517787Y902994D02*
X519625Y901947D01*
G01X523338Y906182D02*
X525176Y905135D01*
G01X523338Y912560D02*
X525176Y911513D01*
G01X517787Y909371D02*
X519625Y908325D01*
G01X525189Y909371D02*
X527027Y908324D01*
G01X523338Y918938D02*
X525176Y917891D01*
G01X517787Y915749D02*
X519625Y914702D01*
G01X525189Y915749D02*
X527027Y914702D01*
G01X525189Y922127D02*
X527027Y921080D01*
G01X523338Y925316D02*
X525176Y924269D01*
G01X517787Y922127D02*
X519625Y921080D01*
G01X523338Y938072D02*
X525176Y937025D01*
G01X525189Y928505D02*
X527027Y927458D01*
G01X525189Y934883D02*
X527027Y933836D01*
G01X523338Y931694D02*
X525176Y930647D01*
G01X517787Y928505D02*
X519625Y927458D01*
G01X517787Y934883D02*
X519625Y933836D01*
G01X525189Y941261D02*
X527027Y940214D01*
G01X517787Y941261D02*
X519625Y940214D01*
G01X525189Y947639D02*
X527027Y946592D01*
G01X517787Y947639D02*
X519625Y946592D01*
G01X523338Y944450D02*
X525176Y943403D01*
G01X523338Y950828D02*
X525176Y949781D01*
G01X525189Y954017D02*
X527027Y952970D01*
G01X523338Y957206D02*
X525176Y956159D01*
G01X517787Y954017D02*
X519625Y952970D01*
G01X525189Y960395D02*
X527027Y959348D01*
G01X525189Y966773D02*
X527027Y965726D01*
G01X523338Y963584D02*
X525176Y962537D01*
G01X517787Y960395D02*
X519625Y959348D01*
G01X517787Y966773D02*
X519625Y965726D01*
G01X523338Y969962D02*
X525176Y968915D01*
G01X519637Y982718D02*
X521475Y981671D01*
G01X517787Y979529D02*
X519625Y978482D01*
G01X525189Y985907D02*
X527027Y984860D01*
G01X521488Y985907D02*
X523326Y984860D01*
G01X517787Y985907D02*
X519625Y984860D01*
G01X525189Y973151D02*
X527027Y972104D01*
G01X525189Y979529D02*
X527027Y978482D01*
G01X523338Y976340D02*
X525176Y975293D01*
G01X523338Y982718D02*
X525176Y981671D01*
G01X517787Y973151D02*
X519625Y972104D01*
G01X525189Y992285D02*
X527027Y991238D01*
G01X525189Y998663D02*
X527027Y997616D01*
G01X523338Y989096D02*
X525176Y988049D01*
G01X523338Y995474D02*
X525176Y994427D01*
G01X517787Y992285D02*
X519625Y991238D01*
G01X517787Y998663D02*
X519625Y997616D01*
G01X523338Y1001852D02*
X525176Y1000805D01*
G01X525189Y1011419D02*
X527027Y1010372D01*
G01X525189Y1005041D02*
X527027Y1003994D01*
G01X523338Y1008230D02*
X525176Y1007183D01*
G01X517787Y1011419D02*
X519625Y1010372D01*
G01X517787Y1005041D02*
X519625Y1003994D01*
G01X518968Y1027009D02*
X520806Y1028056D01*
G01X526370Y1027009D02*
X528208Y1028056D01*
G01X524519Y1030198D02*
X526357Y1031245D01*
G01X524519Y1036576D02*
X526357Y1037623D01*
G01X524519Y1042954D02*
X526357Y1044001D01*
G01X518968Y1039765D02*
X520806Y1040812D01*
G01X518968Y1033387D02*
X520806Y1034434D01*
G01X526370Y1039765D02*
X528208Y1040812D01*
G01X526370Y1033387D02*
X528208Y1034434D01*
G01X518968Y1046143D02*
X520806Y1047190D01*
G01X524519Y1049332D02*
X526357Y1050379D01*
G01X524519Y1055710D02*
X526357Y1056757D01*
G01X518968Y1052521D02*
X520806Y1053568D01*
G01X517118Y1055710D02*
X518956Y1056757D01*
G01X518968Y1058899D02*
X520806Y1059946D01*
G01X515267Y1058899D02*
X517105Y1059946D01*
G01X526370Y1046143D02*
X528208Y1047190D01*
G01X526370Y1052521D02*
X528208Y1053568D01*
G01X526370Y1058899D02*
X528208Y1059946D01*
G01X528220Y1055710D02*
X530058Y1056757D01*
G01X524519Y1062088D02*
X526357Y1063135D01*
G01X524519Y1068466D02*
X526357Y1069513D01*
G01X518968Y1065277D02*
X520806Y1066324D01*
G01X518968Y1071655D02*
X520806Y1072702D01*
G01X526370Y1065277D02*
X528208Y1066324D01*
G01X526370Y1071655D02*
X528208Y1072702D01*
G01X524519Y1074844D02*
X526357Y1075891D01*
G01X518968Y1078033D02*
X520806Y1079080D01*
G01X524519Y1087600D02*
X526357Y1088647D01*
G01X524519Y1081222D02*
X526357Y1082269D01*
G01X518968Y1084411D02*
X520806Y1085458D01*
G01X526370Y1078033D02*
X528208Y1079080D01*
G01X526370Y1084411D02*
X528208Y1085458D01*
G01X524519Y1093978D02*
X526357Y1095025D01*
G01X518968Y1090789D02*
X520806Y1091836D01*
G01X524519Y1100356D02*
X526357Y1101403D01*
G01X518968Y1103545D02*
X520806Y1104592D01*
G01X518968Y1097167D02*
X520806Y1098214D01*
G01X526370Y1090789D02*
X528208Y1091836D01*
G01X526370Y1103545D02*
X528208Y1104592D01*
G01X526370Y1097167D02*
X528208Y1098214D01*
G01X524519Y1106734D02*
X526357Y1107781D01*
G01X518968Y1109923D02*
X520806Y1110970D01*
G01X524519Y1113112D02*
X526357Y1114159D01*
G01X518968Y1116301D02*
X520806Y1117348D01*
G01X526370Y1109923D02*
X528208Y1110970D01*
G01X526370Y1116301D02*
X528208Y1117348D01*
G01X524519Y1119490D02*
X526357Y1120537D01*
G01X524519Y1125868D02*
X526357Y1126915D01*
G01X518968Y1122679D02*
X520806Y1123726D01*
G01X524519Y1132246D02*
X526357Y1133293D01*
G01X518968Y1129057D02*
X520806Y1130103D01*
G01X526370Y1122679D02*
X528208Y1123726D01*
G01X526370Y1129057D02*
X528208Y1130104D01*
G01X518968Y1141812D02*
X520806Y1142859D01*
G01X524519Y1138623D02*
X526357Y1139670D01*
G01X518968Y1135434D02*
X520806Y1136481D01*
G01X524519Y1145001D02*
X526357Y1146048D01*
G01X518968Y1148190D02*
X520806Y1149237D01*
G01X526370Y1135434D02*
X528208Y1136481D01*
G01X526370Y1141812D02*
X528208Y1142859D01*
G01X526370Y1148190D02*
X528208Y1149237D01*
G01X524519Y1164135D02*
X524551Y1164254D01*
X526370Y1165290D01*
G01X524519Y1151379D02*
X526357Y1152426D01*
G01X524519Y1157757D02*
X526357Y1158804D01*
G01X518968Y1154568D02*
X520806Y1155615D01*
G01X515267Y1154568D02*
X517105Y1155615D01*
G01X520818Y1157757D02*
X522657Y1158804D01*
G01X515267Y1160946D02*
X517105Y1161993D01*
G01X526370Y1154568D02*
X528208Y1155615D01*
G01X528220Y1157757D02*
X530058Y1158804D01*
G01X532590Y877482D02*
X534428Y876435D01*
G01X538141Y880671D02*
X539979Y879624D01*
G01X530740Y880671D02*
X532578Y879624D01*
G01X539992Y877482D02*
X541830Y876435D01*
G01X541842Y880671D02*
X543680Y879624D01*
G01X543693Y877482D02*
X545531Y876435D01*
G01X536291Y890238D02*
X538129Y889191D01*
G01X538141Y893427D02*
X539979Y892380D01*
G01X530740Y893427D02*
X532578Y892380D01*
G01X541842Y887049D02*
X543680Y886002D01*
G01X536291Y883860D02*
X538129Y882813D01*
G01X530740Y887049D02*
X532578Y886002D01*
G01X532590Y883860D02*
X534428Y882813D01*
G01X543693Y890238D02*
X545531Y889191D01*
G01X543693Y883860D02*
X545531Y882813D01*
G01X536291Y896616D02*
X538129Y895569D01*
G01X538141Y887049D02*
X539979Y886002D01*
G01X543693Y896616D02*
X545531Y895569D01*
G01X536291Y902994D02*
X538129Y901947D01*
G01X538141Y899805D02*
X539979Y898758D01*
G01X530740Y899805D02*
X532578Y898758D01*
G01X538141Y912560D02*
X539979Y911513D01*
G01X536291Y909371D02*
X538129Y908325D01*
G01X530740Y906182D02*
X532578Y905135D01*
G01X530740Y912560D02*
X532578Y911513D01*
G01X543693Y902994D02*
X545531Y901947D01*
G01X543693Y909371D02*
X545531Y908324D01*
G01X538141Y906182D02*
X539979Y905135D01*
G01X538141Y918938D02*
X539979Y917891D01*
G01X530740Y918938D02*
X532578Y917891D01*
G01X536291Y922127D02*
X538129Y921080D01*
G01X530740Y925316D02*
X532578Y924269D01*
G01X543693Y915749D02*
X545531Y914702D01*
G01X543693Y922127D02*
X545531Y921080D01*
G01X538141Y925316D02*
X539979Y924269D01*
G01X536291Y915749D02*
X538129Y914702D01*
G01X536291Y928505D02*
X538129Y927458D01*
G01X538141Y931694D02*
X539979Y930647D01*
G01X530740Y931694D02*
X532578Y930647D01*
G01X538141Y938072D02*
X539979Y937025D01*
G01X536291Y941261D02*
X538129Y940214D01*
G01X530740Y938072D02*
X532578Y937025D01*
G01X543693Y928505D02*
X545531Y927458D01*
G01X543693Y934883D02*
X545531Y933836D01*
G01X536291Y934883D02*
X538129Y933836D01*
G01X543693Y941261D02*
X545531Y940214D01*
G01X538141Y950828D02*
X539979Y949781D01*
G01X536291Y947639D02*
X538129Y946592D01*
G01X530740Y944450D02*
X532578Y943403D01*
G01X530740Y950828D02*
X532578Y949781D01*
G01X538141Y957206D02*
X539979Y956159D01*
G01X530740Y957206D02*
X532578Y956159D01*
G01X543693Y947639D02*
X545531Y946592D01*
G01X543693Y954017D02*
X545531Y952970D01*
G01X536291Y954017D02*
X538129Y952970D01*
G01X538141Y944450D02*
X539979Y943403D01*
G01X536291Y960395D02*
X538129Y959348D01*
G01X536291Y966773D02*
X538129Y965726D01*
G01X530740Y963584D02*
X532578Y962537D01*
G01X538141Y969962D02*
X539979Y968915D01*
G01X530740Y969962D02*
X532578Y968915D01*
G01X543693Y960395D02*
X545531Y959348D01*
G01X543693Y966773D02*
X545531Y965726D01*
G01X538141Y963584D02*
X539979Y962537D01*
G01X538141Y976340D02*
X539979Y975293D01*
G01X530740Y976340D02*
X532578Y975293D01*
G01X536291Y979529D02*
X538129Y978482D01*
G01X534441Y982718D02*
X536279Y981671D01*
G01X530740Y982718D02*
X532578Y981671D01*
G01X536291Y985907D02*
X538129Y984860D01*
G01X532590Y985907D02*
X534428Y984860D01*
G01X543693Y973151D02*
X545531Y972104D01*
G01X543693Y979529D02*
X545531Y978482D01*
G01X536291Y973151D02*
X538129Y972104D01*
G01X538141Y982718D02*
X539979Y981671D01*
G01X543693Y985907D02*
X545531Y984860D01*
G01X530740Y995474D02*
X532578Y994427D01*
G01X538141Y989096D02*
X539979Y988049D01*
G01X530740Y989096D02*
X532578Y988049D01*
G01X538141Y995474D02*
X539979Y994427D01*
G01X536291Y998663D02*
X538129Y997616D01*
G01X530740Y1001852D02*
X532578Y1000805D01*
G01X543693Y992285D02*
X545531Y991238D01*
G01X543693Y998663D02*
X545531Y997616D01*
G01X538141Y1001852D02*
X539979Y1000805D01*
G01X536291Y992285D02*
X538129Y991238D01*
G01X538141Y1008230D02*
X539977Y1007184D01*
X539978D01*
G01X536291Y1005041D02*
X538129Y1003994D01*
G01X530740Y1008230D02*
X532578Y1007183D01*
G01X543693Y1011419D02*
X545531Y1010372D01*
G01X543693Y1005041D02*
X545531Y1003994D01*
G01X536291Y1011419D02*
X538129Y1010372D01*
G01X537472Y1027009D02*
X539310Y1028056D01*
G01X539322Y1030198D02*
X541160Y1031245D01*
G01X531921Y1030198D02*
X533759Y1031245D01*
G01X537472Y1033387D02*
X539310Y1034434D01*
G01X537472Y1039765D02*
X539310Y1040812D01*
G01X531921Y1036576D02*
X533759Y1037623D01*
G01X539322Y1042954D02*
X541160Y1044001D01*
G01X531921Y1042954D02*
X533759Y1044001D01*
G01X539322Y1036576D02*
X541160Y1037623D01*
G01X541173Y1058899D02*
X543011Y1059946D01*
G01X539322Y1049332D02*
X541160Y1050379D01*
G01X537472Y1052521D02*
X539310Y1053568D01*
G01X531921Y1049332D02*
X533759Y1050379D01*
G01X531921Y1055710D02*
X533759Y1056757D01*
G01X537472Y1058899D02*
X539310Y1059946D01*
G01X530070Y1058899D02*
X531908Y1059946D01*
G01X543023Y1055710D02*
X544861Y1056757D01*
G01X537472Y1046143D02*
X539310Y1047190D01*
G01X539322Y1055710D02*
X541160Y1056757D01*
G01X539322Y1062088D02*
X541160Y1063135D01*
G01X531921Y1062088D02*
X533759Y1063135D01*
G01X539322Y1068466D02*
X541160Y1069513D01*
G01X537472Y1071655D02*
X539310Y1072702D01*
G01X531921Y1068466D02*
X533759Y1069513D01*
G01X531921Y1074844D02*
X533759Y1075891D01*
G01X537472Y1065277D02*
X539310Y1066324D01*
G01X539322Y1074844D02*
X541160Y1075891D01*
G01X537472Y1078033D02*
X539310Y1079080D01*
G01X539322Y1087600D02*
X541160Y1088647D01*
G01X531921Y1087600D02*
X533759Y1088647D01*
G01X539322Y1081222D02*
X541160Y1082269D01*
G01X531921Y1081222D02*
X533759Y1082269D01*
G01X537472Y1084411D02*
X539310Y1085458D01*
G01X537472Y1090789D02*
X539310Y1091836D01*
G01X531921Y1093978D02*
X533759Y1095025D01*
G01X537472Y1097167D02*
X539310Y1098214D01*
G01X539322Y1100356D02*
X541160Y1101403D01*
G01X531921Y1100356D02*
X533759Y1101403D01*
G01X537472Y1103545D02*
X539310Y1104592D01*
G01X539322Y1093978D02*
X541160Y1095025D01*
G01X539322Y1106734D02*
X541160Y1107781D01*
G01X531921Y1106734D02*
X533759Y1107781D01*
G01X537472Y1109923D02*
X539310Y1110970D01*
G01X537472Y1116301D02*
X539310Y1117348D01*
G01X531921Y1113112D02*
X533759Y1114159D01*
G01X539322Y1119490D02*
X541160Y1120537D01*
G01X531921Y1119490D02*
X533759Y1120537D01*
G01X539322Y1113112D02*
X541160Y1114159D01*
G01X539322Y1125868D02*
X541160Y1126915D01*
G01X531921Y1125868D02*
X533759Y1126915D01*
G01X537472Y1129057D02*
X539310Y1130103D01*
G01X531921Y1132246D02*
X533759Y1133293D01*
G01X539322Y1132246D02*
X541160Y1133293D01*
G01X537472Y1122679D02*
X539310Y1123726D01*
G01X539322Y1138623D02*
X541160Y1139670D01*
G01X537472Y1135434D02*
X539310Y1136481D01*
G01X531921Y1138623D02*
X533759Y1139670D01*
G01X531921Y1145001D02*
X533759Y1146048D01*
G01X539322Y1145001D02*
X541160Y1146048D01*
G01X537472Y1148190D02*
X539310Y1149237D01*
G01X537472Y1141812D02*
X539310Y1142859D01*
G01X541173Y1154568D02*
X543011Y1155615D01*
G01X531921Y1157757D02*
X533759Y1158804D01*
G01X537472Y1154568D02*
X539310Y1155615D01*
G01X533771Y1154568D02*
X535609Y1155615D01*
G01X531921Y1151379D02*
X533759Y1152426D01*
G01X541173Y1160946D02*
X543011Y1161993D01*
G01X539322Y1151379D02*
X541160Y1152426D01*
G01X551094Y877482D02*
X552932Y876435D01*
G01X554795Y877482D02*
X556633Y876435D01*
G01X549244Y880671D02*
X551082Y879624D01*
G01X545543Y874293D02*
Y872085D01*
G01X552944Y887049D02*
X554783Y886002D01*
G01X547393Y883860D02*
X549231Y882813D01*
G01X556645Y893427D02*
X558483Y892380D01*
G01X551094Y890238D02*
X552932Y889191D01*
G01X549244Y893427D02*
X551082Y892380D01*
G01X551094Y896616D02*
X552932Y895569D01*
G01X556645Y887049D02*
X558483Y886002D01*
G01X549244Y887049D02*
X551082Y886002D01*
G01X558496Y883860D02*
X560334Y882813D01*
G01X556645Y899805D02*
X558483Y898758D01*
G01X551094Y902994D02*
X552932Y901947D01*
G01X549244Y899805D02*
X551082Y898758D01*
G01X556645Y906182D02*
X558483Y905135D01*
G01X549244Y906182D02*
X551082Y905135D01*
G01X549244Y912560D02*
X551082Y911513D01*
G01X551094Y909371D02*
X552932Y908325D01*
G01X556645Y912560D02*
X558483Y911513D01*
G01X556645Y918938D02*
X558483Y917891D01*
G01X549244Y918938D02*
X551082Y917891D01*
G01X551094Y915749D02*
X552932Y914702D01*
G01X556645Y925316D02*
X558483Y924269D01*
G01X549244Y925316D02*
X551082Y924269D01*
G01X551094Y922127D02*
X552932Y921080D01*
G01X556645Y931694D02*
X558483Y930647D01*
G01X551094Y928505D02*
X552932Y927458D01*
G01X551094Y934883D02*
X552932Y933836D01*
G01X549244Y931694D02*
X551082Y930647D01*
G01X556645Y938072D02*
X558483Y937025D01*
G01X549244Y938072D02*
X551082Y937025D01*
G01X551094Y941261D02*
X552932Y940214D01*
G01X556645Y944450D02*
X558483Y943403D01*
G01X556645Y950828D02*
X558483Y949781D01*
G01X549244Y944450D02*
X551082Y943403D01*
G01X549244Y950828D02*
X551082Y949781D01*
G01X551094Y947639D02*
X552932Y946592D01*
G01X551094Y954017D02*
X552932Y952970D01*
G01X549244Y957206D02*
X551082Y956159D01*
G01X556645Y957206D02*
X558483Y956159D01*
G01X556645Y963584D02*
X558483Y962537D01*
G01X551094Y960395D02*
X552932Y959348D01*
G01X549244Y963584D02*
X551082Y962537D01*
G01X551094Y966773D02*
X552932Y965726D01*
G01X556645Y969962D02*
X558483Y968915D01*
G01X549244Y969962D02*
X551082Y968915D01*
G01X556645Y976340D02*
X558483Y975293D01*
G01X556645Y982718D02*
X558483Y981671D01*
G01X545543Y982718D02*
X547381Y981671D01*
G01X549244Y976340D02*
X551082Y975293D01*
G01X551094Y973151D02*
X552932Y972104D01*
G01X549244Y982718D02*
X551082Y981671D01*
G01X551094Y979529D02*
X552932Y978482D01*
G01X551094Y985907D02*
X552932Y984860D01*
G01X547393Y985907D02*
X549231Y984860D01*
G01X558496Y985907D02*
X560334Y984860D01*
G01X556645Y989096D02*
X558483Y988049D01*
G01X556645Y995474D02*
X558483Y994427D01*
G01X551094Y992285D02*
X552932Y991238D01*
G01X549244Y995474D02*
X551082Y994427D01*
G01X551094Y998663D02*
X552932Y997616D01*
G01X549244Y989096D02*
X551082Y988049D01*
G01X556645Y1001852D02*
X558483Y1000805D01*
G01X549244Y1001852D02*
X551082Y1000805D01*
G01X556645Y1008230D02*
X558483Y1007183D01*
G01X551094Y1011419D02*
X552932Y1010372D01*
G01X549244Y1008230D02*
X551082Y1007183D01*
G01X551094Y1005041D02*
X552932Y1003994D01*
G01X552275Y1027009D02*
X554113Y1028056D01*
G01X544874Y1027009D02*
X546712Y1028056D01*
G01X550425Y1030198D02*
X552263Y1031245D01*
G01X557826Y1030198D02*
X559664Y1031245D01*
G01X544874Y1039765D02*
X546712Y1040812D01*
G01X544874Y1033387D02*
X546712Y1034434D01*
G01X552275Y1039765D02*
X554113Y1040812D01*
G01X550425Y1036576D02*
X552263Y1037623D01*
G01X552275Y1033387D02*
X554113Y1034434D01*
G01X550425Y1042954D02*
X552263Y1044001D01*
G01X557826Y1036576D02*
X559664Y1037623D01*
G01X557826Y1042954D02*
X559664Y1044001D01*
G01X544874Y1046143D02*
X546712Y1047190D01*
G01X552275Y1046143D02*
X554113Y1047190D01*
G01X544874Y1052521D02*
X546712Y1053568D01*
G01X544874Y1058899D02*
X546712Y1059946D01*
G01X550425Y1055710D02*
X552263Y1056757D01*
G01X554126Y1055710D02*
X555964Y1056757D01*
G01X552275Y1052521D02*
X554113Y1053568D01*
G01X550425Y1049332D02*
X552263Y1050379D01*
G01X552275Y1058899D02*
X554113Y1059946D01*
G01X555976Y1058899D02*
X557814Y1059946D01*
G01X557826Y1049332D02*
X559664Y1050379D01*
G01X557826Y1055710D02*
X559664Y1056757D01*
G01X550425Y1062088D02*
X552263Y1063135D01*
G01X544874Y1071655D02*
X546712Y1072702D01*
G01X544874Y1065277D02*
X546712Y1066324D01*
G01X550425Y1068466D02*
X552263Y1069513D01*
G01X552275Y1065277D02*
X554113Y1066324D01*
G01X552275Y1071655D02*
X554113Y1072702D01*
G01X557826Y1062088D02*
X559664Y1063135D01*
G01X557826Y1068466D02*
X559664Y1069513D01*
G01X550425Y1074844D02*
X552263Y1075891D01*
G01X557826Y1074844D02*
X559664Y1075891D01*
G01X544874Y1078033D02*
X546712Y1079080D01*
G01X552275Y1078033D02*
X554113Y1079080D01*
G01X544874Y1084411D02*
X546712Y1085458D01*
G01X550425Y1087600D02*
X552263Y1088647D01*
G01X552275Y1084411D02*
X554113Y1085458D01*
G01X550425Y1081222D02*
X552263Y1082269D01*
G01X557826Y1087600D02*
X559664Y1088647D01*
G01X557826Y1081222D02*
X559664Y1082269D01*
G01X544874Y1090789D02*
X546712Y1091836D01*
G01X552275Y1090789D02*
X554113Y1091836D01*
G01X550425Y1093978D02*
X552263Y1095025D01*
G01X550425Y1100356D02*
X552263Y1101403D01*
G01X552275Y1097167D02*
X554113Y1098214D01*
G01X544874Y1103545D02*
X546712Y1104592D01*
G01X544874Y1097167D02*
X546712Y1098214D01*
G01X552275Y1103545D02*
X554113Y1104592D01*
G01X557826Y1093978D02*
X559664Y1095025D01*
G01X557826Y1100356D02*
X559664Y1101403D01*
G01X550425Y1106734D02*
X552263Y1107781D01*
G01X552275Y1109923D02*
X554113Y1110970D01*
G01X544874Y1109923D02*
X546712Y1110970D01*
G01X552275Y1116301D02*
X554113Y1117348D01*
G01X550425Y1113112D02*
X552263Y1114159D01*
G01X544874Y1116301D02*
X546712Y1117348D01*
G01X557826Y1106734D02*
X559664Y1107781D01*
G01X557826Y1113112D02*
X559664Y1114159D01*
G01X550425Y1119490D02*
X552263Y1120537D01*
G01X557826Y1119490D02*
X559664Y1120537D01*
G01X544874Y1122679D02*
X546712Y1123726D01*
G01X552275Y1122679D02*
X554113Y1123726D01*
G01X550425Y1125868D02*
X552263Y1126915D01*
G01X550425Y1132246D02*
X552263Y1133293D01*
G01X552275Y1129057D02*
X554113Y1130103D01*
G01X557826Y1125868D02*
X559664Y1126915D01*
G01X557826Y1132246D02*
X559664Y1133293D01*
G01X544874Y1129057D02*
X546712Y1130104D01*
G01X550425Y1138623D02*
X552263Y1139670D01*
G01X552275Y1135434D02*
X554113Y1136481D01*
G01X544874Y1135434D02*
X546712Y1136481D01*
G01X552275Y1141812D02*
X554113Y1142859D01*
G01X544874Y1141812D02*
X546712Y1142859D01*
G01X544874Y1148190D02*
X546712Y1149237D01*
G01X550425Y1145001D02*
X552263Y1146048D01*
G01X552275Y1148190D02*
X554113Y1149237D01*
G01X557826Y1138623D02*
X559664Y1139670D01*
G01X557826Y1145001D02*
X559664Y1146048D01*
G01X554126Y1164135D02*
X555964Y1165182D01*
G01X552275Y1154568D02*
X554113Y1155615D01*
G01X550425Y1151379D02*
X552263Y1152426D01*
G01X554126Y1157757D02*
X555964Y1158804D01*
G01X550425Y1157757D02*
X552263Y1158804D01*
G01X546724Y1157757D02*
X548562Y1158804D01*
G01X544874Y1154568D02*
X546712Y1155615D01*
G01X552275Y1160946D02*
X554113Y1161993D01*
G01X557826Y1151379D02*
X559664Y1152426D01*
G01X557826Y1157757D02*
X559664Y1158804D01*
G01X560346Y880671D02*
X562184Y879624D01*
G01X567748Y874293D02*
X569586Y873246D01*
G01X564047Y880671D02*
X565885Y879624D01*
G01X562196Y877482D02*
X564034Y876435D01*
G01X562196Y883860D02*
X564034Y882813D01*
G01X567748Y887049D02*
X569586Y886002D01*
G01X569598Y883860D02*
X571436Y882813D01*
G01X569598Y890238D02*
X571436Y889191D01*
G01X562196Y890238D02*
X564034Y889191D01*
G01X564047Y893427D02*
X565885Y892380D01*
G01X569598Y896616D02*
X571436Y895569D01*
G01X573299Y883860D02*
X575137Y882813D01*
G01X562196Y896616D02*
X564034Y895569D01*
G01X564047Y887049D02*
X565885Y886002D01*
G01X562196Y902994D02*
X564034Y901947D01*
G01X569598Y902994D02*
X571436Y901947D01*
G01X564047Y899805D02*
X565885Y898758D01*
G01X562196Y909371D02*
X564034Y908325D01*
G01X569598Y909371D02*
X571436Y908325D01*
G01X564047Y912560D02*
X565885Y911513D01*
G01X564047Y906182D02*
X565885Y905135D01*
G01X564047Y918938D02*
X565885Y917891D01*
G01X569598Y915749D02*
X571436Y914702D01*
G01X562196Y922127D02*
X564034Y921080D01*
G01X569598Y922127D02*
X571436Y921080D01*
G01X564047Y925316D02*
X565885Y924269D01*
G01X562196Y915749D02*
X564034Y914702D01*
G01X562196Y928505D02*
X564034Y927458D01*
G01X569598Y928505D02*
X571436Y927458D01*
G01X564047Y931694D02*
X565885Y930647D01*
G01X569598Y934883D02*
X571436Y933836D01*
G01X564047Y938072D02*
X565885Y937025D01*
G01X562196Y941261D02*
X564034Y940214D01*
G01X569598Y941261D02*
X571436Y940214D01*
G01X562196Y934883D02*
X564034Y933836D01*
G01X564047Y950828D02*
X565885Y949781D01*
G01X562196Y947639D02*
X564034Y946592D01*
G01X569598Y947639D02*
X571436Y946592D01*
G01X569598Y954017D02*
X571436Y952970D01*
G01X564047Y957206D02*
X565885Y956159D01*
G01X562196Y954017D02*
X564034Y952970D01*
G01X564047Y944450D02*
X565885Y943403D01*
G01X562196Y960395D02*
X564034Y959348D01*
G01X569598Y960395D02*
X571436Y959348D01*
G01X562196Y966773D02*
X564034Y965726D01*
G01X569598Y966773D02*
X571436Y965726D01*
G01X564047Y969962D02*
X565885Y968915D01*
G01X564047Y963584D02*
X565885Y962537D01*
G01X560346Y982718D02*
X562184Y981671D01*
G01X564047Y976340D02*
X565885Y975293D01*
G01X569598Y973151D02*
X571436Y972104D01*
G01X562196Y979529D02*
X564034Y978482D01*
G01X569598Y979529D02*
X571436Y978482D01*
G01X565897Y985907D02*
X567735Y984860D01*
G01X562196Y985907D02*
X564034Y984860D01*
G01X569598Y985907D02*
X571436Y984860D01*
G01X564047Y982718D02*
X565885Y981671D01*
G01X562196Y973151D02*
X564034Y972104D01*
G01X567748Y989096D02*
X569586Y988049D01*
G01X569598Y992285D02*
X571436Y991238D01*
G01X564047Y995474D02*
X565885Y994427D01*
G01X562196Y998663D02*
X564034Y997616D01*
G01X569598Y998663D02*
X571436Y997616D01*
G01X564047Y989096D02*
X565885Y988049D01*
G01X564047Y1001852D02*
X565885Y1000805D01*
G01X562196Y992285D02*
X564034Y991238D01*
G01X569598Y1011419D02*
X571436Y1010372D01*
G01X564047Y1008230D02*
X565885Y1007183D01*
G01X562196Y1005041D02*
X564034Y1003994D01*
G01X569598Y1005041D02*
X571436Y1003994D01*
G01X562196Y1011419D02*
X564034Y1010372D01*
G01X563378Y1027009D02*
X565216Y1028056D01*
G01X570779Y1027009D02*
X572617Y1028056D01*
G01X565228Y1030198D02*
X567066Y1031245D01*
G01X563378Y1033387D02*
X565215Y1034434D01*
G01X563378Y1039765D02*
X565215Y1040812D01*
G01X570779Y1033387D02*
X572617Y1034434D01*
G01X570779Y1039765D02*
X572617Y1040812D01*
G01X565228Y1042954D02*
X567066Y1044001D01*
G01X565228Y1036576D02*
X567066Y1037623D01*
G01X563378Y1058899D02*
X565215Y1059946D01*
G01X570779Y1046143D02*
X572617Y1047190D01*
G01X565228Y1049332D02*
X567066Y1050379D01*
G01X570779Y1052521D02*
X572617Y1053568D01*
G01X568929Y1055710D02*
X570767Y1056757D01*
G01X563378Y1052521D02*
X565215Y1053568D01*
G01X570779Y1058899D02*
X572617Y1059946D01*
G01X567078Y1058899D02*
X568916Y1059946D01*
G01X565228Y1055710D02*
X567066Y1056757D01*
G01X563378Y1046143D02*
X565215Y1047190D01*
G01X565228Y1062088D02*
X567066Y1063135D01*
G01X570779Y1065277D02*
X572617Y1066324D01*
G01X570779Y1071655D02*
X572617Y1072702D01*
G01X565228Y1068466D02*
X567066Y1069513D01*
G01X563378Y1071655D02*
X565215Y1072702D01*
G01X563378Y1065277D02*
X565215Y1066324D01*
G01X565228Y1074844D02*
X567066Y1075891D01*
G01X563378Y1078033D02*
X565215Y1079080D01*
G01X570779Y1078033D02*
X572617Y1079080D01*
G01X565228Y1087600D02*
X567066Y1088647D01*
G01X570779Y1084411D02*
X572617Y1085458D01*
G01X565228Y1081222D02*
X567066Y1082269D01*
G01X563378Y1084411D02*
X565215Y1085458D01*
G01X570779Y1090789D02*
X572617Y1091836D01*
G01X563378Y1090789D02*
X565215Y1091836D01*
G01X570779Y1103545D02*
X572617Y1104592D01*
G01X570779Y1097167D02*
X572617Y1098214D01*
G01X565228Y1100356D02*
X567066Y1101403D01*
G01X563378Y1097167D02*
X565215Y1098214D01*
G01X565228Y1093978D02*
X567066Y1095025D01*
G01X563378Y1103545D02*
X565215Y1104592D01*
G01X565228Y1106734D02*
X567066Y1107781D01*
G01X570779Y1109923D02*
X572617Y1110970D01*
G01X563378Y1109923D02*
X565215Y1110970D01*
G01X570779Y1116301D02*
X572617Y1117348D01*
G01X563378Y1116301D02*
X565215Y1117348D01*
G01X565228Y1119490D02*
X567066Y1120537D01*
G01X565228Y1113112D02*
X567066Y1114159D01*
G01X570779Y1122679D02*
X572617Y1123726D01*
G01X565228Y1125868D02*
X567066Y1126915D01*
G01X570779Y1129057D02*
X572617Y1130103D01*
G01X563378Y1129057D02*
X565215Y1130103D01*
G01X563378Y1122679D02*
X565215Y1123726D01*
G01X565228Y1132246D02*
X567066Y1133293D01*
G01X570779Y1135434D02*
X572617Y1136481D01*
G01X563378Y1148190D02*
X565215Y1149237D01*
G01X570779Y1148190D02*
X572617Y1149237D01*
G01X565228Y1145001D02*
X567066Y1146048D01*
G01X570779Y1141812D02*
X572617Y1142859D01*
G01X565228Y1138623D02*
X567066Y1139670D01*
G01X563378Y1135434D02*
X565215Y1136481D01*
G01X563378Y1141812D02*
X565215Y1142859D01*
G01X572629Y1157757D02*
X574467Y1158804D01*
G01X563378Y1154568D02*
X565215Y1155615D01*
G01X567078Y1154568D02*
X568916Y1155615D01*
G01X570779Y1154568D02*
X572617Y1155615D01*
G01X559677Y1154568D02*
X561515Y1155615D01*
G01X563378Y1160946D02*
X565215Y1161993D01*
G01X565228Y1151379D02*
X567066Y1152426D01*
G01X561527Y1157757D02*
X563365Y1158804D01*
G01X570767Y1165182D02*
X568929Y1164135D01*
G01X575149Y880671D02*
X576987Y879624D01*
G01X575149Y887049D02*
X576987Y886002D01*
G01X575149Y893427D02*
X576987Y892380D01*
G01X575149Y899805D02*
X576987Y898758D01*
G01X575149Y906182D02*
X577728D01*
G01X575149Y912560D02*
X577728D01*
G01X575149Y918938D02*
X577728D01*
G01X575149Y925316D02*
X577728D01*
G01X575149Y931694D02*
X577728D01*
G01X575149Y938072D02*
X577728D01*
G01X575149Y944450D02*
X577728D01*
G01X575149Y950828D02*
X577728D01*
G01X575149Y957206D02*
X577728D01*
G01X575149Y963584D02*
X577728D01*
G01X575149Y969962D02*
X577728D01*
G01X575149Y976340D02*
X577728D01*
G01X575149Y982718D02*
X577728D01*
G01X575149Y989096D02*
X577728D01*
G01X575149Y995474D02*
X577728D01*
G01X575149Y1008230D02*
X577728D01*
G01X575149Y1001852D02*
X577728D01*
G01X576330Y1030198D02*
X578909D01*
G01X576330Y1036576D02*
X578909D01*
G01X576330Y1042954D02*
X578909D01*
G01X576330Y1049332D02*
X578909D01*
G01X576330Y1055710D02*
X578909D01*
G01X576330Y1062088D02*
X578909D01*
G01X576330Y1074844D02*
X578909D01*
G01X576330Y1068466D02*
X578909D01*
G01X576330Y1087600D02*
X578909D01*
G01X576330Y1081222D02*
X578909D01*
G01X576330Y1093978D02*
X578909D01*
G01X576330Y1100356D02*
X578909D01*
G01X576330Y1106734D02*
X578909D01*
G01X576330Y1113112D02*
X578909D01*
G01X576330Y1119490D02*
X578909D01*
G01X576330Y1125868D02*
X578909D01*
G01X576330Y1132246D02*
X578909D01*
G01X576330Y1138623D02*
X578909D01*
G01X576330Y1145001D02*
X578909D01*
G01X576330Y1151379D02*
X578909D01*
G01X576330Y1157757D02*
X578168Y1158804D01*
G01X1288535Y874292D02*
X1286697Y873245D01*
G01X1288535Y880670D02*
X1286697Y879623D01*
G01X1281134Y880670D02*
X1279296Y879623D01*
G01X1286685Y896615D02*
X1284847Y895568D01*
G01X1286685Y883859D02*
X1284847Y882812D01*
G01X1288535Y887048D02*
X1286697Y886001D01*
G01X1282984Y883859D02*
X1281146Y882812D01*
G01X1281134Y887048D02*
X1279296Y886001D01*
G01X1286685Y890237D02*
X1284847Y889190D01*
G01X1281134Y893426D02*
X1279296Y892379D01*
G01X1286685Y902993D02*
X1284847Y901946D01*
G01X1281134Y899804D02*
X1279296Y898757D01*
G01X1286685Y909370D02*
X1284847Y908324D01*
G01X1281134Y906181D02*
X1278555D01*
G01X1281134Y912559D02*
X1278555D01*
G01X1286685Y915748D02*
X1284847Y914701D01*
G01X1281134Y918937D02*
X1278555D01*
G01X1286685Y922126D02*
X1284847Y921079D01*
G01X1281134Y925315D02*
X1278555D01*
G01X1286685Y928504D02*
X1284847Y927457D01*
G01X1286685Y934882D02*
X1284847Y933835D01*
G01X1281134Y931693D02*
X1278555D01*
G01X1281134Y938071D02*
X1278555D01*
G01X1286685Y941260D02*
X1284847Y940213D01*
G01X1286685Y947638D02*
X1284847Y946591D01*
G01X1281134Y950827D02*
X1278555D01*
G01X1286685Y954016D02*
X1284847Y952969D01*
G01X1281134Y944449D02*
X1278555D01*
G01X1286685Y960394D02*
X1284847Y959347D01*
G01X1281134Y957205D02*
X1278555D01*
G01X1286685Y966772D02*
X1284847Y965725D01*
G01X1281134Y963583D02*
X1278555D01*
G01X1281134Y969961D02*
X1278555D01*
G01X1286685Y973150D02*
X1284847Y972103D01*
G01X1281134Y976339D02*
X1278555D01*
G01X1286685Y979528D02*
X1284847Y978481D01*
G01X1281134Y982717D02*
X1278555D01*
G01X1286685Y985906D02*
X1284847Y984859D01*
G01X1290386Y985906D02*
X1288548Y984859D01*
G01X1281134Y995473D02*
X1278555D01*
G01X1286685Y992284D02*
X1284847Y991237D01*
G01X1288535Y989095D02*
X1286697Y988048D01*
G01X1281134Y989095D02*
X1278555D01*
G01X1286685Y998662D02*
X1284847Y997615D01*
G01X1286685Y1011418D02*
X1284847Y1010371D01*
G01X1286685Y1005040D02*
X1284847Y1003993D01*
G01X1281134Y1008229D02*
X1278555D01*
G01X1281134Y1001851D02*
X1278555D01*
G01X1282315Y1030197D02*
X1279736D01*
G01X1287866Y1027008D02*
X1286028Y1028055D01*
G01X1287866Y1033386D02*
X1286028Y1034433D01*
G01X1287866Y1039764D02*
X1286028Y1040811D01*
G01X1282315Y1042953D02*
X1279736D01*
G01X1282315Y1036575D02*
X1279736D01*
G01X1287866Y1046142D02*
X1286028Y1047189D01*
G01X1287866Y1052520D02*
X1286028Y1053567D01*
G01X1289716Y1055709D02*
X1287878Y1056756D01*
G01X1291567Y1058898D02*
X1289729Y1059945D01*
G01X1287866Y1058898D02*
X1286028Y1059945D01*
G01X1282315Y1055709D02*
X1279736D01*
G01X1282315Y1049331D02*
X1279736D01*
G01X1282315Y1062087D02*
X1279736D01*
G01X1282315Y1068465D02*
X1279736D01*
G01X1282315Y1074843D02*
X1279736D01*
G01X1287866Y1065276D02*
X1286028Y1066323D01*
G01X1287866Y1071654D02*
X1286028Y1072701D01*
G01X1287866Y1078032D02*
X1286028Y1079079D01*
G01X1282315Y1081221D02*
X1279736D01*
G01X1282315Y1087599D02*
X1279736D01*
G01X1287866Y1084410D02*
X1286028Y1085457D01*
G01X1282315Y1093977D02*
X1279736D01*
G01X1287866Y1090788D02*
X1286028Y1091835D01*
G01X1282315Y1100355D02*
X1279736D01*
G01X1287866Y1097166D02*
X1286028Y1098213D01*
G01X1287866Y1103544D02*
X1286028Y1104591D01*
G01X1282315Y1106733D02*
X1279736D01*
G01X1287866Y1109922D02*
X1286028Y1110969D01*
G01X1282315Y1113111D02*
X1279736D01*
G01X1282315Y1119489D02*
X1279736D01*
G01X1287866Y1116300D02*
X1286028Y1117347D01*
G01X1282315Y1125867D02*
X1279736D01*
G01X1287866Y1122678D02*
X1286028Y1123725D01*
G01X1287866Y1129056D02*
X1286028Y1130102D01*
G01X1282315Y1132245D02*
X1279736D01*
G01X1282315Y1138622D02*
X1279736D01*
G01X1287866Y1135433D02*
X1286028Y1136480D01*
G01X1287866Y1141811D02*
X1286028Y1142858D01*
G01X1282315Y1145000D02*
X1279736D01*
G01X1287866Y1148189D02*
X1286028Y1149236D01*
G01X1282315Y1151378D02*
X1279736D01*
G01X1282315Y1157756D02*
X1279736D01*
G01X1291567Y1154567D02*
X1289729Y1155614D01*
G01X1287866Y1154567D02*
X1286028Y1155614D01*
G01X1286016Y1157756D02*
X1284178Y1158803D01*
G01X1289716Y1164134D02*
X1287878Y1165181D01*
G01X1292236Y874292D02*
X1290398Y873245D01*
G01X1303338Y880670D02*
X1301500Y879623D01*
G01X1305189Y877481D02*
X1303351Y876434D01*
G01X1295937Y880670D02*
X1294099Y879623D01*
G01X1297787Y877481D02*
X1295949Y876434D01*
G01X1305189Y896615D02*
X1303351Y895568D01*
G01X1292236Y887048D02*
X1290398Y886001D01*
G01X1292236Y893426D02*
X1290398Y892379D01*
G01X1294086Y883859D02*
X1292249Y882812D01*
G01X1299638Y887048D02*
X1297800Y886001D01*
G01X1303338Y887048D02*
X1301500Y886001D01*
G01X1297787Y883859D02*
X1295949Y882812D01*
G01X1294086Y890237D02*
X1292249Y889190D01*
G01X1305189Y890237D02*
X1303351Y889190D01*
G01X1299638Y893426D02*
X1297800Y892379D01*
G01X1294086Y896615D02*
X1292249Y895568D01*
G01X1292236Y899804D02*
X1290398Y898757D01*
G01X1292236Y912559D02*
X1290398Y911512D01*
G01X1294086Y902993D02*
X1292249Y901946D01*
G01X1299638Y899804D02*
X1297800Y898757D01*
G01X1305189Y902993D02*
X1303351Y901946D01*
G01X1294086Y909370D02*
X1292249Y908324D01*
G01X1299638Y906181D02*
X1297800Y905134D01*
G01X1299638Y912559D02*
X1297800Y911512D01*
G01X1305189Y909370D02*
X1303351Y908324D01*
G01X1292236Y906181D02*
X1290398Y905134D01*
G01X1292236Y918937D02*
X1290398Y917890D01*
G01X1299638Y918937D02*
X1297800Y917890D01*
G01X1305189Y915748D02*
X1303351Y914701D01*
G01X1305189Y922126D02*
X1303351Y921079D01*
G01X1299638Y925315D02*
X1297800Y924268D01*
G01X1294086Y922126D02*
X1292249Y921079D01*
G01X1292236Y925315D02*
X1290398Y924268D01*
G01X1294086Y915748D02*
X1292249Y914701D01*
G01X1299638Y931693D02*
X1297800Y930646D01*
G01X1305189Y928504D02*
X1303351Y927457D01*
G01X1305189Y934882D02*
X1303351Y933835D01*
G01X1294086Y928504D02*
X1292249Y927457D01*
G01X1305189Y941260D02*
X1303351Y940213D01*
G01X1299638Y938071D02*
X1297800Y937024D01*
G01X1294086Y941260D02*
X1292249Y940213D01*
G01X1292236Y931693D02*
X1290398Y930646D01*
G01X1292236Y938071D02*
X1290398Y937024D01*
G01X1294086Y934882D02*
X1292249Y933835D01*
G01X1292236Y950827D02*
X1290398Y949780D01*
G01X1292236Y957205D02*
X1290398Y956158D01*
G01X1299638Y950827D02*
X1297800Y949780D01*
G01X1305189Y947638D02*
X1303351Y946591D01*
G01X1294086Y947638D02*
X1292249Y946591D01*
G01X1299638Y944449D02*
X1297800Y943402D01*
G01X1305189Y954016D02*
X1303351Y952969D01*
G01X1299638Y957205D02*
X1297800Y956158D01*
G01X1292236Y944449D02*
X1290398Y943402D01*
G01X1294086Y954016D02*
X1292249Y952969D01*
G01X1292236Y969961D02*
X1290398Y968914D01*
G01X1299638Y963583D02*
X1297800Y962536D01*
G01X1305189Y960394D02*
X1303351Y959347D01*
G01X1305189Y966772D02*
X1303351Y965725D01*
G01X1294086Y960394D02*
X1292249Y959347D01*
G01X1294086Y966772D02*
X1292249Y965725D01*
G01X1299638Y969961D02*
X1297800Y968914D01*
G01X1292236Y963583D02*
X1290398Y962536D01*
G01X1292236Y976339D02*
X1290398Y975292D01*
G01X1299638Y982717D02*
X1297800Y981670D01*
G01X1299638Y976339D02*
X1297800Y975292D01*
G01X1305189Y973150D02*
X1303351Y972103D01*
G01X1305189Y979528D02*
X1303351Y978481D01*
G01X1295937Y982717D02*
X1294099Y981670D01*
G01X1294086Y979528D02*
X1292249Y978481D01*
G01X1305189Y985906D02*
X1303351Y984859D01*
G01X1297787Y985906D02*
X1295949Y984859D01*
G01X1294086Y985906D02*
X1292249Y984859D01*
G01X1292236Y982717D02*
X1290398Y981670D01*
G01X1294086Y973150D02*
X1292249Y972103D01*
G01X1292236Y989095D02*
X1290398Y988048D01*
G01X1292236Y995473D02*
X1290398Y994426D01*
G01X1299638Y995473D02*
X1297800Y994426D01*
G01X1299638Y989095D02*
X1297800Y988048D01*
G01X1305189Y992284D02*
X1303351Y991237D01*
G01X1305189Y998662D02*
X1303351Y997615D01*
G01X1294086Y998662D02*
X1292249Y997615D01*
G01X1299638Y1001851D02*
X1297800Y1000804D01*
G01X1292236Y1001851D02*
X1290398Y1000804D01*
G01X1294086Y992284D02*
X1292249Y991237D01*
G01X1292236Y1008229D02*
X1290398Y1007182D01*
G01X1294086Y1011418D02*
X1292249Y1010371D01*
G01X1299638Y1008229D02*
X1297800Y1007182D01*
G01X1305189Y1011418D02*
X1303351Y1010371D01*
G01X1305189Y1005040D02*
X1303351Y1003993D01*
G01X1294086Y1005040D02*
X1292249Y1003993D01*
G01X1306370Y1027008D02*
X1304532Y1028055D01*
G01X1300819Y1030197D02*
X1298981Y1031244D01*
G01X1293417Y1030197D02*
X1291579Y1031244D01*
G01X1295268Y1027008D02*
X1293430Y1028055D01*
G01X1295268Y1033386D02*
X1293430Y1034433D01*
G01X1295268Y1039764D02*
X1293430Y1040811D01*
G01X1300819Y1042953D02*
X1298981Y1044000D01*
G01X1300819Y1036575D02*
X1298981Y1037622D01*
G01X1306370Y1033386D02*
X1304532Y1034433D01*
G01X1306370Y1039764D02*
X1304532Y1040811D01*
G01X1293417Y1042953D02*
X1291579Y1044000D01*
G01X1293417Y1036575D02*
X1291579Y1037622D01*
G01X1306370Y1046142D02*
X1304532Y1047189D01*
G01X1293417Y1049331D02*
X1291579Y1050378D01*
G01X1295268Y1052520D02*
X1293430Y1053567D01*
G01X1295268Y1058898D02*
X1293430Y1059945D01*
G01X1306370Y1052520D02*
X1304532Y1053567D01*
G01X1300819Y1049331D02*
X1298981Y1050378D01*
G01X1304520Y1055709D02*
X1302681Y1056756D01*
G01X1300819Y1055709D02*
X1298981Y1056756D01*
G01X1302669Y1058898D02*
X1300831Y1059945D01*
G01X1306370Y1058898D02*
X1304532Y1059945D01*
G01X1295268Y1046142D02*
X1293430Y1047189D01*
G01X1293417Y1055709D02*
X1291579Y1056756D01*
G01X1300819Y1062087D02*
X1298981Y1063134D01*
G01X1293417Y1062087D02*
X1291579Y1063134D01*
G01X1293417Y1068465D02*
X1291579Y1069512D01*
G01X1295268Y1071654D02*
X1293430Y1072701D01*
G01X1306370Y1071654D02*
X1304532Y1072701D01*
G01X1306370Y1065276D02*
X1304532Y1066323D01*
G01X1300819Y1068465D02*
X1298981Y1069512D01*
G01X1300819Y1074843D02*
X1298981Y1075890D01*
G01X1295268Y1065276D02*
X1293430Y1066323D01*
G01X1293417Y1074843D02*
X1291579Y1075890D01*
G01X1295268Y1078032D02*
X1293430Y1079079D01*
G01X1306370Y1078032D02*
X1304532Y1079079D01*
G01X1306370Y1084410D02*
X1304532Y1085457D01*
G01X1300819Y1087599D02*
X1298981Y1088646D01*
G01X1293417Y1081221D02*
X1291579Y1082268D01*
G01X1300819Y1081221D02*
X1298981Y1082268D01*
G01X1293417Y1087599D02*
X1291579Y1088646D01*
G01X1295268Y1084410D02*
X1293430Y1085457D01*
G01X1295268Y1090788D02*
X1293430Y1091835D01*
G01X1306370Y1090788D02*
X1304532Y1091835D01*
G01X1300819Y1093977D02*
X1298981Y1095024D01*
G01X1295268Y1097166D02*
X1293430Y1098213D01*
G01X1300819Y1100355D02*
X1298981Y1101402D01*
G01X1306370Y1097166D02*
X1304532Y1098213D01*
G01X1306370Y1103544D02*
X1304532Y1104591D01*
G01X1293417Y1100355D02*
X1291579Y1101402D01*
G01X1293417Y1093977D02*
X1291579Y1095024D01*
G01X1295268Y1103544D02*
X1293430Y1104591D01*
G01X1300819Y1106733D02*
X1298981Y1107780D01*
G01X1293417Y1106733D02*
X1291579Y1107780D01*
G01X1295268Y1109922D02*
X1293430Y1110969D01*
G01X1306370Y1109922D02*
X1304532Y1110969D01*
G01X1295268Y1116300D02*
X1293430Y1117347D01*
G01X1300819Y1113111D02*
X1298981Y1114158D01*
G01X1306370Y1116300D02*
X1304532Y1117347D01*
G01X1293417Y1119489D02*
X1291579Y1120536D01*
G01X1300819Y1119489D02*
X1298981Y1120536D01*
G01X1293417Y1113111D02*
X1291579Y1114158D01*
G01X1306370Y1122678D02*
X1304532Y1123725D01*
G01X1293417Y1125867D02*
X1291579Y1126914D01*
G01X1300819Y1125867D02*
X1298981Y1126914D01*
G01X1306370Y1129056D02*
X1304532Y1130102D01*
G01X1300819Y1132245D02*
X1298981Y1133292D01*
G01X1295268Y1129056D02*
X1293430Y1130102D01*
G01X1295268Y1122678D02*
X1293430Y1123725D01*
G01X1293417Y1132245D02*
X1291579Y1133292D01*
G01X1306370Y1135433D02*
X1304532Y1136480D01*
G01X1300819Y1138622D02*
X1298981Y1139669D01*
G01X1293417Y1138622D02*
X1291579Y1139669D01*
G01X1295268Y1135433D02*
X1293430Y1136480D01*
G01X1306370Y1141811D02*
X1304532Y1142858D01*
G01X1293417Y1145000D02*
X1291579Y1146047D01*
G01X1295268Y1148189D02*
X1293430Y1149236D01*
G01X1300819Y1145000D02*
X1298981Y1146047D01*
G01X1306370Y1148189D02*
X1304532Y1149236D01*
G01X1295268Y1141811D02*
X1293430Y1142858D01*
G01X1295268Y1154567D02*
X1293430Y1155614D01*
G01X1306370Y1154567D02*
X1304532Y1155614D01*
G01X1300819Y1151378D02*
X1298981Y1152425D01*
G01X1298968Y1154567D02*
X1297130Y1155614D01*
G01X1304520Y1157756D02*
X1302681Y1158803D01*
G01X1300819Y1157756D02*
X1298981Y1158803D01*
G01X1306370Y1160945D02*
X1304532Y1161992D01*
G01X1298968Y1160945D02*
X1297130Y1161992D01*
G01X1293417Y1151378D02*
X1291579Y1152425D01*
G01X1297118Y1157756D02*
X1295280Y1158803D01*
G01X1316291Y877481D02*
X1314453Y876434D01*
G01X1310740Y874292D02*
X1308902Y873245D01*
G01X1310740Y880670D02*
X1308902Y879623D01*
G01X1312590Y896615D02*
X1310752Y895568D01*
G01X1308890Y883859D02*
X1307052Y882812D01*
G01X1307039Y887048D02*
X1305201Y886001D01*
G01X1307039Y893426D02*
X1305201Y892379D01*
G01X1312590Y883859D02*
X1310752Y882812D01*
G01X1314441Y887048D02*
X1312603Y886001D01*
G01X1318142Y887048D02*
X1316304Y886001D01*
G01X1319992Y883859D02*
X1318154Y882812D01*
G01X1312590Y890237D02*
X1310752Y889190D01*
G01X1319992Y890237D02*
X1318154Y889190D01*
G01X1318142Y893426D02*
X1316304Y892379D01*
G01X1319992Y896615D02*
X1318154Y895568D01*
G01X1307039Y899804D02*
X1305201Y898757D01*
G01X1307039Y906181D02*
X1305201Y905134D01*
G01X1307039Y912559D02*
X1305201Y911512D01*
G01X1312590Y902993D02*
X1310752Y901946D01*
G01X1319992Y902993D02*
X1318154Y901946D01*
G01X1318142Y899804D02*
X1316304Y898757D01*
G01X1318142Y912559D02*
X1316304Y911512D01*
G01X1319992Y909370D02*
X1318154Y908324D01*
G01X1312590Y909370D02*
X1310752Y908323D01*
G01X1318142Y906181D02*
X1316304Y905134D01*
G01X1307039Y918937D02*
X1305201Y917890D01*
G01X1307039Y925315D02*
X1305201Y924268D01*
G01X1312590Y915748D02*
X1310752Y914701D01*
G01X1318142Y918937D02*
X1316304Y917890D01*
G01X1319992Y922126D02*
X1318154Y921079D01*
G01X1312590Y922126D02*
X1310752Y921079D01*
G01X1319992Y915748D02*
X1318154Y914701D01*
G01X1318142Y925315D02*
X1316304Y924268D01*
G01X1307039Y931693D02*
X1305201Y930646D01*
G01X1307039Y938071D02*
X1305201Y937024D01*
G01X1312590Y928504D02*
X1310752Y927457D01*
G01X1312590Y934882D02*
X1310752Y933835D01*
G01X1319992Y928504D02*
X1318154Y927457D01*
G01X1318142Y931693D02*
X1316304Y930646D01*
G01X1318142Y938071D02*
X1316304Y937024D01*
G01X1312590Y941260D02*
X1310752Y940213D01*
G01X1319992Y941260D02*
X1318154Y940213D01*
G01X1319992Y934882D02*
X1318154Y933835D01*
G01X1307039Y944449D02*
X1305201Y943402D01*
G01X1307039Y950827D02*
X1305201Y949780D01*
G01X1307039Y957205D02*
X1305201Y956158D01*
G01X1312590Y947638D02*
X1310752Y946591D01*
G01X1318142Y950827D02*
X1316304Y949780D01*
G01X1319992Y947638D02*
X1318154Y946591D01*
G01X1312590Y954016D02*
X1310752Y952969D01*
G01X1318142Y957205D02*
X1316304Y956158D01*
G01X1318142Y944449D02*
X1316304Y943402D01*
G01X1319992Y954016D02*
X1318154Y952969D01*
G01X1319992Y960394D02*
X1318154Y959347D01*
G01X1319992Y966772D02*
X1318154Y965725D01*
G01X1318142Y969961D02*
X1316304Y968914D01*
G01X1307039Y963583D02*
X1305201Y962536D01*
G01X1307039Y969961D02*
X1305201Y968914D01*
G01X1312590Y960394D02*
X1310752Y959347D01*
G01X1312590Y966772D02*
X1310752Y965725D01*
G01X1318142Y963583D02*
X1316304Y962536D01*
G01X1307039Y976339D02*
X1305201Y975292D01*
G01X1307039Y982717D02*
X1305201Y981670D01*
G01X1308890Y985906D02*
X1307052Y984859D01*
G01X1312590Y973150D02*
X1310752Y972103D01*
G01X1312590Y979528D02*
X1310752Y978481D01*
G01X1318142Y976339D02*
X1316304Y975292D01*
G01X1319992Y979528D02*
X1318154Y978481D01*
G01X1310740Y982717D02*
X1308902Y981670D01*
G01X1312590Y985906D02*
X1310752Y984859D01*
G01X1319992Y985906D02*
X1318154Y984859D01*
G01X1319992Y973150D02*
X1318154Y972103D01*
G01X1318142Y982717D02*
X1316304Y981670D01*
G01X1307039Y989095D02*
X1305201Y988048D01*
G01X1307039Y995473D02*
X1305201Y994426D01*
G01X1307039Y1001851D02*
X1305201Y1000804D01*
G01X1312590Y992284D02*
X1310752Y991237D01*
G01X1312590Y998662D02*
X1310752Y997615D01*
G01X1318142Y989095D02*
X1316304Y988048D01*
G01X1319992Y998662D02*
X1318154Y997615D01*
G01X1318142Y995473D02*
X1316304Y994426D01*
G01X1319992Y992284D02*
X1318154Y991237D01*
G01X1318142Y1001851D02*
X1316304Y1000804D01*
G01X1307039Y1008229D02*
X1305201Y1007182D01*
G01X1312590Y1005040D02*
X1310752Y1003993D01*
G01X1312590Y1011418D02*
X1310752Y1010371D01*
G01X1319992Y1011418D02*
X1318154Y1010371D01*
G01X1318142Y1008229D02*
X1316304Y1007182D01*
G01X1319992Y1005040D02*
X1318154Y1003993D01*
G01X1313771Y1027008D02*
X1311933Y1028055D01*
G01X1308220Y1030197D02*
X1306382Y1031244D01*
G01X1319323Y1030197D02*
X1317485Y1031244D01*
G01X1321173Y1027008D02*
X1319335Y1028055D01*
G01X1308220Y1042953D02*
X1306382Y1044000D01*
G01X1308220Y1036575D02*
X1306382Y1037622D01*
G01X1321173Y1033386D02*
X1319335Y1034433D01*
G01X1313771Y1039764D02*
X1311933Y1040811D01*
G01X1321173Y1039764D02*
X1319335Y1040811D01*
G01X1319323Y1042953D02*
X1317485Y1044000D01*
G01X1313771Y1033386D02*
X1311933Y1034433D01*
G01X1319323Y1036575D02*
X1317485Y1037622D01*
G01X1308220Y1049331D02*
X1306382Y1050378D01*
G01X1308220Y1055709D02*
X1306382Y1056756D01*
G01X1313771Y1046142D02*
X1311933Y1047189D01*
G01X1315622Y1055709D02*
X1313784Y1056756D01*
G01X1313771Y1058898D02*
X1311933Y1059945D01*
G01X1317472Y1058898D02*
X1315634Y1059945D01*
G01X1321173Y1058898D02*
X1319335Y1059945D01*
G01X1319323Y1049331D02*
X1317485Y1050378D01*
G01X1321173Y1052520D02*
X1319335Y1053567D01*
G01X1313771Y1052520D02*
X1311933Y1053567D01*
G01X1321173Y1046142D02*
X1319335Y1047189D01*
G01X1319323Y1055709D02*
X1317485Y1056756D01*
G01X1308220Y1062087D02*
X1306382Y1063134D01*
G01X1308220Y1068465D02*
X1306382Y1069512D01*
G01X1319323Y1062087D02*
X1317485Y1063134D01*
G01X1321173Y1071654D02*
X1319335Y1072701D01*
G01X1319323Y1068465D02*
X1317485Y1069512D01*
G01X1313771Y1065276D02*
X1311933Y1066323D01*
G01X1313771Y1071654D02*
X1311933Y1072701D01*
G01X1308220Y1074843D02*
X1306382Y1075890D01*
G01X1321173Y1065276D02*
X1319335Y1066323D01*
G01X1319323Y1074843D02*
X1317485Y1075890D01*
G01X1308220Y1087599D02*
X1306382Y1088646D01*
G01X1308220Y1081221D02*
X1306382Y1082268D01*
G01X1321173Y1078032D02*
X1319335Y1079079D01*
G01X1313771Y1078032D02*
X1311933Y1079079D01*
G01X1313771Y1084410D02*
X1311933Y1085457D01*
G01X1319323Y1087599D02*
X1317485Y1088646D01*
G01X1319323Y1081221D02*
X1317485Y1082268D01*
G01X1321173Y1084410D02*
X1319335Y1085457D01*
G01X1308220Y1093977D02*
X1306382Y1095024D01*
G01X1308220Y1100355D02*
X1306382Y1101402D01*
G01X1321173Y1090788D02*
X1319335Y1091835D01*
G01X1313771Y1090788D02*
X1311933Y1091835D01*
G01X1313771Y1097166D02*
X1311933Y1098213D01*
G01X1321173Y1097166D02*
X1319335Y1098213D01*
G01X1319323Y1100355D02*
X1317485Y1101402D01*
G01X1313771Y1103544D02*
X1311933Y1104591D01*
G01X1319323Y1093977D02*
X1317485Y1095024D01*
G01X1321173Y1103544D02*
X1319335Y1104591D01*
G01X1308220Y1106733D02*
X1306382Y1107780D01*
G01X1308220Y1113111D02*
X1306382Y1114158D01*
G01X1319323Y1106733D02*
X1317485Y1107780D01*
G01X1321173Y1109922D02*
X1319335Y1110969D01*
G01X1313771Y1109922D02*
X1311933Y1110969D01*
G01X1313771Y1116300D02*
X1311933Y1117347D01*
G01X1321173Y1116300D02*
X1319335Y1117347D01*
G01X1308220Y1119489D02*
X1306382Y1120536D01*
G01X1319323Y1119489D02*
X1317485Y1120536D01*
G01X1319323Y1113111D02*
X1317485Y1114158D01*
G01X1308220Y1125867D02*
X1306382Y1126914D01*
G01X1308220Y1132245D02*
X1306382Y1133292D01*
G01X1313771Y1122678D02*
X1311933Y1123725D01*
G01X1319323Y1125867D02*
X1317485Y1126914D01*
G01X1321173Y1129056D02*
X1319335Y1130102D01*
G01X1313771Y1129056D02*
X1311933Y1130103D01*
G01X1321173Y1122678D02*
X1319335Y1123725D01*
G01X1319323Y1132245D02*
X1317485Y1133292D01*
G01X1308220Y1138622D02*
X1306382Y1139669D01*
G01X1308220Y1145000D02*
X1306382Y1146047D01*
G01X1321173Y1135433D02*
X1319335Y1136480D01*
G01X1319323Y1138622D02*
X1317485Y1139669D01*
G01X1313771Y1135433D02*
X1311933Y1136480D01*
G01X1313771Y1141811D02*
X1311933Y1142858D01*
G01X1319323Y1145000D02*
X1317485Y1146047D01*
G01X1321173Y1148189D02*
X1319335Y1149236D01*
G01X1313771Y1148189D02*
X1311933Y1149236D01*
G01X1321173Y1141811D02*
X1319335Y1142858D01*
G01X1319323Y1157756D02*
X1317485Y1158803D01*
G01X1315622Y1157756D02*
X1313784Y1158803D01*
G01X1321173Y1160945D02*
X1319335Y1161992D01*
G01X1313771Y1160945D02*
X1311933Y1161992D01*
G01X1308220Y1164134D02*
X1306382Y1165181D01*
G01X1315622Y1164134D02*
X1313784Y1165181D01*
G01X1308220Y1151378D02*
X1306382Y1152425D01*
G01X1308220Y1157756D02*
X1306382Y1158803D01*
G01X1321173Y1154567D02*
X1319335Y1155614D01*
G01X1317472Y1154567D02*
X1315634Y1155614D01*
G01X1313771Y1154567D02*
X1311933Y1155614D01*
G01X1311921Y1157756D02*
X1310083Y1158803D01*
G01X1319323Y1151378D02*
X1317485Y1152425D01*
G01X1321842Y880670D02*
X1320004Y879623D01*
G01X1332945Y874292D02*
X1331107Y873245D01*
G01X1327394Y877481D02*
X1325556Y876434D01*
G01X1332945Y880670D02*
X1331107Y879623D01*
G01X1323693Y883859D02*
X1321855Y882812D01*
G01X1325543Y887048D02*
X1323705Y886001D01*
G01X1331094Y883859D02*
X1329256Y882812D01*
G01X1334795Y883859D02*
X1332957Y882812D01*
G01X1332945Y887048D02*
X1331107Y886001D01*
G01X1329244Y887048D02*
X1327406Y886001D01*
G01X1325543Y893426D02*
X1323705Y892379D01*
G01X1331094Y890237D02*
X1329256Y889190D01*
G01X1332945Y893426D02*
X1331107Y892379D01*
G01X1331094Y896615D02*
X1329256Y895568D01*
G01X1325543Y899804D02*
X1323705Y898757D01*
G01X1332945Y899804D02*
X1331107Y898757D01*
G01X1331094Y902993D02*
X1329256Y901946D01*
G01X1332945Y912559D02*
X1331107Y911512D01*
G01X1325543Y912559D02*
X1323705Y911512D01*
G01X1325543Y906181D02*
X1323705Y905134D01*
G01X1332945Y906181D02*
X1331107Y905134D01*
G01X1331094Y909370D02*
X1329256Y908323D01*
G01X1331094Y915748D02*
X1329256Y914701D01*
G01X1325543Y918937D02*
X1323705Y917890D01*
G01X1332945Y918937D02*
X1331107Y917890D01*
G01X1325543Y925315D02*
X1323705Y924268D01*
G01X1331094Y922126D02*
X1329256Y921079D01*
G01X1332945Y925315D02*
X1331107Y924268D01*
G01X1332945Y931693D02*
X1331107Y930646D01*
G01X1331094Y934882D02*
X1329256Y933835D01*
G01X1325543Y931693D02*
X1323705Y930646D01*
G01X1331094Y928504D02*
X1329256Y927457D01*
G01X1332945Y938071D02*
X1331107Y937024D01*
G01X1331094Y941260D02*
X1329256Y940213D01*
G01X1325543Y938071D02*
X1323705Y937024D01*
G01X1332945Y944449D02*
X1331107Y943402D01*
G01X1331094Y947638D02*
X1329256Y946591D01*
G01X1332945Y950827D02*
X1331107Y949780D01*
G01X1325543Y944449D02*
X1323705Y943402D01*
G01X1325543Y950827D02*
X1323705Y949780D01*
G01X1331094Y954016D02*
X1329256Y952969D01*
G01X1332945Y957205D02*
X1331107Y956158D01*
G01X1325543Y957205D02*
X1323705Y956158D01*
G01X1331094Y960394D02*
X1329256Y959347D01*
G01X1332945Y963583D02*
X1331107Y962536D01*
G01X1331094Y966772D02*
X1329256Y965725D01*
G01X1325543Y963583D02*
X1323705Y962536D01*
G01X1332945Y969961D02*
X1331107Y968914D01*
G01X1325543Y969961D02*
X1323705Y968914D01*
G01X1321842Y982717D02*
X1320004Y981670D01*
G01X1323693Y985906D02*
X1321855Y984859D01*
G01X1325543Y976339D02*
X1323705Y975292D01*
G01X1325543Y982717D02*
X1323705Y981670D01*
G01X1331094Y973150D02*
X1329256Y972103D01*
G01X1332945Y976339D02*
X1331107Y975292D01*
G01X1331094Y979528D02*
X1329256Y978481D01*
G01X1332945Y982717D02*
X1331107Y981670D01*
G01X1331094Y985906D02*
X1329256Y984859D01*
G01X1334795Y985906D02*
X1332957Y984859D01*
G01X1325543Y1001851D02*
X1323705Y1000804D01*
G01X1325543Y989095D02*
X1323705Y988048D01*
G01X1325543Y995473D02*
X1323705Y994426D01*
G01X1331094Y998662D02*
X1329256Y997615D01*
G01X1332945Y989095D02*
X1331107Y988048D01*
G01X1331094Y992284D02*
X1329256Y991237D01*
G01X1332945Y995473D02*
X1331107Y994426D01*
G01X1332945Y1001851D02*
X1331107Y1000804D01*
G01X1325543Y1008229D02*
X1323705Y1007182D01*
G01X1331094Y1005040D02*
X1329256Y1003993D01*
G01X1332945Y1008229D02*
X1331107Y1007182D01*
G01X1331094Y1011418D02*
X1329256Y1010371D01*
G01X1332275Y1027008D02*
X1330437Y1028055D01*
G01X1326724Y1030197D02*
X1324886Y1031244D01*
G01X1334126Y1030197D02*
X1332288Y1031244D01*
G01X1326724Y1042953D02*
X1324886Y1044000D01*
G01X1326724Y1036575D02*
X1324886Y1037622D01*
G01X1334126Y1042953D02*
X1332288Y1044000D01*
G01X1332275Y1033386D02*
X1330437Y1034433D01*
G01X1334126Y1036575D02*
X1332288Y1037622D01*
G01X1332275Y1039764D02*
X1330437Y1040811D01*
G01X1332275Y1046142D02*
X1330437Y1047189D01*
G01X1326724Y1049331D02*
X1324886Y1050378D01*
G01X1326724Y1055709D02*
X1324886Y1056756D01*
G01X1334126Y1049331D02*
X1332288Y1050378D01*
G01X1332275Y1052520D02*
X1330437Y1053567D01*
G01X1330425Y1055709D02*
X1328587Y1056756D01*
G01X1334126Y1055709D02*
X1332288Y1056756D01*
G01X1328575Y1058898D02*
X1326737Y1059945D01*
G01X1332275Y1058898D02*
X1330437Y1059945D01*
G01X1334126Y1062087D02*
X1332288Y1063134D01*
G01X1326724Y1062087D02*
X1324886Y1063134D01*
G01X1326724Y1068465D02*
X1324886Y1069512D01*
G01X1332275Y1065276D02*
X1330437Y1066323D01*
G01X1334126Y1068465D02*
X1332288Y1069512D01*
G01X1332275Y1071654D02*
X1330437Y1072701D01*
G01X1326724Y1074843D02*
X1324886Y1075890D01*
G01X1334126Y1074843D02*
X1332288Y1075890D01*
G01X1332275Y1078032D02*
X1330437Y1079079D01*
G01X1326724Y1087599D02*
X1324886Y1088646D01*
G01X1332275Y1084410D02*
X1330437Y1085457D01*
G01X1334126Y1087599D02*
X1332288Y1088646D01*
G01X1326724Y1081221D02*
X1324886Y1082268D01*
G01X1334126Y1081221D02*
X1332288Y1082268D01*
G01X1332275Y1090788D02*
X1330437Y1091835D01*
G01X1326724Y1093977D02*
X1324886Y1095024D01*
G01X1334126Y1093977D02*
X1332288Y1095024D01*
G01X1326724Y1100355D02*
X1324886Y1101402D01*
G01X1332275Y1097166D02*
X1330437Y1098213D01*
G01X1334126Y1100355D02*
X1332288Y1101402D01*
G01X1332275Y1103544D02*
X1330437Y1104591D01*
G01X1326724Y1106733D02*
X1324886Y1107780D01*
G01X1334126Y1106733D02*
X1332288Y1107780D01*
G01X1332275Y1109922D02*
X1330437Y1110969D01*
G01X1326724Y1113111D02*
X1324886Y1114158D01*
G01X1334126Y1113111D02*
X1332288Y1114158D01*
G01X1332275Y1116300D02*
X1330437Y1117347D01*
G01X1326724Y1119489D02*
X1324886Y1120536D01*
G01X1334126Y1119489D02*
X1332288Y1120536D01*
G01X1332275Y1122678D02*
X1330437Y1123725D01*
G01X1326724Y1125867D02*
X1324886Y1126914D01*
G01X1334126Y1125867D02*
X1332288Y1126914D01*
G01X1326724Y1132245D02*
X1324886Y1133292D01*
G01X1334126Y1132245D02*
X1332288Y1133292D01*
G01X1332275Y1129056D02*
X1330439Y1130101D01*
Y1130102D01*
G01X1326724Y1138622D02*
X1324886Y1139669D01*
G01X1332275Y1135433D02*
X1330437Y1136480D01*
G01X1334126Y1138622D02*
X1332288Y1139669D01*
G01X1332275Y1141811D02*
X1330437Y1142858D01*
G01X1334126Y1145000D02*
X1332288Y1146047D01*
G01X1332275Y1148189D02*
X1330437Y1149236D01*
G01X1326724Y1145000D02*
X1324886Y1146047D01*
G01X1334126Y1164134D02*
X1332288Y1165181D01*
G01X1324874Y1154567D02*
X1323036Y1155614D01*
G01X1324874Y1160945D02*
X1323036Y1161992D01*
G01X1334126Y1151378D02*
X1332288Y1152425D01*
G01X1332275Y1154567D02*
X1330437Y1155614D01*
G01X1326724Y1151378D02*
X1324886Y1152425D01*
G01X1334126Y1157756D02*
X1332288Y1158803D01*
G01X1330425Y1157756D02*
X1328587Y1158803D01*
G01X1326724Y1157756D02*
X1324886Y1158803D01*
G01X1332275Y1160945D02*
X1330437Y1161992D01*
G01X1326724Y1164134D02*
X1324886Y1165181D01*
G01X1323023Y1157756D02*
X1321185Y1158803D01*
G01X1338496Y877481D02*
X1336658Y876434D01*
G01X1347748Y880670D02*
X1345910Y879623D01*
G01X1345897Y877481D02*
X1344059Y876434D01*
G01X1349598Y877481D02*
X1347760Y876434D01*
G01X1340346Y887048D02*
X1338508Y886001D01*
G01X1338496Y883859D02*
X1336658Y882812D01*
G01X1338496Y890237D02*
X1336658Y889190D01*
G01X1338496Y896615D02*
X1336658Y895568D01*
G01X1344047Y887048D02*
X1342209Y886001D01*
G01X1345897Y883859D02*
X1344059Y882812D01*
G01X1345897Y890237D02*
X1344059Y889190D01*
G01X1344047Y893426D02*
X1342209Y892379D01*
G01X1349598Y883859D02*
X1347760Y882812D01*
G01X1345897Y896615D02*
X1344059Y895568D01*
G01X1338496Y902993D02*
X1336658Y901946D01*
G01X1338496Y909370D02*
X1336658Y908324D01*
G01X1344047Y899804D02*
X1342209Y898757D01*
G01X1345897Y902993D02*
X1344059Y901946D01*
G01X1344047Y912559D02*
X1342209Y911512D01*
G01X1345897Y909370D02*
X1344059Y908323D01*
G01X1344047Y906181D02*
X1342209Y905134D01*
G01X1338496Y915748D02*
X1336658Y914701D01*
G01X1338496Y922126D02*
X1336658Y921079D01*
G01X1344047Y918937D02*
X1342209Y917890D01*
G01X1345897Y922126D02*
X1344059Y921079D01*
G01X1344047Y925315D02*
X1342209Y924268D01*
G01X1345897Y915748D02*
X1344059Y914701D01*
G01X1338496Y934882D02*
X1336658Y933835D01*
G01X1338496Y928504D02*
X1336658Y927457D01*
G01X1338496Y941260D02*
X1336658Y940213D01*
G01X1345897Y928504D02*
X1344059Y927457D01*
G01X1344047Y931693D02*
X1342209Y930646D01*
G01X1345897Y941260D02*
X1344059Y940213D01*
G01X1344047Y938071D02*
X1342209Y937024D01*
G01X1345897Y934882D02*
X1344059Y933835D01*
G01X1345897Y947638D02*
X1344059Y946591D01*
G01X1344047Y950827D02*
X1342209Y949780D01*
G01X1344047Y957205D02*
X1342209Y956158D01*
G01X1338496Y947638D02*
X1336658Y946591D01*
G01X1338496Y954016D02*
X1336658Y952969D01*
G01X1345897Y954016D02*
X1344059Y952969D01*
G01X1344047Y944449D02*
X1342209Y943402D01*
G01X1338496Y966772D02*
X1336658Y965725D01*
G01X1338496Y960394D02*
X1336658Y959347D01*
G01X1345897Y960394D02*
X1344059Y959347D01*
G01X1345897Y966772D02*
X1344059Y965725D01*
G01X1344047Y969961D02*
X1342209Y968914D01*
G01X1344047Y963583D02*
X1342209Y962536D01*
G01X1336646Y982717D02*
X1334807Y981670D01*
G01X1338496Y973150D02*
X1336658Y972103D01*
G01X1338496Y979528D02*
X1336658Y978481D01*
G01X1338496Y985906D02*
X1336658Y984859D01*
G01X1344047Y976339D02*
X1342209Y975292D01*
G01X1345897Y979528D02*
X1344059Y978481D01*
G01X1347748Y982717D02*
X1345910Y981670D01*
G01X1345897Y985906D02*
X1344059Y984859D01*
G01X1349598Y985906D02*
X1347760Y984859D01*
G01X1345897Y973150D02*
X1344059Y972103D01*
G01X1344047Y982717D02*
X1342209Y981670D01*
G01X1338496Y998662D02*
X1336658Y997615D01*
G01X1338496Y992284D02*
X1336658Y991237D01*
G01X1344047Y995473D02*
X1342209Y994426D01*
G01X1345897Y998662D02*
X1344059Y997615D01*
G01X1344047Y989095D02*
X1342209Y988048D01*
G01X1344047Y1001851D02*
X1342209Y1000804D01*
G01X1345897Y992284D02*
X1344059Y991237D01*
G01X1338496Y1011418D02*
X1336658Y1010371D01*
G01X1345897Y1011418D02*
X1344059Y1010371D01*
G01X1338496Y1005040D02*
X1336658Y1003993D01*
G01X1345897Y1005040D02*
X1344059Y1003993D01*
G01X1344047Y1008229D02*
X1342209Y1007182D01*
G01X1339677Y1027008D02*
X1337839Y1028055D01*
G01X1345228Y1030197D02*
X1343390Y1031244D01*
G01X1347079Y1027008D02*
X1345241Y1028055D01*
G01X1339677Y1039764D02*
X1337839Y1040811D01*
G01X1339677Y1033386D02*
X1337839Y1034433D01*
G01X1345228Y1042953D02*
X1343390Y1044000D01*
G01X1347079Y1039764D02*
X1345241Y1040811D01*
G01X1347079Y1033386D02*
X1345241Y1034433D01*
G01X1345228Y1036575D02*
X1343390Y1037622D01*
G01X1339677Y1046142D02*
X1337839Y1047189D01*
G01X1339677Y1052520D02*
X1337839Y1053567D01*
G01X1339677Y1058898D02*
X1337839Y1059945D01*
G01X1341527Y1055709D02*
X1339689Y1056756D01*
G01X1345228Y1049331D02*
X1343390Y1050378D01*
G01X1347079Y1052520D02*
X1345241Y1053567D01*
G01X1343378Y1058898D02*
X1341540Y1059945D01*
G01X1347079Y1058898D02*
X1345241Y1059945D01*
G01X1347079Y1046142D02*
X1345241Y1047189D01*
G01X1345228Y1055709D02*
X1343390Y1056756D01*
G01X1339677Y1071654D02*
X1337839Y1072701D01*
G01X1339677Y1065276D02*
X1337839Y1066323D01*
G01X1345228Y1062087D02*
X1343390Y1063134D01*
G01X1345228Y1068465D02*
X1343390Y1069512D01*
G01X1347079Y1071654D02*
X1345241Y1072701D01*
G01X1347079Y1065276D02*
X1345241Y1066323D01*
G01X1345228Y1074843D02*
X1343390Y1075890D01*
G01X1339677Y1078032D02*
X1337839Y1079079D01*
G01X1339677Y1084410D02*
X1337839Y1085457D01*
G01X1347079Y1078032D02*
X1345241Y1079079D01*
G01X1345228Y1087599D02*
X1343390Y1088646D01*
G01X1345228Y1081221D02*
X1343390Y1082268D01*
G01X1347079Y1084410D02*
X1345241Y1085457D01*
G01X1339677Y1090788D02*
X1337839Y1091835D01*
G01X1339677Y1097166D02*
X1337839Y1098213D01*
G01X1339677Y1103544D02*
X1337839Y1104591D01*
G01X1347079Y1090788D02*
X1345241Y1091835D01*
G01X1345228Y1100355D02*
X1343390Y1101402D01*
G01X1347079Y1097166D02*
X1345241Y1098213D01*
G01X1347079Y1103544D02*
X1345241Y1104591D01*
G01X1345228Y1093977D02*
X1343390Y1095024D01*
G01X1339677Y1109922D02*
X1337839Y1110969D01*
G01X1339677Y1116300D02*
X1337839Y1117347D01*
G01X1345228Y1106733D02*
X1343390Y1107780D01*
G01X1347079Y1109922D02*
X1345241Y1110969D01*
G01X1347079Y1116300D02*
X1345241Y1117347D01*
G01X1345228Y1119489D02*
X1343390Y1120536D01*
G01X1345228Y1113111D02*
X1343390Y1114158D01*
G01X1339677Y1122678D02*
X1337839Y1123725D01*
G01X1339677Y1129056D02*
X1337839Y1130102D01*
G01X1345228Y1125867D02*
X1343390Y1126914D01*
G01X1347079Y1129056D02*
X1345241Y1130102D01*
G01X1347079Y1122678D02*
X1345241Y1123725D01*
G01X1345228Y1132245D02*
X1343390Y1133292D01*
G01X1339677Y1135433D02*
X1337839Y1136480D01*
G01X1339677Y1141811D02*
X1337839Y1142858D01*
G01X1339677Y1148189D02*
X1337839Y1149236D01*
G01X1345228Y1138622D02*
X1343390Y1139669D01*
G01X1347079Y1135433D02*
X1345241Y1136480D01*
G01X1347079Y1148189D02*
X1345241Y1149236D01*
G01X1345228Y1145000D02*
X1343390Y1146047D01*
G01X1347079Y1141811D02*
X1345241Y1142858D01*
G01X1339677Y1154567D02*
X1337839Y1155614D01*
G01X1337827Y1157756D02*
X1335989Y1158803D01*
G01X1339677Y1160945D02*
X1337839Y1161992D01*
G01X1343378Y1154567D02*
X1341540Y1155614D01*
G01X1341527Y1157756D02*
X1339689Y1158803D01*
G01X1350779Y1154567D02*
X1348941Y1155614D01*
G01X1347079Y1154567D02*
X1345241Y1155614D01*
G01X1341527Y1164134D02*
X1339689Y1165181D01*
G01X1347079Y1160945D02*
X1345241Y1161992D01*
G01X1350779Y1160945D02*
X1348941Y1161992D01*
G01X1348929Y1157756D02*
X1347091Y1158803D01*
G01X1345228Y1151378D02*
X1343390Y1152425D01*
G01X1351449Y880670D02*
X1349611Y879623D01*
G01X1353299Y877481D02*
X1351461Y876434D01*
G01X1355149Y880670D02*
X1353311Y879623D01*
G01X1366252Y880670D02*
X1364414Y879623D01*
G01X1362551Y874292D02*
X1360713Y873245D01*
G01X1364401Y877481D02*
X1362563Y876434D01*
G01X1360701Y877481D02*
X1358863Y876434D01*
G01X1357000Y877481D02*
X1355162Y876434D01*
G01X1351449Y887048D02*
X1349611Y886001D01*
G01X1351449Y893426D02*
X1349611Y892379D01*
G01X1355149Y887048D02*
X1353311Y886001D01*
G01X1364401Y883859D02*
X1362563Y882812D01*
G01X1360701Y883859D02*
X1358863Y882812D01*
G01X1366252Y887048D02*
X1364414Y886001D01*
G01X1362551Y887048D02*
X1360713Y886001D01*
G01X1357000Y883859D02*
X1355162Y882812D01*
G01X1358850Y893426D02*
X1357012Y892379D01*
G01X1357000Y896615D02*
X1355162Y895568D01*
G01X1364401Y890237D02*
X1362563Y889190D01*
G01X1360701Y890237D02*
X1358863Y889190D01*
G01X1353299Y883859D02*
X1351461Y882812D01*
G01X1358850Y887048D02*
X1357012Y886001D01*
G01X1364401Y896615D02*
X1362563Y895568D01*
G01X1360701Y896615D02*
X1358863Y895568D01*
G01X1357000Y890237D02*
X1355162Y889190D01*
G01X1351449Y899804D02*
X1349611Y898757D01*
G01X1351449Y906181D02*
X1349611Y905134D01*
G01X1351449Y912559D02*
X1349611Y911512D01*
G01X1358850Y899804D02*
X1357012Y898757D01*
G01X1364401Y902993D02*
X1362563Y901946D01*
G01X1360701Y902993D02*
X1358863Y901946D01*
G01X1358850Y906181D02*
X1357012Y905134D01*
G01X1358850Y912559D02*
X1357012Y911512D01*
G01X1357000Y909370D02*
X1355162Y908324D01*
G01X1364401Y909370D02*
X1362563Y908324D01*
G01X1360701Y909370D02*
X1358863Y908324D01*
G01X1357000Y902993D02*
X1355162Y901946D01*
G01X1351449Y918937D02*
X1349611Y917890D01*
G01X1351449Y925315D02*
X1349611Y924268D01*
G01X1360701Y915748D02*
X1358863Y914701D01*
G01X1364401Y915748D02*
X1362563Y914701D01*
G01X1358850Y918937D02*
X1357012Y917890D01*
G01X1357000Y922126D02*
X1355162Y921079D01*
G01X1358850Y925315D02*
X1357012Y924268D01*
G01X1360701Y922126D02*
X1358863Y921079D01*
G01X1364401Y922126D02*
X1362563Y921079D01*
G01X1357000Y915748D02*
X1355162Y914701D01*
G01X1351449Y931693D02*
X1349611Y930646D01*
G01X1351449Y938071D02*
X1349611Y937024D01*
G01X1364401Y934882D02*
X1362563Y933835D01*
G01X1360701Y934882D02*
X1358863Y933835D01*
G01X1357000Y934882D02*
X1355162Y933835D01*
G01X1364401Y928504D02*
X1362563Y927457D01*
G01X1360701Y928504D02*
X1358863Y927457D01*
G01X1358850Y931693D02*
X1357012Y930646D01*
G01X1357000Y941260D02*
X1355162Y940213D01*
G01X1364401Y941260D02*
X1362563Y940213D01*
G01X1360701Y941260D02*
X1358863Y940213D01*
G01X1357000Y928504D02*
X1355162Y927457D01*
G01X1358850Y938071D02*
X1357012Y937024D01*
G01X1351449Y944449D02*
X1349611Y943402D01*
G01X1351449Y950827D02*
X1349611Y949780D01*
G01X1351449Y957205D02*
X1349611Y956158D01*
G01X1358850Y944449D02*
X1357012Y943402D01*
G01X1360701Y947638D02*
X1358863Y946591D01*
G01X1364401Y947638D02*
X1362563Y946591D01*
G01X1358850Y950827D02*
X1357012Y949780D01*
G01X1358850Y957205D02*
X1357012Y956158D01*
G01X1357000Y954016D02*
X1355162Y952969D01*
G01X1364401Y954016D02*
X1362563Y952969D01*
G01X1360701Y954016D02*
X1358863Y952969D01*
G01X1357000Y947638D02*
X1355162Y946591D01*
G01X1351449Y963583D02*
X1349611Y962536D01*
G01X1351449Y969961D02*
X1349611Y968914D01*
G01X1360701Y960394D02*
X1358863Y959347D01*
G01X1364401Y960394D02*
X1362563Y959347D01*
G01X1358850Y963583D02*
X1357012Y962536D01*
G01X1357000Y966772D02*
X1355162Y965725D01*
G01X1358850Y969961D02*
X1357012Y968914D01*
G01X1364401Y966772D02*
X1362563Y965725D01*
G01X1360701Y966772D02*
X1358863Y965725D01*
G01X1357000Y960394D02*
X1355162Y959347D01*
G01X1351449Y976339D02*
X1349611Y975292D01*
G01X1351449Y982717D02*
X1349611Y981670D01*
G01X1360701Y973150D02*
X1358863Y972103D01*
G01X1364401Y973150D02*
X1362563Y972103D01*
G01X1358850Y976339D02*
X1357012Y975292D01*
G01X1362551Y982717D02*
X1360713Y981670D01*
G01X1357000Y979528D02*
X1355162Y978481D01*
G01X1364401Y985906D02*
X1362563Y984859D01*
G01X1357000Y985906D02*
X1355162Y984859D01*
G01X1358850Y982717D02*
X1357012Y981670D01*
G01X1366252Y982717D02*
X1364414Y981670D01*
G01X1360701Y985906D02*
X1358863Y984859D01*
G01X1364401Y979528D02*
X1362563Y978481D01*
G01X1360701Y979528D02*
X1358863Y978481D01*
G01X1357000Y973150D02*
X1355162Y972103D01*
G01X1351449Y989095D02*
X1349611Y988048D01*
G01X1351449Y995473D02*
X1349611Y994426D01*
G01X1351449Y1001851D02*
X1349611Y1000804D01*
G01X1357000Y992284D02*
X1355162Y991237D01*
G01X1357000Y998662D02*
X1355162Y997615D01*
G01X1364401Y992284D02*
X1362563Y991237D01*
G01X1364401Y998662D02*
X1362563Y997615D01*
G01X1362551Y995473D02*
X1360713Y994426D01*
G01X1362551Y989095D02*
X1360713Y988048D01*
G01X1362551Y1001851D02*
X1360713Y1000804D01*
G01X1358850Y989095D02*
X1357012Y988048D01*
G01X1360701Y998662D02*
X1358863Y997615D01*
G01X1358850Y995473D02*
X1357012Y994426D01*
G01X1360701Y992284D02*
X1358863Y991237D01*
G01X1366252Y989095D02*
X1364414Y988048D01*
G01X1366252Y995473D02*
X1364414Y994426D01*
G01X1358850Y1001851D02*
X1357012Y1000804D01*
G01X1351449Y1008229D02*
X1349611Y1007182D01*
G01X1360701Y1011418D02*
X1358863Y1010371D01*
G01X1362551Y1008229D02*
X1360713Y1007182D01*
G01X1364401Y1005040D02*
X1362563Y1003993D01*
G01X1357000Y1005040D02*
X1355162Y1003993D01*
G01X1366252Y1001851D02*
X1364414Y1000804D01*
G01X1358850Y1008229D02*
X1357012Y1007182D01*
G01X1360701Y1005040D02*
X1358863Y1003993D01*
G01X1366252Y1008229D02*
X1364414Y1007182D01*
G01X1364401Y1011418D02*
X1362563Y1010371D01*
G01X1357000Y1011418D02*
X1355162Y1010371D01*
G01X1358181Y1027008D02*
X1356343Y1028055D01*
G01X1365583Y1027008D02*
X1363745Y1028055D01*
G01X1352630Y1030197D02*
X1350792Y1031244D01*
G01X1363732Y1030197D02*
X1361894Y1031244D01*
G01X1361882Y1027008D02*
X1360044Y1028055D01*
G01X1360031Y1030197D02*
X1358193Y1031244D01*
G01X1352630Y1042953D02*
X1350792Y1044000D01*
G01X1352630Y1036575D02*
X1350792Y1037622D01*
G01X1358181Y1033386D02*
X1356343Y1034433D01*
G01X1358181Y1039764D02*
X1356343Y1040811D01*
G01X1365583Y1033386D02*
X1363745Y1034433D01*
G01X1365583Y1039764D02*
X1363745Y1040811D01*
G01X1363732Y1042953D02*
X1361894Y1044000D01*
G01X1363732Y1036575D02*
X1361894Y1037622D01*
G01X1360031Y1042953D02*
X1358193Y1044000D01*
G01X1360031Y1036575D02*
X1358193Y1037622D01*
G01X1361882Y1033386D02*
X1360044Y1034433D01*
G01X1361882Y1039764D02*
X1360044Y1040811D01*
G01X1356331Y1055709D02*
X1354493Y1056756D01*
G01X1352630Y1055709D02*
X1350792Y1056756D01*
G01X1352630Y1049331D02*
X1350792Y1050378D01*
G01X1354480Y1058898D02*
X1352642Y1059945D01*
G01X1358181Y1046142D02*
X1356343Y1047189D01*
G01X1365583Y1046142D02*
X1363745Y1047189D01*
G01X1358181Y1052520D02*
X1356343Y1053567D01*
G01X1363732Y1049331D02*
X1361894Y1050378D01*
G01X1358181Y1058898D02*
X1356343Y1059945D01*
G01X1365583Y1052520D02*
X1363745Y1053567D01*
G01X1361882Y1058898D02*
X1360044Y1059945D01*
G01X1365583Y1058898D02*
X1363745Y1059945D01*
G01X1360031Y1049331D02*
X1358193Y1050378D01*
G01X1361882Y1046142D02*
X1360044Y1047189D01*
G01X1352630Y1062087D02*
X1350792Y1063134D01*
G01X1352630Y1068465D02*
X1350792Y1069512D01*
G01X1360031Y1062087D02*
X1358193Y1063134D01*
G01X1358181Y1071654D02*
X1356343Y1072701D01*
G01X1365583Y1065276D02*
X1363745Y1066323D01*
G01X1360031Y1068465D02*
X1358193Y1069512D01*
G01X1361882Y1065276D02*
X1360044Y1066323D01*
G01X1352630Y1074843D02*
X1350792Y1075890D01*
G01X1360031Y1074843D02*
X1358193Y1075890D01*
G01X1361882Y1071654D02*
X1360044Y1072701D01*
G01X1365583Y1071654D02*
X1363745Y1072701D01*
G01X1358181Y1065276D02*
X1356343Y1066323D01*
G01X1352630Y1081221D02*
X1350792Y1082268D01*
G01X1352630Y1087599D02*
X1350792Y1088646D01*
G01X1365583Y1078032D02*
X1363745Y1079079D01*
G01X1361882Y1078032D02*
X1360044Y1079079D01*
G01X1358181Y1084410D02*
X1356343Y1085457D01*
G01X1360031Y1087599D02*
X1358193Y1088646D01*
G01X1360031Y1081221D02*
X1358193Y1082268D01*
G01X1361882Y1084410D02*
X1360044Y1085457D01*
G01X1365583Y1084410D02*
X1363745Y1085457D01*
G01X1358181Y1078032D02*
X1356343Y1079079D01*
G01X1352630Y1093977D02*
X1350792Y1095024D01*
G01X1352630Y1100355D02*
X1350792Y1101402D01*
G01X1358181Y1103544D02*
X1356343Y1104591D01*
G01X1365583Y1090788D02*
X1363745Y1091835D01*
G01X1361882Y1090788D02*
X1360044Y1091835D01*
G01X1360031Y1093977D02*
X1358193Y1095024D01*
G01X1358181Y1097166D02*
X1356343Y1098213D01*
G01X1365583Y1103544D02*
X1363745Y1104591D01*
G01X1361882Y1103544D02*
X1360044Y1104591D01*
G01X1361882Y1097166D02*
X1360044Y1098213D01*
G01X1365583Y1097166D02*
X1363745Y1098213D01*
G01X1358181Y1090788D02*
X1356343Y1091835D01*
G01X1360031Y1100355D02*
X1358193Y1101402D01*
G01X1352630Y1106733D02*
X1350792Y1107780D01*
G01X1352630Y1113111D02*
X1350792Y1114158D01*
G01X1360031Y1106733D02*
X1358193Y1107780D01*
G01X1361882Y1109922D02*
X1360044Y1110969D01*
G01X1365583Y1109922D02*
X1363745Y1110969D01*
G01X1358181Y1116300D02*
X1356343Y1117347D01*
G01X1360031Y1113111D02*
X1358193Y1114158D01*
G01X1352630Y1119489D02*
X1350792Y1120536D01*
G01X1360031Y1119489D02*
X1358193Y1120536D01*
G01X1361882Y1116300D02*
X1360044Y1117347D01*
G01X1365583Y1116300D02*
X1363745Y1117347D01*
G01X1358181Y1109922D02*
X1356343Y1110969D01*
G01X1352630Y1125867D02*
X1350792Y1126914D01*
G01X1352630Y1132245D02*
X1350792Y1133292D01*
G01X1360031Y1125867D02*
X1358193Y1126914D01*
G01X1365583Y1122678D02*
X1363745Y1123725D01*
G01X1361882Y1122678D02*
X1360044Y1123725D01*
G01X1358181Y1129056D02*
X1356343Y1130102D01*
G01X1360031Y1132245D02*
X1358193Y1133292D01*
G01X1361882Y1129056D02*
X1360044Y1130102D01*
G01X1365583Y1129056D02*
X1363745Y1130102D01*
G01X1358181Y1122678D02*
X1356343Y1123725D01*
G01X1352630Y1138622D02*
X1350792Y1139669D01*
G01X1352630Y1145000D02*
X1350792Y1146047D01*
G01X1360031Y1138622D02*
X1358193Y1139669D01*
G01X1365583Y1135433D02*
X1363745Y1136480D01*
G01X1361882Y1135433D02*
X1360044Y1136480D01*
G01X1358181Y1141811D02*
X1356343Y1142858D01*
G01X1365583Y1148189D02*
X1363745Y1149236D01*
G01X1361882Y1148189D02*
X1360044Y1149236D01*
G01X1360031Y1145000D02*
X1358193Y1146047D01*
G01X1365583Y1141811D02*
X1363745Y1142858D01*
G01X1361882Y1141811D02*
X1360044Y1142858D01*
G01X1358181Y1148189D02*
X1356343Y1149236D01*
G01X1358181Y1135433D02*
X1356343Y1136480D01*
G01X1356331Y1157756D02*
X1354493Y1158803D01*
G01X1352630Y1151378D02*
X1350792Y1152425D01*
G01X1352630Y1157756D02*
X1350792Y1158803D01*
G01X1354480Y1160945D02*
X1352642Y1161992D01*
G01X1358181Y1154567D02*
X1356343Y1155614D01*
G01X1365583Y1154567D02*
X1363745Y1155614D01*
G01X1361882Y1154567D02*
X1360044Y1155614D01*
G01X1365583Y1160945D02*
X1363745Y1161992D01*
G01X1360031Y1151378D02*
X1358193Y1152425D01*
G01X1361882Y1160945D02*
X1360044Y1161992D01*
G01X1358181Y1160945D02*
X1356343Y1161992D01*
G01X1375504Y877481D02*
X1373666Y876434D01*
G01X1377354Y874292D02*
X1375516Y873245D01*
G01X1377354Y880670D02*
X1375516Y879623D01*
G01X1371803Y877481D02*
X1369965Y876434D01*
G01X1368102Y877481D02*
X1366264Y876434D01*
G01X1379205Y877481D02*
X1377367Y876434D01*
G01X1371803Y883859D02*
X1369965Y882812D01*
G01X1368102Y883859D02*
X1366264Y882812D01*
G01X1371803Y890237D02*
X1369965Y889190D01*
G01X1369953Y893426D02*
X1368115Y892379D01*
G01X1368102Y896615D02*
X1366264Y895568D01*
G01X1375504Y883859D02*
X1373666Y882812D01*
G01X1379205Y883859D02*
X1377367Y882812D01*
G01X1381055Y893426D02*
X1379217Y892379D01*
G01X1379205Y896615D02*
X1377367Y895568D01*
G01X1375504Y890237D02*
X1373666Y889190D01*
G01X1369953Y887048D02*
X1368115Y886001D01*
G01X1371803Y896615D02*
X1369965Y895568D01*
G01X1375504Y896615D02*
X1373666Y895568D01*
G01X1368102Y890237D02*
X1366264Y889190D01*
G01X1379205Y890237D02*
X1377366Y889190D01*
G01X1381055Y887048D02*
X1379216Y886001D01*
G01X1369953Y899804D02*
X1368115Y898757D01*
G01X1371803Y902993D02*
X1369965Y901946D01*
G01X1368102Y902993D02*
X1366264Y901946D01*
G01X1369953Y906181D02*
X1368115Y905134D01*
G01X1369953Y912559D02*
X1368115Y911512D01*
G01X1368102Y909370D02*
X1366264Y908324D01*
G01X1381055Y899804D02*
X1379217Y898757D01*
G01X1379205Y902993D02*
X1377367Y901946D01*
G01X1375504Y902993D02*
X1373666Y901946D01*
G01X1381055Y906181D02*
X1379217Y905134D01*
G01X1379205Y909370D02*
X1377367Y908324D01*
G01X1371803Y909370D02*
X1369965Y908324D01*
G01X1375504Y909370D02*
X1373666Y908324D01*
G01X1381055Y912559D02*
X1379217Y911512D01*
G01X1371803Y915748D02*
X1369965Y914701D01*
G01X1369953Y918937D02*
X1368115Y917890D01*
G01X1368102Y915748D02*
X1366264Y914701D01*
G01X1369953Y925315D02*
X1368115Y924268D01*
G01X1368102Y922126D02*
X1366264Y921079D01*
G01X1379205Y915748D02*
X1377367Y914701D01*
G01X1375504Y915748D02*
X1373666Y914701D01*
G01X1381055Y918937D02*
X1379217Y917890D01*
G01X1379205Y922126D02*
X1377367Y921079D01*
G01X1381055Y925315D02*
X1379217Y924268D01*
G01X1371803Y922126D02*
X1369965Y921079D01*
G01X1375504Y922126D02*
X1373666Y921079D01*
G01X1368102Y934882D02*
X1366264Y933835D01*
G01X1371803Y928504D02*
X1369965Y927457D01*
G01X1369953Y931693D02*
X1368115Y930646D01*
G01X1371803Y934882D02*
X1369965Y933835D01*
G01X1368102Y928504D02*
X1366264Y927457D01*
G01X1368102Y941260D02*
X1366264Y940213D01*
G01X1379205Y928504D02*
X1377367Y927457D01*
G01X1375504Y928504D02*
X1373666Y927457D01*
G01X1381055Y931693D02*
X1379217Y930646D01*
G01X1379205Y934882D02*
X1377367Y933835D01*
G01X1375504Y934882D02*
X1373666Y933835D01*
G01X1379205Y941260D02*
X1377367Y940213D01*
G01X1371803Y941260D02*
X1369965Y940213D01*
G01X1375504Y941260D02*
X1373666Y940213D01*
G01X1369953Y944449D02*
X1368115Y943402D01*
G01X1371803Y947638D02*
X1369965Y946591D01*
G01X1369953Y950827D02*
X1368115Y949780D01*
G01X1368102Y947638D02*
X1366264Y946591D01*
G01X1369953Y957205D02*
X1368115Y956158D01*
G01X1368102Y954016D02*
X1366264Y952969D01*
G01X1381055Y944449D02*
X1379217Y943402D01*
G01X1375504Y947638D02*
X1373666Y946591D01*
G01X1379205Y947638D02*
X1377367Y946591D01*
G01X1381055Y950827D02*
X1379217Y949780D01*
G01X1379205Y954016D02*
X1377367Y952969D01*
G01X1371803Y954016D02*
X1369965Y952969D01*
G01X1375504Y954016D02*
X1373666Y952969D01*
G01X1381055Y957205D02*
X1379217Y956158D01*
G01X1368102Y960394D02*
X1366264Y959347D01*
G01X1371803Y960394D02*
X1369965Y959347D01*
G01X1369953Y963583D02*
X1368115Y962536D01*
G01X1368102Y966772D02*
X1366264Y965725D01*
G01X1369953Y969961D02*
X1368115Y968914D01*
G01X1375504Y960394D02*
X1373666Y959347D01*
G01X1379205Y966772D02*
X1377367Y965725D01*
G01X1379205Y960394D02*
X1377367Y959347D01*
G01X1381055Y963583D02*
X1379217Y962536D01*
G01X1381055Y969961D02*
X1379217Y968914D01*
G01X1371803Y966772D02*
X1369965Y965725D01*
G01X1375504Y966772D02*
X1373666Y965725D01*
G01X1371803Y973150D02*
X1369965Y972103D01*
G01X1369953Y976339D02*
X1368115Y975292D01*
G01X1369953Y982717D02*
X1368115Y981670D01*
G01X1368102Y973150D02*
X1366264Y972103D01*
G01X1368102Y979528D02*
X1366264Y978481D01*
G01X1371803Y985906D02*
X1369965Y984859D01*
G01X1375504Y973150D02*
X1373666Y972103D01*
G01X1379205Y973150D02*
X1377367Y972103D01*
G01X1381055Y976339D02*
X1379217Y975292D01*
G01X1377354Y982717D02*
X1375516Y981670D01*
G01X1379205Y979528D02*
X1377367Y978481D01*
G01X1379205Y985906D02*
X1377367Y984859D01*
G01X1368102Y985906D02*
X1366264Y984859D01*
G01X1371803Y979528D02*
X1369965Y978481D01*
G01X1375504Y979528D02*
X1373666Y978481D01*
G01X1373653Y982717D02*
X1371815Y981670D01*
G01X1381055Y982717D02*
X1379217Y981670D01*
G01X1375504Y985906D02*
X1373666Y984859D01*
G01X1371803Y992284D02*
X1369965Y991237D01*
G01X1371803Y998662D02*
X1369965Y997615D01*
G01X1369953Y995473D02*
X1368115Y994426D01*
G01X1369953Y989095D02*
X1368115Y988048D01*
G01X1369953Y1001851D02*
X1368115Y1000804D01*
G01X1377354Y995473D02*
X1375516Y994426D01*
G01X1379205Y992284D02*
X1377367Y991237D01*
G01X1379205Y998662D02*
X1377367Y997615D01*
G01X1377354Y989095D02*
X1375516Y988048D01*
G01X1377354Y1001851D02*
X1375516Y1000804D01*
G01X1375504Y992284D02*
X1373666Y991237D01*
G01X1373653Y989095D02*
X1371815Y988048D01*
G01X1373653Y995473D02*
X1371815Y994426D01*
G01X1373653Y1001851D02*
X1371815Y1000804D01*
G01X1368102Y998662D02*
X1366264Y997615D01*
G01X1368102Y992284D02*
X1366264Y991237D01*
G01X1381055Y989095D02*
X1379217Y988048D01*
G01X1381055Y995473D02*
X1379217Y994426D01*
G01X1375504Y998662D02*
X1373666Y997615D01*
G01X1371803Y1005040D02*
X1369965Y1003993D01*
G01X1369953Y1008229D02*
X1368115Y1007182D01*
G01X1368102Y1011418D02*
X1366264Y1010371D01*
G01X1375504Y1011418D02*
X1373666Y1010371D01*
G01X1377354Y1008229D02*
X1375516Y1007182D01*
G01X1373653Y1008229D02*
X1371815Y1007182D01*
G01X1379205Y1005040D02*
X1377367Y1003993D01*
G01X1368102Y1005040D02*
X1366264Y1003993D01*
G01X1381055Y1001851D02*
X1379217Y1000804D01*
G01X1381055Y1008229D02*
X1379217Y1007182D01*
G01X1379205Y1011418D02*
X1377367Y1010371D01*
G01X1375504Y1005040D02*
X1373666Y1003993D01*
G01X1371803Y1011418D02*
X1369965Y1010371D01*
G01X1372984Y1027008D02*
X1371146Y1028055D01*
G01X1376685Y1027008D02*
X1374847Y1028055D01*
G01X1371134Y1030197D02*
X1369296Y1031244D01*
G01X1378535Y1030197D02*
X1376697Y1031244D01*
G01X1380386Y1027008D02*
X1378548Y1028055D01*
G01X1369283Y1027008D02*
X1367445Y1028055D01*
G01X1374835Y1030197D02*
X1372997Y1031244D01*
G01X1367433Y1030197D02*
X1365595Y1031244D01*
G01X1371134Y1042953D02*
X1369296Y1044000D01*
G01X1371134Y1036575D02*
X1369296Y1037622D01*
G01X1372984Y1033386D02*
X1371146Y1034433D01*
G01X1378535Y1036575D02*
X1376697Y1037622D01*
G01X1380386Y1039764D02*
X1378548Y1040811D01*
G01X1372984Y1039764D02*
X1371146Y1040811D01*
G01X1376685Y1033386D02*
X1374847Y1034433D01*
G01X1378535Y1042953D02*
X1376697Y1044000D01*
G01X1376685Y1039764D02*
X1374847Y1040811D01*
G01X1380386Y1033386D02*
X1378548Y1034433D01*
G01X1367433Y1042953D02*
X1365595Y1044000D01*
G01X1367433Y1036575D02*
X1365595Y1037622D01*
G01X1369283Y1033386D02*
X1367445Y1034433D01*
G01X1369283Y1039764D02*
X1367445Y1040811D01*
G01X1374835Y1042953D02*
X1372997Y1044000D01*
G01X1374835Y1036575D02*
X1372997Y1037622D01*
G01X1380386Y1052520D02*
X1378548Y1053567D01*
G01X1378535Y1049331D02*
X1376697Y1050378D01*
G01X1369283Y1058898D02*
X1367445Y1059945D01*
G01X1371134Y1055709D02*
X1369296Y1056756D01*
G01X1371134Y1049331D02*
X1369296Y1050378D01*
G01X1372984Y1046142D02*
X1371146Y1047189D01*
G01X1380386Y1046142D02*
X1378548Y1047189D01*
G01X1378535Y1055709D02*
X1376697Y1056756D01*
G01X1372984Y1052520D02*
X1371146Y1053567D01*
G01X1380386Y1058898D02*
X1378548Y1059945D01*
G01X1376685Y1046142D02*
X1374847Y1047189D01*
G01X1367433Y1055709D02*
X1365595Y1056756D01*
G01X1376685Y1058898D02*
X1374847Y1059945D01*
G01X1374835Y1049331D02*
X1372997Y1050378D01*
G01X1374835Y1055709D02*
X1372997Y1056756D01*
G01X1372984Y1058898D02*
X1371146Y1059945D01*
G01X1376685Y1052520D02*
X1374847Y1053567D01*
G01X1369283Y1046142D02*
X1367445Y1047189D01*
G01X1369283Y1052520D02*
X1367445Y1053567D01*
G01X1367433Y1049331D02*
X1365595Y1050378D01*
G01X1371134Y1062087D02*
X1369296Y1063134D01*
G01X1371134Y1068465D02*
X1369296Y1069512D01*
G01X1369283Y1065276D02*
X1367445Y1066323D01*
G01X1369283Y1071654D02*
X1367445Y1072701D01*
G01X1372984Y1065276D02*
X1371146Y1066323D01*
G01X1380386Y1065276D02*
X1378548Y1066323D01*
G01X1376685Y1065276D02*
X1374847Y1066323D01*
G01X1380386Y1071654D02*
X1378548Y1072701D01*
G01X1371134Y1074843D02*
X1369296Y1075890D01*
G01X1376685Y1071654D02*
X1374847Y1072701D01*
G01X1372984Y1071654D02*
X1371146Y1072701D01*
G01X1369283Y1078032D02*
X1367445Y1079079D01*
G01X1371134Y1087599D02*
X1369296Y1088646D01*
G01X1369283Y1084410D02*
X1367445Y1085457D01*
G01X1371134Y1081221D02*
X1369296Y1082268D01*
G01X1372984Y1078032D02*
X1371146Y1079079D01*
G01X1380386Y1078032D02*
X1378548Y1079079D01*
G01X1376685Y1078032D02*
X1374847Y1079079D01*
G01X1380386Y1084410D02*
X1378548Y1085457D01*
G01X1372984Y1084410D02*
X1371146Y1085457D01*
G01X1376685Y1084410D02*
X1374847Y1085457D01*
G01X1369283Y1090788D02*
X1367445Y1091835D01*
G01X1371134Y1093977D02*
X1369296Y1095024D01*
G01X1369283Y1103544D02*
X1367445Y1104591D01*
G01X1369283Y1097166D02*
X1367445Y1098213D01*
G01X1372984Y1090788D02*
X1371146Y1091835D01*
G01X1380386Y1090788D02*
X1378548Y1091835D01*
G01X1376685Y1090788D02*
X1374847Y1091835D01*
G01X1372984Y1103544D02*
X1371146Y1104591D01*
G01X1376685Y1103544D02*
X1374847Y1104591D01*
G01X1380386Y1097166D02*
X1378548Y1098213D01*
G01X1380386Y1103544D02*
X1378548Y1104591D01*
G01X1372984Y1097166D02*
X1371146Y1098213D01*
G01X1376685Y1097166D02*
X1374847Y1098213D01*
G01X1371134Y1106733D02*
X1369296Y1107780D01*
G01X1369283Y1109922D02*
X1367445Y1110969D01*
G01X1371134Y1113111D02*
X1369296Y1114158D01*
G01X1369283Y1116300D02*
X1367445Y1117347D01*
G01X1372984Y1109922D02*
X1371146Y1110969D01*
G01X1380386Y1109922D02*
X1378548Y1110969D01*
G01X1376685Y1109922D02*
X1374847Y1110969D01*
G01X1380386Y1116300D02*
X1378548Y1117347D01*
G01X1371134Y1119489D02*
X1369296Y1120536D01*
G01X1372984Y1116300D02*
X1371146Y1117347D01*
G01X1376685Y1116300D02*
X1374847Y1117347D01*
G01X1371134Y1125867D02*
X1369296Y1126914D01*
G01X1369283Y1122678D02*
X1367445Y1123725D01*
G01X1371134Y1132245D02*
X1369296Y1133292D01*
G01X1376685Y1122678D02*
X1374847Y1123725D01*
G01X1372984Y1122678D02*
X1371146Y1123725D01*
G01X1380386Y1122678D02*
X1378548Y1123725D01*
G01X1380386Y1129056D02*
X1378548Y1130102D01*
G01X1369283Y1129056D02*
X1367445Y1130103D01*
G01X1376685Y1129056D02*
X1374847Y1130102D01*
G01X1372984Y1129056D02*
X1371146Y1130102D01*
G01X1371134Y1138622D02*
X1369296Y1139669D01*
G01X1369283Y1135433D02*
X1367445Y1136480D01*
G01X1369283Y1141811D02*
X1367445Y1142858D01*
G01X1371134Y1145000D02*
X1369296Y1146047D01*
G01X1376685Y1135433D02*
X1374847Y1136480D01*
G01X1372984Y1135433D02*
X1371146Y1136480D01*
G01X1380386Y1135433D02*
X1378548Y1136480D01*
G01X1380386Y1141811D02*
X1378548Y1142858D01*
G01X1372984Y1148189D02*
X1371146Y1149236D01*
G01X1376685Y1148189D02*
X1374847Y1149236D01*
G01X1369283Y1148189D02*
X1367445Y1149236D01*
G01X1380386Y1148189D02*
X1378548Y1149236D01*
G01X1372984Y1141811D02*
X1371146Y1142858D01*
G01X1376685Y1141811D02*
X1374847Y1142858D01*
G01X1369283Y1154567D02*
X1367445Y1155614D01*
G01X1367433Y1157756D02*
X1365595Y1158803D01*
G01X1372984Y1154567D02*
X1371146Y1155614D01*
G01X1380386Y1154567D02*
X1378548Y1155614D01*
G01X1376685Y1154567D02*
X1374847Y1155614D01*
G01X1378535Y1157756D02*
X1376697Y1158803D01*
G01X1378535Y1164134D02*
X1376697Y1165181D01*
G01X1376685Y1160945D02*
X1374847Y1161992D01*
G01X1371134Y1151378D02*
X1369296Y1152425D01*
G01X1369283Y1160945D02*
X1367445Y1161992D01*
G01X1380386Y1160945D02*
X1378548Y1161992D01*
G01X1372984Y1160945D02*
X1371146Y1161992D01*
G01X1388457Y880670D02*
X1386619Y879623D01*
G01X1384756Y874292D02*
X1382918Y873245D01*
G01X1386606Y877481D02*
X1384768Y876434D01*
G01X1395858Y874292D02*
X1394020Y873245D01*
G01X1390307Y877481D02*
X1388469Y876434D01*
G01X1394008Y877481D02*
X1392170Y876434D01*
G01X1382905Y877481D02*
X1381067Y876434D01*
G01X1386606Y883859D02*
X1384768Y882812D01*
G01X1382905Y883859D02*
X1381067Y882812D01*
G01X1382905Y890237D02*
X1381067Y889190D01*
G01X1386606Y890237D02*
X1384768Y889190D01*
G01X1394008Y883859D02*
X1392170Y882812D01*
G01X1390307Y883859D02*
X1388469Y882812D01*
G01X1390307Y896615D02*
X1388469Y895568D01*
G01X1394008Y890237D02*
X1392170Y889190D01*
G01X1392157Y893426D02*
X1390319Y892379D01*
G01X1382905Y896615D02*
X1381067Y895568D01*
G01X1386606Y896615D02*
X1384768Y895568D01*
G01X1392157Y887048D02*
X1390319Y886001D01*
G01X1394008Y896615D02*
X1392170Y895568D01*
G01X1390307Y890237D02*
X1388469Y889190D01*
G01X1382905Y902993D02*
X1381067Y901946D01*
G01X1386606Y902993D02*
X1384768Y901946D01*
G01X1390307Y902993D02*
X1388469Y901946D01*
G01X1392157Y899804D02*
X1390319Y898757D01*
G01X1394008Y902993D02*
X1392170Y901946D01*
G01X1390307Y909370D02*
X1388469Y908324D01*
G01X1392157Y912559D02*
X1390319Y911512D01*
G01X1392157Y906181D02*
X1390319Y905134D01*
G01X1386606Y909370D02*
X1384768Y908324D01*
G01X1394008Y909370D02*
X1392170Y908324D01*
G01X1382905Y909370D02*
X1381067Y908323D01*
G01X1382905Y915748D02*
X1381067Y914701D01*
G01X1386606Y915748D02*
X1384768Y914701D01*
G01X1392157Y918937D02*
X1390319Y917890D01*
G01X1390307Y915748D02*
X1388469Y914701D01*
G01X1394008Y915748D02*
X1392170Y914701D01*
G01X1390307Y922126D02*
X1388469Y921079D01*
G01X1392157Y925315D02*
X1390319Y924268D01*
G01X1386606Y922126D02*
X1384768Y921079D01*
G01X1382905Y922126D02*
X1381067Y921079D01*
G01X1394008Y922126D02*
X1392170Y921079D01*
G01X1382905Y928504D02*
X1381067Y927457D01*
G01X1386606Y928504D02*
X1384768Y927457D01*
G01X1390307Y928504D02*
X1388469Y927457D01*
G01X1390307Y934882D02*
X1388469Y933835D01*
G01X1394008Y928504D02*
X1392170Y927457D01*
G01X1392157Y931693D02*
X1390319Y930646D01*
G01X1394008Y934882D02*
X1392170Y933835D01*
G01X1390307Y941260D02*
X1388469Y940213D01*
G01X1392157Y938071D02*
X1390319Y937024D01*
G01X1384756Y931693D02*
X1382918Y930646D01*
G01X1388457Y931693D02*
X1386619Y930646D01*
G01X1386606Y941260D02*
X1384768Y940213D01*
G01X1382905Y941260D02*
X1381067Y940213D01*
G01X1395858Y931693D02*
X1394020Y930646D01*
G01X1394008Y941260D02*
X1392170Y940213D01*
G01X1382905Y947638D02*
X1381067Y946591D01*
G01X1386606Y947638D02*
X1384768Y946591D01*
G01X1390307Y947638D02*
X1388469Y946591D01*
G01X1392157Y944449D02*
X1390319Y943402D01*
G01X1394008Y947638D02*
X1392170Y946591D01*
G01X1392157Y950827D02*
X1390319Y949780D01*
G01X1390307Y954016D02*
X1388469Y952969D01*
G01X1392157Y957205D02*
X1390319Y956158D01*
G01X1386606Y954016D02*
X1384768Y952969D01*
G01X1382905Y954016D02*
X1381067Y952969D01*
G01X1394008Y954016D02*
X1392170Y952969D01*
G01X1382905Y960394D02*
X1381067Y959347D01*
G01X1386606Y960394D02*
X1384768Y959347D01*
G01X1390307Y966772D02*
X1388469Y965725D01*
G01X1390307Y960394D02*
X1388469Y959347D01*
G01X1394008Y960394D02*
X1392170Y959347D01*
G01X1392157Y963583D02*
X1390319Y962536D01*
G01X1392157Y969961D02*
X1390319Y968914D01*
G01X1386606Y966772D02*
X1384768Y965725D01*
G01X1382905Y966772D02*
X1381067Y965725D01*
G01X1394008Y966772D02*
X1392170Y965725D01*
G01X1390307Y979528D02*
X1388469Y978481D01*
G01X1382905Y973150D02*
X1381067Y972103D01*
G01X1386606Y973150D02*
X1384768Y972103D01*
G01X1384756Y982717D02*
X1382918Y981670D01*
G01X1386606Y985906D02*
X1384768Y984859D01*
G01X1390307Y973150D02*
X1388469Y972103D01*
G01X1394008Y973150D02*
X1392170Y972103D01*
G01X1392157Y982717D02*
X1390319Y981670D01*
G01X1392157Y976339D02*
X1390319Y975292D01*
G01X1394008Y985906D02*
X1392170Y984859D01*
G01X1382905Y979528D02*
X1381067Y978481D01*
G01X1386606Y979528D02*
X1384768Y978481D01*
G01X1388457Y982717D02*
X1386619Y981670D01*
G01X1382905Y985906D02*
X1381067Y984859D01*
G01X1394008Y979528D02*
X1392170Y978481D01*
G01X1395858Y982717D02*
X1394020Y981670D01*
G01X1390307Y985906D02*
X1388469Y984859D01*
G01X1386606Y992284D02*
X1384768Y991237D01*
G01X1384756Y989095D02*
X1382918Y988048D01*
G01X1394008Y992284D02*
X1392170Y991237D01*
G01X1392157Y989095D02*
X1390319Y988048D01*
G01X1388457Y989095D02*
X1386619Y988048D01*
G01X1395858Y989095D02*
X1394020Y988048D01*
G01X1382905Y992284D02*
X1381067Y991237D01*
G01X1390307Y992284D02*
X1388469Y991237D01*
G01X1382236Y1030197D02*
X1380398Y1031244D01*
G01X1382236Y1042953D02*
X1380398Y1044000D01*
G01X1382236Y1036575D02*
X1380398Y1037622D01*
G01X1387787Y1046142D02*
X1385949Y1047189D01*
G01X1387787Y1052520D02*
X1385949Y1053567D01*
G01X1385937Y1055709D02*
X1384099Y1056756D01*
G01X1385937Y1049331D02*
X1384099Y1050378D01*
G01X1395189Y1046142D02*
X1393351Y1047189D01*
G01X1395189Y1052520D02*
X1393351Y1053567D01*
G01X1391488Y1058898D02*
X1389650Y1059945D01*
G01X1393338Y1055709D02*
X1391500Y1056756D01*
G01X1393338Y1049331D02*
X1391500Y1050378D01*
G01X1391488Y1046142D02*
X1389650Y1047189D01*
G01X1384086Y1046142D02*
X1382249Y1047189D01*
G01X1382236Y1049331D02*
X1380398Y1050378D01*
G01X1391488Y1052520D02*
X1389650Y1053567D01*
G01X1389638Y1049331D02*
X1387800Y1050378D01*
G01X1395189Y1058898D02*
X1393351Y1059945D01*
G01X1389638Y1055709D02*
X1387800Y1056756D01*
G01X1382236Y1055709D02*
X1380398Y1056756D01*
G01X1387787Y1058898D02*
X1385949Y1059945D01*
G01X1384086Y1052520D02*
X1382249Y1053567D01*
G01X1384086Y1058898D02*
X1382249Y1059945D01*
G01X1391488Y1065276D02*
X1389650Y1066323D01*
G01X1393338Y1068465D02*
X1391500Y1069512D01*
G01X1391488Y1071654D02*
X1389650Y1072701D01*
G01X1382236Y1062087D02*
X1380398Y1063134D01*
G01X1387787Y1065276D02*
X1385949Y1066323D01*
G01X1384086Y1065276D02*
X1382249Y1066323D01*
G01X1382236Y1068465D02*
X1380398Y1069512D01*
G01X1393338Y1062087D02*
X1391500Y1063134D01*
G01X1395189Y1065276D02*
X1393351Y1066323D01*
G01X1382236Y1074843D02*
X1380398Y1075890D01*
G01X1393338Y1074843D02*
X1391500Y1075890D01*
G01X1395189Y1071654D02*
X1393351Y1072701D01*
G01X1387787Y1071654D02*
X1385949Y1072701D01*
G01X1384086Y1071654D02*
X1382249Y1072701D01*
G01X1387787Y1078032D02*
X1385949Y1079079D01*
G01X1384086Y1078032D02*
X1382249Y1079079D01*
G01X1382236Y1087599D02*
X1380398Y1088646D01*
G01X1382236Y1081221D02*
X1380398Y1082268D01*
G01X1395189Y1078032D02*
X1393351Y1079079D01*
G01X1391488Y1078032D02*
X1389650Y1079079D01*
G01X1393338Y1087599D02*
X1391500Y1088646D01*
G01X1391488Y1084410D02*
X1389650Y1085457D01*
G01X1393338Y1081221D02*
X1391500Y1082268D01*
G01X1395189Y1084410D02*
X1393351Y1085457D01*
G01X1387787Y1084410D02*
X1385949Y1085457D01*
G01X1384086Y1084410D02*
X1382249Y1085457D01*
G01X1387787Y1090788D02*
X1385949Y1091835D01*
G01X1384086Y1090788D02*
X1382249Y1091835D01*
G01X1382236Y1093977D02*
X1380398Y1095024D01*
G01X1395189Y1090788D02*
X1393351Y1091835D01*
G01X1391488Y1090788D02*
X1389650Y1091835D01*
G01X1393338Y1093977D02*
X1391500Y1095024D01*
G01X1393338Y1100355D02*
X1391500Y1101402D01*
G01X1391488Y1097166D02*
X1389650Y1098213D01*
G01X1395189Y1103544D02*
X1393351Y1104591D01*
G01X1391488Y1103544D02*
X1389650Y1104591D01*
G01X1395189Y1097166D02*
X1393351Y1098213D01*
G01X1387787Y1097166D02*
X1385949Y1098213D01*
G01X1384086Y1097166D02*
X1382249Y1098213D01*
G01X1387787Y1109922D02*
X1385949Y1110969D01*
G01X1384086Y1109922D02*
X1382249Y1110969D01*
G01X1382236Y1106733D02*
X1380398Y1107780D01*
G01X1382236Y1113111D02*
X1380398Y1114158D01*
G01X1395189Y1109922D02*
X1393351Y1110969D01*
G01X1391488Y1109922D02*
X1389650Y1110969D01*
G01X1393338Y1106733D02*
X1391500Y1107780D01*
G01X1391488Y1116300D02*
X1389650Y1117347D01*
G01X1393338Y1113111D02*
X1391500Y1114158D01*
G01X1382236Y1119489D02*
X1380398Y1120536D01*
G01X1393338Y1119489D02*
X1391500Y1120536D01*
G01X1395189Y1116300D02*
X1393351Y1117347D01*
G01X1389638Y1106733D02*
X1387800Y1107780D01*
G01X1387787Y1116300D02*
X1385949Y1117347D01*
G01X1384086Y1116300D02*
X1382249Y1117347D01*
G01X1385937Y1106733D02*
X1384099Y1107780D01*
G01X1387787Y1122678D02*
X1385949Y1123725D01*
G01X1384086Y1122678D02*
X1382249Y1123725D01*
G01X1382236Y1125867D02*
X1380398Y1126914D01*
G01X1382236Y1132245D02*
X1380398Y1133292D01*
G01X1395189Y1122678D02*
X1393351Y1123725D01*
G01X1391488Y1122678D02*
X1389650Y1123725D01*
G01X1393338Y1125867D02*
X1391500Y1126914D01*
G01X1393338Y1132245D02*
X1391500Y1133292D01*
G01X1391488Y1129056D02*
X1389650Y1130102D01*
G01X1395189Y1129056D02*
X1393351Y1130102D01*
G01X1384086Y1129056D02*
X1382249Y1130102D01*
G01X1387787Y1129056D02*
X1385949Y1130102D01*
G01X1382236Y1138622D02*
X1380398Y1139669D01*
G01X1387787Y1135433D02*
X1385949Y1136480D01*
G01X1384086Y1135433D02*
X1382249Y1136480D01*
G01X1387787Y1148189D02*
X1385949Y1149236D01*
G01X1384086Y1148189D02*
X1382249Y1149236D01*
G01X1382236Y1145000D02*
X1380398Y1146047D01*
G01X1393338Y1138622D02*
X1391500Y1139669D01*
G01X1395189Y1135433D02*
X1393351Y1136480D01*
G01X1391488Y1135433D02*
X1389650Y1136480D01*
G01X1391488Y1141811D02*
X1389650Y1142858D01*
G01X1395189Y1148189D02*
X1393351Y1149236D01*
G01X1393338Y1145000D02*
X1391500Y1146047D01*
G01X1391488Y1148189D02*
X1389650Y1149236D01*
G01X1395189Y1141811D02*
X1393351Y1142858D01*
G01X1387787Y1141811D02*
X1385949Y1142858D01*
G01X1384086Y1141811D02*
X1382249Y1142858D01*
G01X1387787Y1154567D02*
X1385949Y1155614D01*
G01X1384086Y1154567D02*
X1382249Y1155614D01*
G01X1387787Y1160945D02*
X1385949Y1161992D01*
G01X1389638Y1157756D02*
X1387800Y1158803D01*
G01X1395189Y1154567D02*
X1393351Y1155614D01*
G01X1391488Y1154567D02*
X1389650Y1155614D01*
G01X1393338Y1151378D02*
X1391500Y1152425D01*
G01X1382236Y1151378D02*
X1380398Y1152425D01*
G01X1391488Y1160945D02*
X1389650Y1161992D01*
G01X1395189Y1160945D02*
X1393351Y1161992D01*
G01X1384086Y1160945D02*
X1382249Y1161992D01*
G01X1399559Y874292D02*
X1397721Y873245D01*
G01X1399559Y880670D02*
X1397721Y879623D01*
G01X1397709Y877481D02*
X1395871Y876434D01*
G01X1410661Y880670D02*
X1408823Y879623D01*
G01X1401409Y877481D02*
X1399571Y876434D01*
G01X1405110Y877481D02*
X1403272Y876434D01*
G01X1401409Y883859D02*
X1399571Y882812D01*
G01X1397709Y883859D02*
X1395871Y882812D01*
G01X1403260Y893426D02*
X1401422Y892379D01*
G01X1401409Y896615D02*
X1399571Y895568D01*
G01X1397709Y890237D02*
X1395871Y889190D01*
G01X1405110Y883859D02*
X1403272Y882812D01*
G01X1408811Y883859D02*
X1406973Y882812D01*
G01X1405110Y890237D02*
X1403272Y889190D01*
G01X1408811Y890237D02*
X1406973Y889190D01*
G01X1403260Y887048D02*
X1401422Y886001D01*
G01X1397709Y896615D02*
X1395871Y895568D01*
G01X1401409Y890237D02*
X1399571Y889190D01*
G01X1410661Y893426D02*
X1408823Y892379D01*
G01X1406960Y893426D02*
X1405123Y892379D01*
G01X1401409Y902993D02*
X1399571Y901946D01*
G01X1397709Y902993D02*
X1395871Y901946D01*
G01X1403260Y906181D02*
X1401422Y905134D01*
G01X1403260Y912559D02*
X1401422Y911512D01*
G01X1406960Y906181D02*
X1405123Y905134D01*
G01X1410661Y906181D02*
X1408823Y905134D01*
G01X1403260Y899804D02*
X1401422Y898757D01*
G01X1401409Y909370D02*
X1399571Y908323D01*
G01X1397709Y909370D02*
X1395871Y908324D01*
G01X1406960Y912559D02*
X1405123Y911512D01*
G01X1410661Y899804D02*
X1408823Y898757D01*
G01X1406960Y899804D02*
X1405123Y898757D01*
G01X1401409Y915748D02*
X1399571Y914701D01*
G01X1403260Y918937D02*
X1401422Y917890D01*
G01X1397709Y915748D02*
X1395871Y914701D01*
G01X1401409Y922126D02*
X1399571Y921079D01*
G01X1403260Y925315D02*
X1401422Y924268D01*
G01X1406960Y918937D02*
X1405123Y917890D01*
G01X1410661Y918937D02*
X1408823Y917890D01*
G01X1410661Y912559D02*
X1408823Y911512D01*
G01X1397709Y922126D02*
X1395871Y921079D01*
G01X1410661Y925315D02*
X1408823Y924268D01*
G01X1406960Y925315D02*
X1405123Y924268D01*
G01X1397709Y928504D02*
X1395871Y927457D01*
G01X1397709Y934882D02*
X1395871Y933835D01*
G01X1401409Y928504D02*
X1399571Y927457D01*
G01X1403260Y931693D02*
X1401422Y930646D01*
G01X1401409Y934882D02*
X1399571Y933835D01*
G01X1401409Y941260D02*
X1399571Y940213D01*
G01X1403260Y938071D02*
X1401422Y937024D01*
G01X1406960Y931693D02*
X1405123Y930646D01*
G01X1410661Y931693D02*
X1408823Y930646D01*
G01X1406960Y938071D02*
X1405123Y937024D01*
G01X1410661Y938071D02*
X1408823Y937024D01*
G01X1399559Y931693D02*
X1397721Y930646D01*
G01X1397709Y941260D02*
X1395871Y940213D01*
G01X1408811Y934882D02*
X1406973Y933835D01*
G01X1405110Y934882D02*
X1403272Y933835D01*
G01X1403260Y944449D02*
X1401422Y943402D01*
G01X1401409Y947638D02*
X1399571Y946591D01*
G01X1403260Y950827D02*
X1401422Y949780D01*
G01X1401409Y954016D02*
X1399571Y952969D01*
G01X1403260Y957205D02*
X1401422Y956158D01*
G01X1410661Y950827D02*
X1408823Y949780D01*
G01X1406960Y950827D02*
X1405123Y949780D01*
G01X1397709Y947638D02*
X1395871Y946591D01*
G01X1397709Y954016D02*
X1395871Y952969D01*
G01X1406960Y944449D02*
X1405123Y943402D01*
G01X1410661Y944449D02*
X1408823Y943402D01*
G01X1406960Y957205D02*
X1405123Y956158D01*
G01X1401409Y966772D02*
X1399571Y965725D01*
G01X1397709Y960394D02*
X1395871Y959347D01*
G01X1401409Y960394D02*
X1399571Y959347D01*
G01X1403260Y963583D02*
X1401422Y962536D01*
G01X1403260Y969961D02*
X1401422Y968914D01*
G01X1410661Y963583D02*
X1408823Y962536D01*
G01X1406960Y963583D02*
X1405123Y962536D01*
G01X1410661Y957205D02*
X1408823Y956158D01*
G01X1406960Y969961D02*
X1405123Y968914D01*
G01X1397709Y966772D02*
X1395871Y965725D01*
G01X1410661Y969961D02*
X1408823Y968914D01*
G01X1399559Y982717D02*
X1397721Y981670D01*
G01X1401409Y979528D02*
X1399571Y978481D01*
G01X1397709Y973150D02*
X1395871Y972103D01*
G01X1401409Y973150D02*
X1399571Y972103D01*
G01X1403260Y976339D02*
X1401422Y975292D01*
G01X1401409Y985906D02*
X1399571Y984859D01*
G01X1406960Y982717D02*
X1405123Y981670D01*
G01X1410661Y976339D02*
X1408823Y975292D01*
G01X1406960Y976339D02*
X1405123Y975292D01*
G01X1408811Y985906D02*
X1406973Y984859D01*
G01X1397709Y979528D02*
X1395871Y978481D01*
G01X1403260Y982717D02*
X1401422Y981670D01*
G01X1397709Y985906D02*
X1395871Y984859D01*
G01X1410661Y982717D02*
X1408823Y981670D01*
G01X1405110Y985906D02*
X1403272Y984859D01*
G01X1401409Y992284D02*
X1399571Y991237D01*
G01X1399559Y989095D02*
X1397721Y988048D01*
G01X1408811Y992284D02*
X1406973Y991237D01*
G01X1406960Y989095D02*
X1405123Y988048D01*
G01X1403260Y989095D02*
X1401422Y988048D01*
G01X1397709Y992284D02*
X1395871Y991237D01*
G01X1410661Y989095D02*
X1408823Y988048D01*
G01X1405110Y992284D02*
X1403272Y991237D01*
G01X1402590Y1046142D02*
X1400752Y1047189D01*
G01X1400740Y1055709D02*
X1398902Y1056756D01*
G01X1402590Y1052520D02*
X1400752Y1053567D01*
G01X1402590Y1058898D02*
X1400752Y1059945D01*
G01X1400740Y1049331D02*
X1398902Y1050378D01*
G01X1409992Y1046142D02*
X1408154Y1047189D01*
G01X1409992Y1052520D02*
X1408154Y1053567D01*
G01X1408142Y1055709D02*
X1406304Y1056756D01*
G01X1408142Y1049331D02*
X1406304Y1050378D01*
G01X1406291Y1046142D02*
X1404453Y1047189D01*
G01X1398890Y1046142D02*
X1397052Y1047189D01*
G01X1397039Y1049331D02*
X1395201Y1050378D01*
G01X1406291Y1052520D02*
X1404453Y1053567D01*
G01X1398890Y1052520D02*
X1397052Y1053567D01*
G01X1398890Y1058898D02*
X1397052Y1059945D01*
G01X1397039Y1055709D02*
X1395201Y1056756D01*
G01X1404441Y1049331D02*
X1402603Y1050378D01*
G01X1404441Y1055709D02*
X1402603Y1056756D01*
G01X1404441Y1062087D02*
X1402603Y1063134D01*
G01X1404441Y1068465D02*
X1402603Y1069512D01*
G01X1398890Y1065276D02*
X1397052Y1066323D01*
G01X1402590Y1065276D02*
X1400752Y1066323D01*
G01X1402590Y1071654D02*
X1400752Y1072701D01*
G01X1408142Y1062087D02*
X1406304Y1063134D01*
G01X1404441Y1074843D02*
X1402603Y1075890D01*
G01X1408142Y1074843D02*
X1406304Y1075890D01*
G01X1398890Y1071654D02*
X1397052Y1072701D01*
G01X1408142Y1068465D02*
X1406304Y1069512D01*
G01X1402590Y1078032D02*
X1400752Y1079079D01*
G01X1398890Y1078032D02*
X1397052Y1079079D01*
G01X1404441Y1087599D02*
X1402603Y1088646D01*
G01X1404441Y1081221D02*
X1402603Y1082268D01*
G01X1402590Y1084410D02*
X1400752Y1085457D01*
G01X1408142Y1087599D02*
X1406304Y1088646D01*
G01X1408142Y1081221D02*
X1406304Y1082268D01*
G01X1398890Y1084410D02*
X1397052Y1085457D01*
G01X1404441Y1093977D02*
X1402603Y1095024D01*
G01X1402590Y1090788D02*
X1400752Y1091835D01*
G01X1398890Y1090788D02*
X1397052Y1091835D01*
G01X1404441Y1100355D02*
X1402603Y1101402D01*
G01X1402590Y1103544D02*
X1400752Y1104591D01*
G01X1398890Y1103544D02*
X1397052Y1104591D01*
G01X1402590Y1097166D02*
X1400752Y1098213D01*
G01X1408142Y1100355D02*
X1406304Y1101402D01*
G01X1406291Y1103544D02*
X1404453Y1104591D01*
G01X1409992Y1103544D02*
X1408154Y1104591D01*
G01X1408142Y1093977D02*
X1406304Y1095024D01*
G01X1398890Y1097166D02*
X1397052Y1098213D01*
G01X1404441Y1106733D02*
X1402603Y1107780D01*
G01X1398890Y1109922D02*
X1397052Y1110969D01*
G01X1402590Y1109922D02*
X1400752Y1110969D01*
G01X1404441Y1113111D02*
X1402603Y1114158D01*
G01X1402590Y1116300D02*
X1400752Y1117347D01*
G01X1408142Y1106733D02*
X1406304Y1107780D01*
G01X1404441Y1119489D02*
X1402603Y1120536D01*
G01X1408142Y1119489D02*
X1406304Y1120536D01*
G01X1408142Y1113111D02*
X1406304Y1114158D01*
G01X1398890Y1116300D02*
X1397052Y1117347D01*
G01X1397039Y1106733D02*
X1395201Y1107780D01*
G01X1400740Y1106733D02*
X1398902Y1107780D01*
G01X1404441Y1125867D02*
X1402603Y1126914D01*
G01X1398890Y1122678D02*
X1397052Y1123725D01*
G01X1402590Y1122678D02*
X1400752Y1123725D01*
G01X1404441Y1132245D02*
X1402603Y1133292D01*
G01X1408142Y1132245D02*
X1406304Y1133292D01*
G01X1402590Y1129056D02*
X1400752Y1130103D01*
G01X1408142Y1125867D02*
X1406304Y1126914D01*
G01X1398890Y1129056D02*
X1397052Y1130102D01*
G01X1404441Y1138622D02*
X1402603Y1139669D01*
G01X1398890Y1135433D02*
X1397052Y1136480D01*
G01X1402590Y1135433D02*
X1400752Y1136480D01*
G01X1402590Y1141811D02*
X1400752Y1142858D01*
G01X1404441Y1145000D02*
X1402603Y1146047D01*
G01X1398890Y1148189D02*
X1397052Y1149236D01*
G01X1409992Y1148189D02*
X1408154Y1149236D01*
G01X1406291Y1148189D02*
X1404453Y1149236D01*
G01X1408142Y1145000D02*
X1406304Y1146047D01*
G01X1408142Y1138622D02*
X1406304Y1139669D01*
G01X1402590Y1148189D02*
X1400752Y1149236D01*
G01X1398890Y1141811D02*
X1397052Y1142858D01*
G01X1400740Y1157756D02*
X1398902Y1158803D01*
G01X1398890Y1154567D02*
X1397052Y1155614D01*
G01X1402590Y1154567D02*
X1400752Y1155614D01*
G01X1398890Y1160945D02*
X1397052Y1161992D01*
G01X1400740Y1164134D02*
X1398902Y1165181D01*
G01X1408142Y1157756D02*
X1406304Y1158803D01*
G01X1406291Y1160945D02*
X1404453Y1161992D01*
G01X1408142Y1151378D02*
X1406304Y1152425D01*
G01X1402590Y1160945D02*
X1400752Y1161992D01*
G01X1404441Y1151378D02*
X1402603Y1152425D01*
G01X1412512Y877481D02*
X1410674Y876434D01*
G01X1421764Y880670D02*
X1423602Y879623D01*
G01X1419913Y877481D02*
X1421751Y876434D01*
G01X1412512Y883859D02*
X1410674Y882812D01*
G01X1412512Y890237D02*
X1410674Y889190D01*
G01X1412512Y896615D02*
X1410674Y895568D01*
G01X1419913Y883859D02*
X1421751Y882812D01*
G01X1419913Y896615D02*
X1421751Y895568D01*
G01X1419913Y890237D02*
X1421751Y889190D01*
G01X1423614Y890237D02*
X1425452Y889190D01*
G01X1421764Y893426D02*
X1423602Y892379D01*
G01X1412512Y902993D02*
X1410674Y901946D01*
G01X1412512Y909370D02*
X1410674Y908324D01*
G01X1419913Y902993D02*
X1421751Y901946D01*
G01X1421764Y906181D02*
X1423602Y905134D01*
G01X1419913Y909370D02*
X1421751Y908324D01*
G01X1421764Y899804D02*
X1423602Y898757D01*
G01X1412512Y915748D02*
X1410674Y914701D01*
G01X1412512Y922126D02*
X1410674Y921079D01*
G01X1421764Y918937D02*
X1423602Y917890D01*
G01X1419913Y915748D02*
X1421751Y914701D01*
G01X1419913Y922126D02*
X1421751Y921079D01*
G01X1421764Y912559D02*
X1423602Y911512D01*
G01X1421764Y925315D02*
X1423602Y924268D01*
G01X1419913Y941260D02*
X1421751Y940213D01*
G01X1412512Y928504D02*
X1410674Y927457D01*
G01X1412512Y934882D02*
X1410674Y933835D01*
G01X1412512Y941260D02*
X1410674Y940213D01*
G01X1421764Y931693D02*
X1423602Y930646D01*
G01X1419913Y928504D02*
X1421751Y927457D01*
G01X1419913Y934882D02*
X1421751Y933835D01*
G01X1421764Y938071D02*
X1423602Y937024D01*
G01X1423614Y934882D02*
X1425452Y933835D01*
G01X1412512Y947638D02*
X1410674Y946591D01*
G01X1412512Y954016D02*
X1410674Y952969D01*
G01X1421764Y950827D02*
X1423602Y949780D01*
G01X1419913Y947638D02*
X1421751Y946591D01*
G01X1419913Y954016D02*
X1421751Y952969D01*
G01X1421764Y944449D02*
X1423602Y943402D01*
G01X1412512Y960394D02*
X1410674Y959347D01*
G01X1412512Y966772D02*
X1410674Y965725D01*
G01X1421764Y963583D02*
X1423602Y962536D01*
G01X1419913Y960394D02*
X1421751Y959347D01*
G01X1419913Y966772D02*
X1421751Y965725D01*
G01X1421764Y957205D02*
X1423602Y956158D01*
G01X1421764Y969961D02*
X1423602Y968914D01*
G01X1412512Y973150D02*
X1410674Y972103D01*
G01X1412512Y979528D02*
X1410674Y978481D01*
G01X1421764Y982717D02*
X1423602Y981670D01*
G01X1421764Y976339D02*
X1423602Y975292D01*
G01X1419913Y973150D02*
X1421751Y972103D01*
G01X1419913Y979528D02*
X1421751Y978481D01*
G01X1419913Y985906D02*
X1421751Y984859D01*
G01X1412512Y985906D02*
X1410674Y984859D01*
G01X1421764Y989095D02*
X1423602Y988048D01*
G01X1419913Y992284D02*
X1421751Y991237D01*
G01X1423614Y985906D02*
X1425452Y984859D01*
G01X1423614Y992284D02*
X1425452Y991237D01*
G01X1412512Y992284D02*
X1410674Y991237D01*
G01X1413693Y1058898D02*
X1411855Y1059945D01*
G01X1421094Y1046142D02*
X1422932Y1047189D01*
G01X1421094Y1058898D02*
X1422932Y1059945D01*
G01X1421094Y1052520D02*
X1422932Y1053567D01*
G01X1422945Y1055709D02*
X1424783Y1056756D01*
G01X1422945Y1049331D02*
X1424783Y1050378D01*
G01X1413693Y1046142D02*
X1411855Y1047189D01*
G01X1411842Y1049331D02*
X1410004Y1050378D01*
G01X1411842Y1055709D02*
X1410004Y1056756D01*
G01X1413693Y1052520D02*
X1411855Y1053567D01*
G01X1411842Y1062087D02*
X1410004Y1063134D01*
G01X1413693Y1065276D02*
X1411855Y1066323D01*
G01X1413693Y1071654D02*
X1411855Y1072701D01*
G01X1421094Y1071654D02*
X1422932Y1072701D01*
G01X1421094Y1065276D02*
X1422932Y1066323D01*
G01X1422945Y1062087D02*
X1424783Y1063134D01*
G01X1411842Y1074843D02*
X1410004Y1075890D01*
G01X1422945Y1074843D02*
X1424783Y1075890D01*
G01X1411842Y1068465D02*
X1410004Y1069512D01*
G01X1422945Y1068465D02*
X1424783Y1069512D01*
G01X1413693Y1078032D02*
X1411855Y1079079D01*
G01X1413693Y1084410D02*
X1411855Y1085457D01*
G01X1411842Y1087599D02*
X1410004Y1088646D01*
G01X1421094Y1078032D02*
X1422932Y1079079D01*
G01X1421094Y1084410D02*
X1422932Y1085457D01*
G01X1422945Y1087599D02*
X1424783Y1088646D01*
G01X1411842Y1081221D02*
X1410004Y1082268D01*
G01X1422945Y1081221D02*
X1424783Y1082268D01*
G01X1421094Y1090788D02*
X1422932Y1091835D01*
G01X1421094Y1103544D02*
X1422932Y1104591D01*
G01X1421094Y1097166D02*
X1422932Y1098213D01*
G01X1413693Y1090788D02*
X1411855Y1091835D01*
G01X1413693Y1103544D02*
X1411855Y1104591D01*
G01X1413693Y1097166D02*
X1411855Y1098213D01*
G01X1411842Y1100355D02*
X1410004Y1101402D01*
G01X1422945Y1100355D02*
X1424783Y1101402D01*
G01X1411842Y1093977D02*
X1410004Y1095024D01*
G01X1422945Y1093977D02*
X1424783Y1095024D01*
G01X1411842Y1106733D02*
X1410004Y1107780D01*
G01X1413693Y1109922D02*
X1411855Y1110969D01*
G01X1413693Y1116300D02*
X1411855Y1117347D01*
G01X1421094Y1109922D02*
X1422932Y1110969D01*
G01X1421094Y1116300D02*
X1422932Y1117347D01*
G01X1422945Y1106733D02*
X1424783Y1107780D01*
G01X1411842Y1119489D02*
X1410004Y1120536D01*
G01X1422945Y1119489D02*
X1424783Y1120536D01*
G01X1411842Y1113111D02*
X1410004Y1114158D01*
G01X1422945Y1113111D02*
X1424783Y1114158D01*
G01X1413693Y1122678D02*
X1411855Y1123725D01*
G01X1413693Y1129056D02*
X1411855Y1130102D01*
G01X1411842Y1132245D02*
X1410004Y1133292D01*
G01X1421094Y1122678D02*
X1422932Y1123725D01*
G01X1421094Y1129056D02*
X1422932Y1130102D01*
G01X1422945Y1132245D02*
X1424783Y1133292D01*
G01X1411842Y1125867D02*
X1410004Y1126914D01*
G01X1422945Y1125867D02*
X1424783Y1126914D01*
G01X1413693Y1135433D02*
X1411855Y1136480D01*
G01X1413693Y1141811D02*
X1411855Y1142858D01*
G01X1413693Y1148189D02*
X1411855Y1149236D01*
G01X1421094Y1135433D02*
X1422932Y1136480D01*
G01X1421094Y1141811D02*
X1422932Y1142858D01*
G01X1421094Y1148189D02*
X1422932Y1149236D01*
G01X1411842Y1145000D02*
X1410004Y1146047D01*
G01X1411842Y1138622D02*
X1410004Y1139669D01*
G01X1422945Y1145000D02*
X1424783Y1146047D01*
G01X1422945Y1138622D02*
X1424783Y1139669D01*
G01X1413693Y1154567D02*
X1411855Y1155614D01*
G01X1413693Y1160945D02*
X1411855Y1161992D01*
G01X1421094Y1154567D02*
X1422932Y1155614D01*
G01X1421094Y1160945D02*
X1422932Y1161992D01*
G01X1434716Y877481D02*
X1436554Y876434D01*
G01X1438417Y877481D02*
X1440255Y876434D01*
G01X1427315Y877481D02*
X1429153Y876434D01*
G01X1431016Y877481D02*
X1432854Y876434D01*
G01X1427315Y883859D02*
X1429153Y882812D01*
G01X1427315Y890237D02*
X1429153Y889190D01*
G01X1429165Y893426D02*
X1431003Y892379D01*
G01X1431016Y896615D02*
X1432854Y895568D01*
G01X1434716Y890237D02*
X1436554Y889190D01*
G01X1438417Y890237D02*
X1440255Y889190D01*
G01X1429165Y887048D02*
X1431003Y886001D01*
G01X1425464Y887048D02*
X1427302Y886001D01*
G01X1425464Y893426D02*
X1427302Y892379D01*
G01X1431016Y890237D02*
X1432854Y889190D01*
G01X1434716Y896615D02*
X1436554Y895568D01*
G01X1431016Y902993D02*
X1432854Y901946D01*
G01X1429165Y899804D02*
X1431003Y898757D01*
G01X1429165Y912559D02*
X1431003Y911512D01*
G01X1429165Y906181D02*
X1431003Y905134D01*
G01X1425464Y906181D02*
X1427302Y905134D01*
G01X1434716Y902993D02*
X1436554Y901946D01*
G01X1438417Y902993D02*
X1440255Y901946D01*
G01X1431016Y909370D02*
X1432854Y908323D01*
G01X1438417Y896615D02*
X1440255Y895568D01*
G01X1438417Y909370D02*
X1440255Y908324D01*
G01X1425464Y912559D02*
X1427302Y911512D01*
G01X1434716Y909370D02*
X1436554Y908324D01*
G01X1425464Y899804D02*
X1427302Y898757D01*
G01X1431016Y915748D02*
X1432854Y914701D01*
G01X1429165Y918937D02*
X1431003Y917890D01*
G01X1425464Y918937D02*
X1427302Y917890D01*
G01X1431016Y922126D02*
X1432854Y921079D01*
G01X1429165Y925315D02*
X1431003Y924268D01*
G01X1434716Y915748D02*
X1436554Y914701D01*
G01X1438417Y915748D02*
X1440255Y914701D01*
G01X1438417Y922126D02*
X1440255Y921079D01*
G01X1425464Y925315D02*
X1427302Y924268D01*
G01X1434716Y922126D02*
X1436554Y921079D01*
G01X1431016Y928504D02*
X1432854Y927457D01*
G01X1429165Y931693D02*
X1431003Y930646D01*
G01X1425464Y931693D02*
X1427302Y930646D01*
G01X1431016Y934882D02*
X1432854Y933835D01*
G01X1431016Y941260D02*
X1432854Y940213D01*
G01X1429165Y938071D02*
X1431003Y937024D01*
G01X1425464Y938071D02*
X1427302Y937024D01*
G01X1434716Y928504D02*
X1436554Y927457D01*
G01X1434716Y934882D02*
X1436554Y933835D01*
G01X1438417Y928504D02*
X1440255Y927457D01*
G01X1438417Y934882D02*
X1440255Y933835D01*
G01X1427315Y934882D02*
X1429153Y933835D01*
G01X1432866Y931693D02*
X1434704Y930646D01*
G01X1436567Y931693D02*
X1438405Y930646D01*
G01X1434716Y941260D02*
X1436554Y940213D01*
G01X1429165Y944449D02*
X1431003Y943402D01*
G01X1429165Y950827D02*
X1431003Y949780D01*
G01X1425464Y950827D02*
X1427302Y949780D01*
G01X1431016Y947638D02*
X1432854Y946591D01*
G01X1431016Y954016D02*
X1432854Y952969D01*
G01X1429165Y957205D02*
X1431003Y956158D01*
G01X1434716Y947638D02*
X1436554Y946591D01*
G01X1438417Y947638D02*
X1440255Y946591D01*
G01X1438417Y941260D02*
X1440255Y940213D01*
G01X1438417Y954016D02*
X1440255Y952969D01*
G01X1425464Y944449D02*
X1427302Y943402D01*
G01X1425464Y957205D02*
X1427302Y956158D01*
G01X1434716Y954016D02*
X1436554Y952969D01*
G01X1431016Y960394D02*
X1432854Y959347D01*
G01X1425464Y963583D02*
X1427302Y962536D01*
G01X1429165Y963583D02*
X1431003Y962536D01*
G01X1431016Y966772D02*
X1432854Y965725D01*
G01X1429165Y969961D02*
X1431003Y968914D01*
G01X1434716Y960394D02*
X1436554Y959347D01*
G01X1438417Y960394D02*
X1440255Y959347D01*
G01X1438417Y966772D02*
X1440255Y965725D01*
G01X1425464Y969961D02*
X1427302Y968914D01*
G01X1434716Y966772D02*
X1436554Y965725D01*
G01X1431016Y979528D02*
X1432854Y978481D01*
G01X1429165Y982717D02*
X1431003Y981670D01*
G01X1431016Y973150D02*
X1432854Y972103D01*
G01X1429165Y976339D02*
X1431003Y975292D01*
G01X1425464Y976339D02*
X1427302Y975292D01*
G01X1427315Y985906D02*
X1429153Y984859D01*
G01X1436567Y982717D02*
X1438405Y981670D01*
G01X1434716Y973150D02*
X1436554Y972103D01*
G01X1434716Y985906D02*
X1436554Y984859D01*
G01X1438417Y973150D02*
X1440255Y972103D01*
G01X1438417Y979528D02*
X1440255Y978481D01*
G01X1425464Y982717D02*
X1427302Y981670D01*
G01X1432866Y982717D02*
X1434704Y981670D01*
G01X1431016Y985906D02*
X1432854Y984859D01*
G01X1434716Y979528D02*
X1436554Y978481D01*
G01X1429165Y989095D02*
X1431003Y988048D01*
G01X1427315Y992284D02*
X1429153Y991237D01*
G01X1434716Y992284D02*
X1436554Y991237D01*
G01X1436567Y989095D02*
X1438405Y988048D01*
G01X1438417Y985906D02*
X1440255Y984859D01*
G01X1432866Y989095D02*
X1434704Y988048D01*
G01X1438417Y992284D02*
X1440255Y991237D01*
G01X1425464Y989095D02*
X1427302Y988048D01*
G01X1431016Y992284D02*
X1432854Y991237D01*
G01X1428496Y1046142D02*
X1430334Y1047189D01*
G01X1432197Y1058898D02*
X1434035Y1059945D01*
G01X1430346Y1055709D02*
X1432184Y1056756D01*
G01X1428496Y1052520D02*
X1430334Y1053567D01*
G01X1430346Y1049331D02*
X1432184Y1050378D01*
G01X1435897Y1046142D02*
X1437735Y1047189D01*
G01X1435897Y1052520D02*
X1437735Y1053567D01*
G01X1437748Y1055709D02*
X1439586Y1056756D01*
G01X1437748Y1049331D02*
X1439586Y1050378D01*
G01X1434047Y1049331D02*
X1435885Y1050378D01*
G01X1424795Y1046142D02*
X1426633Y1047189D01*
G01X1432197Y1046142D02*
X1434035Y1047189D01*
G01X1432197Y1052520D02*
X1434035Y1053567D01*
G01X1424795Y1052520D02*
X1426633Y1053567D01*
G01X1426646Y1055709D02*
X1428483Y1056756D01*
G01X1434047Y1055709D02*
X1435885Y1056756D01*
G01X1435897Y1058898D02*
X1437735Y1059945D01*
G01X1426646Y1049331D02*
X1428483Y1050378D01*
G01X1430346Y1062087D02*
X1432184Y1063134D01*
G01X1426646Y1062087D02*
X1428483Y1063134D01*
G01X1430346Y1068465D02*
X1432184Y1069512D01*
G01X1432197Y1071654D02*
X1434035Y1072701D01*
G01X1432197Y1065276D02*
X1434035Y1066323D01*
G01X1435897Y1065276D02*
X1437735Y1066323D01*
G01X1426646Y1074843D02*
X1428483Y1075890D01*
G01X1430346Y1074843D02*
X1432184Y1075890D01*
G01X1435897Y1071654D02*
X1437735Y1072701D01*
G01X1426646Y1068465D02*
X1428483Y1069512D01*
G01X1435897Y1078032D02*
X1437735Y1079079D01*
G01X1432197Y1078032D02*
X1434035Y1079079D01*
G01X1430346Y1081221D02*
X1432184Y1082268D01*
G01X1426646Y1087599D02*
X1428483Y1088646D01*
G01X1430346Y1087599D02*
X1432184Y1088646D01*
G01X1432197Y1084410D02*
X1434035Y1085457D01*
G01X1435897Y1084410D02*
X1437735Y1085457D01*
G01X1426646Y1081221D02*
X1428483Y1082268D01*
G01X1430346Y1093977D02*
X1432184Y1095024D01*
G01X1432197Y1090788D02*
X1434035Y1091835D01*
G01X1432197Y1103544D02*
X1434035Y1104591D01*
G01X1426646Y1100355D02*
X1428483Y1101402D01*
G01X1430346Y1100355D02*
X1432184Y1101402D01*
G01X1432197Y1097166D02*
X1434035Y1098213D01*
G01X1435897Y1090788D02*
X1437735Y1091835D01*
G01X1435897Y1103544D02*
X1437735Y1104591D01*
G01X1435897Y1097166D02*
X1437735Y1098213D01*
G01X1424795Y1103544D02*
X1426633Y1104591D01*
G01X1428496Y1103544D02*
X1430334Y1104591D01*
G01X1426646Y1093977D02*
X1428483Y1095024D01*
G01X1426646Y1106733D02*
X1428483Y1107780D01*
G01X1430346Y1106733D02*
X1432184Y1107780D01*
G01X1432197Y1109922D02*
X1434035Y1110969D01*
G01X1432197Y1116300D02*
X1434035Y1117347D01*
G01X1430346Y1113111D02*
X1432184Y1114158D01*
G01X1435897Y1109922D02*
X1437735Y1110969D01*
G01X1430346Y1119489D02*
X1432184Y1120536D01*
G01X1426646Y1119489D02*
X1428483Y1120536D01*
G01X1435897Y1116300D02*
X1437735Y1117347D01*
G01X1434047Y1106733D02*
X1435885Y1107780D01*
G01X1426646Y1113111D02*
X1428483Y1114158D01*
G01X1437748Y1106733D02*
X1439586Y1107780D01*
G01X1430346Y1125867D02*
X1432184Y1126914D01*
G01X1432197Y1122678D02*
X1434035Y1123725D01*
G01X1426646Y1132245D02*
X1428483Y1133292D01*
G01X1430346Y1132245D02*
X1432184Y1133292D01*
G01X1435897Y1122678D02*
X1437735Y1123725D01*
G01X1432197Y1129056D02*
X1434035Y1130103D01*
G01X1435897Y1129056D02*
X1437735Y1130102D01*
G01X1426646Y1125867D02*
X1428483Y1126914D01*
G01X1430346Y1138622D02*
X1432184Y1139669D01*
G01X1432197Y1135433D02*
X1434035Y1136480D01*
G01X1432197Y1141811D02*
X1434035Y1142858D01*
G01X1428496Y1148189D02*
X1430334Y1149236D01*
G01X1430346Y1145000D02*
X1432184Y1146047D01*
G01X1424795Y1148189D02*
X1426633Y1149236D01*
G01X1435897Y1135433D02*
X1437735Y1136480D01*
G01X1435897Y1148189D02*
X1437735Y1149236D01*
G01X1435897Y1141811D02*
X1437735Y1142858D01*
G01X1426646Y1145000D02*
X1428483Y1146047D01*
G01X1432197Y1148189D02*
X1434035Y1149236D01*
G01X1426646Y1138622D02*
X1428483Y1139669D01*
G01X1428496Y1154567D02*
X1430333Y1155614D01*
G01X1434047Y1157756D02*
X1435885Y1158803D01*
G01X1434047Y1151378D02*
X1435885Y1152425D01*
G01X1428496Y1160945D02*
X1430334Y1161992D01*
G01X1432197Y1160945D02*
X1434035Y1161992D01*
G01X1430346Y1151378D02*
X1432184Y1152425D01*
G01X1426646Y1151378D02*
X1428483Y1152425D01*
G01X1445819Y877481D02*
X1447657Y876434D01*
G01X1443968Y880670D02*
X1445806Y879623D01*
G01X1453220Y877481D02*
X1455058Y876434D01*
G01X1442118Y877481D02*
X1443956Y876434D01*
G01X1449520Y877481D02*
X1451358Y876434D01*
G01X1442118Y883859D02*
X1443956Y882812D01*
G01X1445819Y883859D02*
X1447657Y882812D01*
G01X1445819Y890237D02*
X1447657Y889190D01*
G01X1440268Y893426D02*
X1442106Y892379D01*
G01X1442118Y896615D02*
X1443956Y895568D01*
G01X1449520Y883859D02*
X1451357Y882812D01*
G01X1449520Y890237D02*
X1451358Y889190D01*
G01X1451370Y893426D02*
X1453208Y892379D01*
G01X1453220Y883859D02*
X1455058Y882812D01*
G01X1453220Y890237D02*
X1455058Y889190D01*
G01X1440268Y887048D02*
X1442106Y886001D01*
G01X1442118Y890237D02*
X1443956Y889190D01*
G01X1445819Y896615D02*
X1447657Y895568D01*
G01X1451370Y887048D02*
X1453208Y886001D01*
G01X1449520Y896615D02*
X1451358Y895568D01*
G01X1453220Y896615D02*
X1455058Y895568D01*
G01X1440268Y899804D02*
X1442106Y898757D01*
G01X1445819Y902993D02*
X1447657Y901946D01*
G01X1442118Y902993D02*
X1443956Y901946D01*
G01X1440268Y906181D02*
X1442106Y905134D01*
G01X1442118Y909370D02*
X1443956Y908324D01*
G01X1440268Y912559D02*
X1442106Y911512D01*
G01X1449520Y902993D02*
X1451358Y901946D01*
G01X1451370Y899804D02*
X1453208Y898757D01*
G01X1451370Y906181D02*
X1453208Y905134D01*
G01X1453220Y902993D02*
X1455058Y901946D01*
G01X1453220Y909370D02*
X1455058Y908324D01*
G01X1445819Y909370D02*
X1447657Y908324D01*
G01X1449520Y909370D02*
X1451357Y908324D01*
G01X1451370Y912559D02*
X1453208Y911512D01*
G01X1442118Y915748D02*
X1443956Y914701D01*
G01X1445819Y915748D02*
X1447657Y914701D01*
G01X1440268Y918937D02*
X1442106Y917890D01*
G01X1442118Y922126D02*
X1443956Y921079D01*
G01X1440268Y925315D02*
X1442106Y924268D01*
G01X1449520Y915748D02*
X1451357Y914701D01*
G01X1451370Y918937D02*
X1453208Y917890D01*
G01X1451370Y925315D02*
X1453208Y924268D01*
G01X1453220Y922126D02*
X1455058Y921079D01*
G01X1453220Y915748D02*
X1455058Y914701D01*
G01X1445819Y922126D02*
X1447657Y921079D01*
G01X1449520Y922126D02*
X1451357Y921079D01*
G01X1442118Y928504D02*
X1443956Y927457D01*
G01X1445819Y928504D02*
X1447657Y927457D01*
G01X1442118Y934882D02*
X1443956Y933835D01*
G01X1440268Y938071D02*
X1442106Y937024D01*
G01X1442118Y941260D02*
X1443956Y940213D01*
G01X1451370Y931693D02*
X1453208Y930646D01*
G01X1449520Y928504D02*
X1451357Y927457D01*
G01X1453220Y928504D02*
X1455058Y927457D01*
G01X1453220Y934882D02*
X1455058Y933835D01*
G01X1443968Y931693D02*
X1445806Y930646D01*
G01X1447669Y931693D02*
X1449507Y930646D01*
G01X1445819Y941260D02*
X1447657Y940213D01*
G01X1449520Y941260D02*
X1451357Y940213D01*
G01X1453220Y941260D02*
X1455058Y940213D01*
G01X1445819Y947638D02*
X1447657Y946591D01*
G01X1440268Y944449D02*
X1442106Y943402D01*
G01X1440268Y950827D02*
X1442106Y949780D01*
G01X1442118Y947638D02*
X1443956Y946591D01*
G01X1442118Y954016D02*
X1443956Y952969D01*
G01X1440268Y957205D02*
X1442106Y956158D01*
G01X1449520Y947638D02*
X1451357Y946591D01*
G01X1451370Y944449D02*
X1453208Y943402D01*
G01X1451370Y950827D02*
X1453208Y949780D01*
G01X1453220Y954016D02*
X1455058Y952969D01*
G01X1453220Y947638D02*
X1455058Y946591D01*
G01X1445819Y954016D02*
X1447657Y952969D01*
G01X1449520Y954016D02*
X1451357Y952969D01*
G01X1451370Y957205D02*
X1453208Y956158D01*
G01X1442118Y960394D02*
X1443956Y959347D01*
G01X1445819Y960394D02*
X1447657Y959347D01*
G01X1442118Y966772D02*
X1443956Y965725D01*
G01X1440268Y963583D02*
X1442106Y962536D01*
G01X1440268Y969961D02*
X1442106Y968914D01*
G01X1449520Y960394D02*
X1451357Y959347D01*
G01X1451370Y963583D02*
X1453208Y962536D01*
G01X1451370Y969961D02*
X1453208Y968914D01*
G01X1453220Y966772D02*
X1455058Y965725D01*
G01X1453220Y960394D02*
X1455058Y959347D01*
G01X1445819Y966772D02*
X1447657Y965725D01*
G01X1449520Y966772D02*
X1451357Y965725D01*
G01X1443968Y982717D02*
X1445806Y981670D01*
G01X1442118Y979528D02*
X1443956Y978481D01*
G01X1442118Y973150D02*
X1443956Y972103D01*
G01X1445819Y973150D02*
X1447657Y972103D01*
G01X1440268Y976339D02*
X1442106Y975292D01*
G01X1442118Y985906D02*
X1443956Y984859D01*
G01X1451370Y982717D02*
X1453208Y981670D01*
G01X1449520Y973150D02*
X1451357Y972103D01*
G01X1451370Y976339D02*
X1453208Y975292D01*
G01X1449520Y985906D02*
X1451357Y984859D01*
G01X1453220Y979528D02*
X1455058Y978481D01*
G01X1453220Y973150D02*
X1455058Y972103D01*
G01X1445819Y979528D02*
X1447657Y978481D01*
G01X1440268Y982717D02*
X1442106Y981670D01*
G01X1447669Y982717D02*
X1449507Y981670D01*
G01X1445819Y985906D02*
X1447657Y984859D01*
G01X1449520Y979528D02*
X1451357Y978481D01*
G01X1443968Y989095D02*
X1445806Y988048D01*
G01X1442118Y992284D02*
X1443956Y991237D01*
G01X1451370Y989095D02*
X1453208Y988048D01*
G01X1451370Y995473D02*
X1453208Y994426D01*
G01X1449520Y992284D02*
X1451357Y991237D01*
G01X1453220Y985906D02*
X1455058Y984859D01*
G01X1447669Y989095D02*
X1449507Y988048D01*
G01X1453220Y998662D02*
X1455058Y997615D01*
G01X1453220Y992284D02*
X1455058Y991237D01*
G01X1440268Y989095D02*
X1442106Y988048D01*
G01X1445819Y992284D02*
X1447657Y991237D01*
G01X1451370Y1001851D02*
X1453208Y1000804D01*
G01X1451370Y1008229D02*
X1453208Y1007182D01*
G01X1453220Y1011418D02*
X1455058Y1010371D01*
G01X1453220Y1005040D02*
X1455058Y1003993D01*
G01X1452551Y1030197D02*
X1454389Y1031244D01*
G01X1452551Y1036575D02*
X1454389Y1037622D01*
G01X1452551Y1042953D02*
X1454389Y1044000D01*
G01X1443299Y1046142D02*
X1445137Y1047189D01*
G01X1445149Y1055709D02*
X1446987Y1056756D01*
G01X1443299Y1058898D02*
X1445137Y1059945D01*
G01X1443299Y1052520D02*
X1445137Y1053567D01*
G01X1445149Y1049331D02*
X1446987Y1050378D01*
G01X1450701Y1046142D02*
X1452539Y1047189D01*
G01X1450701Y1052520D02*
X1452539Y1053567D01*
G01X1452551Y1055709D02*
X1454389Y1056756D01*
G01X1452551Y1049331D02*
X1454389Y1050378D01*
G01X1448850Y1049331D02*
X1450688Y1050378D01*
G01X1447000Y1046142D02*
X1448838Y1047189D01*
G01X1439598Y1046142D02*
X1441436Y1047189D01*
G01X1450701Y1058898D02*
X1452539Y1059945D01*
G01X1447000Y1058898D02*
X1448838Y1059945D01*
G01X1441449Y1049331D02*
X1443287Y1050378D01*
G01X1447000Y1052520D02*
X1448838Y1053567D01*
G01X1441449Y1055709D02*
X1443287Y1056756D01*
G01X1439598Y1052520D02*
X1441436Y1053567D01*
G01X1439598Y1058898D02*
X1441436Y1059945D01*
G01X1448850Y1055709D02*
X1450688Y1056756D01*
G01X1441449Y1062087D02*
X1443287Y1063134D01*
G01X1443299Y1071654D02*
X1445137Y1072701D01*
G01X1441449Y1068465D02*
X1443287Y1069512D01*
G01X1447000Y1065276D02*
X1448838Y1066323D01*
G01X1443299Y1065276D02*
X1445137Y1066323D01*
G01X1439598Y1065276D02*
X1441436Y1066323D01*
G01X1450701Y1065276D02*
X1452539Y1066323D01*
G01X1452551Y1062087D02*
X1454389Y1063134D01*
G01X1452551Y1068465D02*
X1454389Y1069512D01*
G01X1441449Y1074843D02*
X1443287Y1075890D01*
G01X1452551Y1074843D02*
X1454389Y1075890D01*
G01X1450701Y1071654D02*
X1452539Y1072701D01*
G01X1447000Y1071654D02*
X1448838Y1072701D01*
G01X1439598Y1071654D02*
X1441436Y1072701D01*
G01X1443299Y1078032D02*
X1445137Y1079079D01*
G01X1447000Y1078032D02*
X1448838Y1079079D01*
G01X1439598Y1078032D02*
X1441436Y1079079D01*
G01X1441449Y1087599D02*
X1443287Y1088646D01*
G01X1443299Y1084410D02*
X1445137Y1085457D01*
G01X1441449Y1081221D02*
X1443287Y1082268D01*
G01X1450701Y1078032D02*
X1452539Y1079079D01*
G01X1452551Y1087599D02*
X1454389Y1088646D01*
G01X1452551Y1081221D02*
X1454389Y1082268D01*
G01X1450701Y1084410D02*
X1452539Y1085457D01*
G01X1439598Y1084410D02*
X1441436Y1085457D01*
G01X1447000Y1084410D02*
X1448838Y1085457D01*
G01X1439598Y1090788D02*
X1441436Y1091835D01*
G01X1447000Y1090788D02*
X1448838Y1091835D01*
G01X1443299Y1090788D02*
X1445137Y1091835D01*
G01X1441449Y1093977D02*
X1443287Y1095024D01*
G01X1443299Y1103544D02*
X1445137Y1104591D01*
G01X1441449Y1100355D02*
X1443287Y1101402D01*
G01X1443299Y1097166D02*
X1445137Y1098213D01*
G01X1439598Y1103544D02*
X1441436Y1104591D01*
G01X1450701Y1090788D02*
X1452539Y1091835D01*
G01X1452551Y1093977D02*
X1454389Y1095024D01*
G01X1450701Y1097166D02*
X1452539Y1098213D01*
G01X1439598Y1097166D02*
X1441436Y1098213D01*
G01X1447000Y1097166D02*
X1448838Y1098213D01*
G01X1439598Y1109922D02*
X1441436Y1110969D01*
G01X1447000Y1109922D02*
X1448838Y1110969D01*
G01X1443299Y1109922D02*
X1445137Y1110969D01*
G01X1441449Y1106733D02*
X1443287Y1107780D01*
G01X1443299Y1116300D02*
X1445137Y1117347D01*
G01X1441449Y1113111D02*
X1443287Y1114158D01*
G01X1450701Y1109922D02*
X1452539Y1110969D01*
G01X1452551Y1106733D02*
X1454389Y1107780D01*
G01X1452551Y1113111D02*
X1454389Y1114158D01*
G01X1441449Y1119489D02*
X1443287Y1120536D01*
G01X1452551Y1119489D02*
X1454389Y1120536D01*
G01X1450701Y1116300D02*
X1452539Y1117347D01*
G01X1439598Y1116300D02*
X1441436Y1117347D01*
G01X1447000Y1116300D02*
X1448838Y1117347D01*
G01X1445149Y1106733D02*
X1446987Y1107780D01*
G01X1448850Y1106733D02*
X1450688Y1107780D01*
G01X1443299Y1122678D02*
X1445137Y1123725D01*
G01X1447000Y1122678D02*
X1448838Y1123725D01*
G01X1439598Y1122678D02*
X1441436Y1123725D01*
G01X1441449Y1125867D02*
X1443287Y1126914D01*
G01X1441449Y1132245D02*
X1443287Y1133292D01*
G01X1443299Y1129056D02*
X1445137Y1130102D01*
G01X1450701Y1122678D02*
X1452539Y1123725D01*
G01X1452551Y1125867D02*
X1454389Y1126914D01*
G01X1452551Y1132245D02*
X1454389Y1133292D01*
G01X1439598Y1129056D02*
X1441436Y1130102D01*
G01X1447000Y1129056D02*
X1448838Y1130102D01*
G01X1450701Y1129056D02*
X1452539Y1130103D01*
G01X1447000Y1148189D02*
X1448838Y1149236D01*
G01X1441449Y1145000D02*
X1443287Y1146047D01*
G01X1439598Y1148189D02*
X1441436Y1149236D01*
G01X1450701Y1135433D02*
X1452539Y1136480D01*
G01X1450701Y1148189D02*
X1452539Y1149236D01*
G01X1443299Y1141811D02*
X1445137Y1142858D01*
G01X1441449Y1138622D02*
X1443287Y1139669D01*
G01X1443299Y1135433D02*
X1445137Y1136480D01*
G01X1447000Y1135433D02*
X1448838Y1136480D01*
G01X1439598Y1135433D02*
X1441436Y1136480D01*
G01X1452551Y1138622D02*
X1454389Y1139669D01*
G01X1452551Y1145000D02*
X1454389Y1146047D01*
G01X1450701Y1141811D02*
X1452539Y1142858D01*
G01X1443299Y1148189D02*
X1445137Y1149236D01*
G01X1439598Y1141811D02*
X1441436Y1142858D01*
G01X1447000Y1141811D02*
X1448838Y1142858D01*
G01X1445149Y1157756D02*
X1446987Y1158803D01*
G01X1448850Y1151378D02*
X1450688Y1152425D01*
G01D02*
X1450701Y1154567D01*
G01X1439598D02*
X1441436Y1155614D01*
G01X1443299Y1160945D02*
X1445137Y1161992D01*
G01X1439598Y1160945D02*
X1441436Y1161992D01*
G01X1452539D02*
X1450701Y1160945D01*
G01X1441449Y1151378D02*
X1443287Y1152425D01*
G01X1452551Y1151378D02*
X1454389Y1152425D01*
G01X1455071Y874292D02*
X1456909Y873245D01*
G01X1455071Y880670D02*
X1456909Y879623D01*
G01X1456921Y877481D02*
X1458759Y876434D01*
G01X1466173Y880670D02*
X1468011Y879623D01*
G01X1468023Y877481D02*
X1469861Y876434D01*
G01X1460622Y877481D02*
X1462460Y876434D01*
G01X1464323Y877481D02*
X1466161Y876434D01*
G01X1460622Y883859D02*
X1462460Y882812D01*
G01X1464323Y883859D02*
X1466161Y882812D01*
G01X1456921Y883859D02*
X1458759Y882812D01*
G01X1456921Y890237D02*
X1458759Y889190D01*
G01X1462472Y893426D02*
X1464310Y892379D01*
G01X1464323Y896615D02*
X1466161Y895568D01*
G01X1460622Y890237D02*
X1462460Y889190D01*
G01X1468023Y883859D02*
X1469861Y882812D01*
G01X1468023Y890237D02*
X1469861Y889190D01*
G01X1462472Y887048D02*
X1464310Y886001D01*
G01X1456921Y896615D02*
X1458759Y895568D01*
G01X1460622Y896615D02*
X1462460Y895568D01*
G01X1464323Y890237D02*
X1466161Y889190D01*
G01X1462472Y899804D02*
X1464310Y898757D01*
G01X1456921Y902993D02*
X1458759Y901946D01*
G01X1464323Y902993D02*
X1466161Y901946D01*
G01X1460622Y902993D02*
X1462460Y901946D01*
G01X1462472Y906181D02*
X1464310Y905134D01*
G01X1462472Y912559D02*
X1464310Y911512D01*
G01X1468023Y902993D02*
X1469861Y901946D01*
G01X1464323Y909370D02*
X1466161Y908323D01*
G01X1468023Y896615D02*
X1469861Y895568D01*
G01X1468023Y909370D02*
X1469861Y908324D01*
G01X1456921Y909370D02*
X1458759Y908324D01*
G01X1460622Y909370D02*
X1462460Y908324D01*
G01X1456921Y915748D02*
X1458759Y914701D01*
G01X1462472Y918937D02*
X1464310Y917890D01*
G01X1462472Y925315D02*
X1464310Y924268D01*
G01X1464323Y922126D02*
X1466161Y921079D01*
G01X1460622Y915748D02*
X1462460Y914701D01*
G01X1464323Y915748D02*
X1466161Y914701D01*
G01X1468023Y915748D02*
X1469861Y914701D01*
G01X1468023Y922126D02*
X1469861Y921079D01*
G01X1456921Y922126D02*
X1458759Y921079D01*
G01X1460622Y922126D02*
X1462460Y921079D01*
G01X1456921Y928504D02*
X1458759Y927457D01*
G01X1464323Y928504D02*
X1466161Y927457D01*
G01X1460622Y928504D02*
X1462460Y927457D01*
G01X1462472Y931693D02*
X1464310Y930646D01*
G01X1460622Y934882D02*
X1462460Y933835D01*
G01X1464323Y934882D02*
X1466161Y933835D01*
G01X1456921Y934882D02*
X1458759Y933835D01*
G01X1464323Y941260D02*
X1466161Y940213D01*
G01X1468023Y934882D02*
X1469861Y933835D01*
G01X1468023Y928504D02*
X1469861Y927457D01*
G01X1460622Y941260D02*
X1462460Y940213D01*
G01X1456921Y941260D02*
X1458759Y940213D01*
G01X1460622Y947638D02*
X1462460Y946591D01*
G01X1464323Y947638D02*
X1466161Y946591D01*
G01X1456921Y947638D02*
X1458759Y946591D01*
G01X1464323Y954016D02*
X1466161Y952969D01*
G01X1462472Y957205D02*
X1464310Y956158D01*
G01X1462472Y944449D02*
X1464310Y943402D01*
G01X1462472Y950827D02*
X1464310Y949780D01*
G01X1468023Y947638D02*
X1469861Y946591D01*
G01X1468023Y954016D02*
X1469861Y952969D01*
G01X1468023Y941260D02*
X1469861Y940213D01*
G01X1456921Y954016D02*
X1458759Y952969D01*
G01X1460622Y954016D02*
X1462460Y952969D01*
G01X1464323Y966772D02*
X1466161Y965725D01*
G01X1460622Y960394D02*
X1462460Y959347D01*
G01X1464323Y960394D02*
X1466161Y959347D01*
G01X1456921Y960394D02*
X1458759Y959347D01*
G01X1462472Y963583D02*
X1464310Y962536D01*
G01X1462472Y969961D02*
X1464310Y968914D01*
G01X1468023Y960394D02*
X1469861Y959347D01*
G01X1468023Y966772D02*
X1469861Y965725D01*
G01X1460622Y966772D02*
X1462460Y965725D01*
G01X1456921Y966772D02*
X1458759Y965725D01*
G01X1458771Y982717D02*
X1460609Y981670D01*
G01X1464323Y979528D02*
X1466161Y978481D01*
G01X1460622Y973150D02*
X1462460Y972103D01*
G01X1464323Y973150D02*
X1466161Y972103D01*
G01X1456921Y973150D02*
X1458759Y972103D01*
G01X1462472Y976339D02*
X1464310Y975292D01*
G01X1456921Y985906D02*
X1458759Y984859D01*
G01X1464323Y985906D02*
X1466161Y984859D01*
G01X1466173Y982717D02*
X1468011Y981670D01*
G01X1468023Y973150D02*
X1469861Y972103D01*
G01X1468023Y979528D02*
X1469861Y978481D01*
G01X1460622Y979528D02*
X1462460Y978481D01*
G01X1456921Y979528D02*
X1458759Y978481D01*
G01X1462472Y982717D02*
X1464310Y981670D01*
G01X1455071Y982717D02*
X1456909Y981670D01*
G01X1460622Y985906D02*
X1462460Y984859D01*
G01X1456921Y998662D02*
X1458759Y997615D01*
G01X1464323Y998662D02*
X1466161Y997615D01*
G01X1458771Y989095D02*
X1460609Y988048D01*
G01X1458771Y995473D02*
X1460609Y994426D01*
G01X1456921Y992284D02*
X1458759Y991237D01*
G01X1464323Y992284D02*
X1466161Y991237D01*
G01X1458771Y1001851D02*
X1460609Y1000804D01*
G01X1466173Y989095D02*
X1468011Y988048D01*
G01X1466173Y995473D02*
X1468011Y994426D01*
G01X1468023Y985906D02*
X1469861Y984859D01*
G01X1462472Y989095D02*
X1464310Y988048D01*
G01X1468023Y998662D02*
X1469861Y997615D01*
G01X1468023Y992284D02*
X1469861Y991237D01*
G01X1462472Y995473D02*
X1464310Y994426D01*
G01X1455071Y989095D02*
X1456909Y988048D01*
G01X1455071Y995473D02*
X1456909Y994426D01*
G01X1460622Y998662D02*
X1462460Y997615D01*
G01X1460622Y992284D02*
X1462460Y991237D01*
G01X1455071Y1001851D02*
X1456909Y1000804D01*
G01X1462472Y1001851D02*
X1464310Y1000804D01*
G01X1466173Y1001851D02*
X1468011Y1000804D01*
G01X1456921Y1005040D02*
X1458759Y1003993D01*
G01X1464323Y1005040D02*
X1466161Y1003993D01*
G01X1464323Y1011418D02*
X1466161Y1010371D01*
G01X1456921Y1011418D02*
X1458759Y1010371D01*
G01X1458771Y1008229D02*
X1460609Y1007182D01*
G01X1466173Y1008229D02*
X1468011Y1007182D01*
G01X1468023Y1011418D02*
X1469861Y1010371D01*
G01X1468023Y1005040D02*
X1469861Y1003993D01*
G01X1462472Y1008229D02*
X1464310Y1007182D01*
G01X1455071Y1008229D02*
X1456909Y1007182D01*
G01X1460622Y1011418D02*
X1462460Y1010371D01*
G01X1460622Y1005040D02*
X1462460Y1003993D01*
G01X1461803Y1027008D02*
X1463641Y1028055D01*
G01X1454401Y1027008D02*
X1456239Y1028055D01*
G01X1456252Y1030197D02*
X1458090Y1031244D01*
G01X1463653Y1030197D02*
X1465491Y1031244D01*
G01X1467354Y1030197D02*
X1469192Y1031244D01*
G01X1459953Y1030197D02*
X1461791Y1031244D01*
G01X1458102Y1027008D02*
X1459940Y1028055D01*
G01X1465504Y1027008D02*
X1467342Y1028055D01*
G01X1458102Y1039764D02*
X1459940Y1040811D01*
G01X1461803Y1033386D02*
X1463641Y1034433D01*
G01X1454401Y1033386D02*
X1456239Y1034433D01*
G01X1465504Y1039764D02*
X1467342Y1040811D01*
G01X1459953Y1036575D02*
X1461791Y1037622D01*
G01X1459953Y1042953D02*
X1461791Y1044000D01*
G01X1467354Y1036575D02*
X1469192Y1037622D01*
G01X1467354Y1042953D02*
X1469192Y1044000D01*
G01X1454401Y1039764D02*
X1456239Y1040811D01*
G01X1461803Y1039764D02*
X1463641Y1040811D01*
G01X1463653Y1042953D02*
X1465491Y1044000D01*
G01X1463653Y1036575D02*
X1465491Y1037622D01*
G01X1456252Y1042953D02*
X1458090Y1044000D01*
G01X1456252Y1036575D02*
X1458090Y1037622D01*
G01X1458102Y1033386D02*
X1459940Y1034433D01*
G01X1465504Y1033386D02*
X1467342Y1034433D01*
G01X1458102Y1046142D02*
X1459940Y1047189D01*
G01X1454401Y1058898D02*
X1456239Y1059945D01*
G01X1458102Y1052520D02*
X1459940Y1053567D01*
G01X1459953Y1055709D02*
X1461791Y1056756D01*
G01X1459953Y1049331D02*
X1461791Y1050378D01*
G01X1465504Y1046142D02*
X1467342Y1047189D01*
G01X1465504Y1058898D02*
X1467342Y1059945D01*
G01X1465504Y1052520D02*
X1467342Y1053567D01*
G01X1467354Y1049331D02*
X1469192Y1050378D01*
G01X1467354Y1055709D02*
X1469192Y1056756D01*
G01X1463653Y1049331D02*
X1465491Y1050378D01*
G01X1454401Y1046142D02*
X1456239Y1047189D01*
G01X1461803Y1046142D02*
X1463641Y1047189D01*
G01X1458102Y1058898D02*
X1459940Y1059945D01*
G01X1456252Y1049331D02*
X1458090Y1050378D01*
G01X1463653Y1055709D02*
X1465491Y1056756D01*
G01X1461803Y1058898D02*
X1463641Y1059945D01*
G01X1456252Y1055709D02*
X1458090Y1056756D01*
G01X1461803Y1052520D02*
X1463641Y1053567D01*
G01X1454401Y1052520D02*
X1456239Y1053567D01*
G01X1463653Y1062087D02*
X1465491Y1063134D01*
G01X1454401Y1071654D02*
X1456239Y1072701D01*
G01X1458102Y1065276D02*
X1459940Y1066323D01*
G01X1461803Y1065276D02*
X1463641Y1066323D01*
G01X1463653Y1068465D02*
X1465491Y1069512D01*
G01X1454401Y1065276D02*
X1456239Y1066323D01*
G01X1465504Y1071654D02*
X1467342Y1072701D01*
G01X1465504Y1065276D02*
X1467342Y1066323D01*
G01X1463653Y1074843D02*
X1465491Y1075890D01*
G01X1458102Y1071654D02*
X1459940Y1072701D01*
G01X1461803Y1071654D02*
X1463641Y1072701D01*
G01X1458102Y1078032D02*
X1459940Y1079079D01*
G01X1461803Y1078032D02*
X1463641Y1079079D01*
G01X1454401Y1078032D02*
X1456239Y1079079D01*
G01X1463653Y1087599D02*
X1465491Y1088646D01*
G01X1454401Y1084410D02*
X1456239Y1085457D01*
G01X1463653Y1081221D02*
X1465491Y1082268D01*
G01X1465504Y1078032D02*
X1467342Y1079079D01*
G01X1465504Y1084410D02*
X1467342Y1085457D01*
G01X1458102Y1084410D02*
X1459940Y1085457D01*
G01X1461803Y1084410D02*
X1463641Y1085457D01*
G01X1454401Y1097166D02*
X1456239Y1098213D01*
G01X1465504Y1090788D02*
X1467342Y1091835D01*
G01X1465504Y1103544D02*
X1467342Y1104591D01*
G01X1465504Y1097166D02*
X1467342Y1098213D01*
G01X1461803Y1090788D02*
X1463641Y1091835D01*
G01X1458102Y1090788D02*
X1459940Y1091835D01*
G01X1454401Y1090788D02*
X1456239Y1091835D01*
G01X1463653Y1093977D02*
X1465491Y1095024D01*
G01X1458102Y1103544D02*
X1459940Y1104591D01*
G01X1461803Y1103544D02*
X1463641Y1104591D01*
G01X1454401Y1103544D02*
X1456239Y1104591D01*
G01X1458102Y1097166D02*
X1459940Y1098213D01*
G01X1461803Y1097166D02*
X1463641Y1098213D01*
G01X1463653Y1106733D02*
X1465491Y1107780D01*
G01X1461803Y1109922D02*
X1463641Y1110969D01*
G01X1458102Y1109922D02*
X1459940Y1110969D01*
G01X1454401Y1109922D02*
X1456239Y1110969D01*
G01X1454401Y1116300D02*
X1456239Y1117347D01*
G01X1463653Y1113111D02*
X1465491Y1114158D01*
G01X1465504Y1109922D02*
X1467342Y1110969D01*
G01X1465504Y1116300D02*
X1467342Y1117347D01*
G01X1463653Y1119489D02*
X1465491Y1120536D01*
G01X1461803Y1116300D02*
X1463641Y1117347D01*
G01X1458102Y1116300D02*
X1459940Y1117347D01*
G01X1463653Y1125867D02*
X1465491Y1126914D01*
G01X1458102Y1122678D02*
X1459940Y1123725D01*
G01X1461803Y1122678D02*
X1463641Y1123725D01*
G01X1454401Y1122678D02*
X1456239Y1123725D01*
G01X1454401Y1129056D02*
X1456239Y1130102D01*
G01X1463653Y1132245D02*
X1465491Y1133292D01*
G01X1465504Y1122678D02*
X1467342Y1123725D01*
G01X1465504Y1129056D02*
X1467342Y1130102D01*
G01X1461803Y1129056D02*
X1463641Y1130102D01*
G01X1458102Y1129056D02*
X1459940Y1130102D01*
G01X1454401Y1141811D02*
X1456239Y1142858D01*
G01X1463653Y1138622D02*
X1465491Y1139669D01*
G01X1458102Y1135433D02*
X1459940Y1136480D01*
G01X1461803Y1135433D02*
X1463641Y1136480D01*
G01X1454401Y1135433D02*
X1456239Y1136480D01*
G01X1463653Y1145000D02*
X1465491Y1146047D01*
G01X1458102Y1148189D02*
X1459940Y1149236D01*
G01X1461803Y1148189D02*
X1463641Y1149236D01*
G01X1465504Y1135433D02*
X1467342Y1136480D01*
G01X1465504Y1141811D02*
X1467342Y1142858D01*
G01X1465504Y1148189D02*
X1467342Y1149236D01*
G01X1454401Y1148189D02*
X1456239Y1149236D01*
G01X1458102Y1141811D02*
X1459940Y1142858D01*
G01X1461803Y1141811D02*
X1463641Y1142858D01*
G01X1461803Y1154567D02*
X1463641Y1155614D01*
G01X1459953Y1151378D02*
X1461791Y1152425D01*
G01X1456252Y1157756D02*
X1458090Y1158803D01*
G01X1467354Y1157756D02*
X1469192Y1158803D01*
G01X1454401Y1160945D02*
X1456239Y1161992D01*
G01X1461803Y1160945D02*
X1463641Y1161992D01*
G01X1465504Y1160945D02*
X1467342Y1161992D01*
G01X1463653Y1151378D02*
X1465491Y1152425D01*
G01X1477275Y874292D02*
X1479113Y873245D01*
G01X1477275Y880670D02*
X1479113Y879623D01*
G01X1482827Y877481D02*
X1484665Y876434D01*
G01X1480976Y880670D02*
X1482814Y879623D01*
G01X1471724Y877481D02*
X1473562Y876434D01*
G01X1475425Y877481D02*
X1477263Y876434D01*
G01X1480976Y887048D02*
X1482814Y886001D01*
G01X1479126Y883859D02*
X1480964Y882812D01*
G01X1477275Y887048D02*
X1479113Y886001D01*
G01X1480976Y893426D02*
X1482814Y892379D01*
G01X1471724Y890237D02*
X1473562Y889190D01*
G01X1473575Y893426D02*
X1475413Y892379D01*
G01X1475425Y896615D02*
X1477263Y895568D01*
G01X1482827Y883859D02*
X1484665Y882812D01*
G01X1473575Y887048D02*
X1475413Y886001D01*
G01X1475425Y890237D02*
X1477263Y889190D01*
G01X1471724Y896615D02*
X1473562Y895568D01*
G01X1480976Y899804D02*
X1482814Y898757D01*
G01X1473575Y899804D02*
X1475413Y898757D01*
G01X1471724Y902993D02*
X1473562Y901946D01*
G01X1480976Y906181D02*
X1482814Y905134D01*
G01X1475425Y909370D02*
X1477263Y908324D01*
G01X1473575Y912559D02*
X1475413Y911512D01*
G01X1473575Y906181D02*
X1475413Y905134D01*
G01X1471724Y909370D02*
X1473562Y908324D01*
G01X1475425Y902993D02*
X1477263Y901946D01*
G01X1480976Y912559D02*
X1482814Y911512D01*
G01X1480976Y918937D02*
X1482814Y917890D01*
G01X1471724Y915748D02*
X1473562Y914701D01*
G01X1473575Y918937D02*
X1475413Y917890D01*
G01X1473575Y925315D02*
X1475413Y924268D01*
G01X1480976Y925315D02*
X1482814Y924268D01*
G01X1475425Y922126D02*
X1477263Y921079D01*
G01X1471724Y922126D02*
X1473562Y921079D01*
G01X1475425Y915748D02*
X1477263Y914701D01*
G01X1471724Y934882D02*
X1473562Y933835D01*
G01X1480976Y931693D02*
X1482814Y930646D01*
G01X1473575Y931693D02*
X1475413Y930646D01*
G01X1475425Y934882D02*
X1477263Y933835D01*
G01X1471724Y928504D02*
X1473562Y927457D01*
G01X1480976Y938071D02*
X1482814Y937024D01*
G01X1475425Y941260D02*
X1477263Y940213D01*
G01X1471724Y941260D02*
X1473562Y940213D01*
G01X1475425Y928504D02*
X1477263Y927457D01*
G01X1473575Y938071D02*
X1475413Y937024D01*
G01X1480976Y944449D02*
X1482814Y943402D01*
G01X1480976Y950827D02*
X1482814Y949780D01*
G01X1473575Y944449D02*
X1475413Y943402D01*
G01X1471724Y947638D02*
X1473562Y946591D01*
G01X1473575Y950827D02*
X1475413Y949780D01*
G01X1475425Y954016D02*
X1477263Y952969D01*
G01X1473575Y957205D02*
X1475413Y956158D01*
G01X1471724Y954016D02*
X1473562Y952969D01*
G01X1475425Y947638D02*
X1477263Y946591D01*
G01X1480976Y957205D02*
X1482814Y956158D01*
G01X1480976Y963583D02*
X1482814Y962536D01*
G01X1471724Y960394D02*
X1473562Y959347D01*
G01X1473575Y963583D02*
X1475413Y962536D01*
G01X1475425Y966772D02*
X1477263Y965725D01*
G01X1480976Y969961D02*
X1482814Y968914D01*
G01X1473575Y969961D02*
X1475413Y968914D01*
G01X1471724Y966772D02*
X1473562Y965725D01*
G01X1475425Y960394D02*
X1477263Y959347D01*
G01X1480976Y976339D02*
X1482814Y975292D01*
G01X1480976Y982717D02*
X1482814Y981670D01*
G01X1471724Y973150D02*
X1473562Y972103D01*
G01X1473575Y976339D02*
X1475413Y975292D01*
G01X1475425Y979528D02*
X1477263Y978481D01*
G01X1473575Y982717D02*
X1475413Y981670D01*
G01X1471724Y985906D02*
X1473562Y984859D01*
G01X1469874Y982717D02*
X1471712Y981670D01*
G01X1471724Y979528D02*
X1473562Y978481D01*
G01X1475425Y973150D02*
X1477263Y972103D01*
G01X1475425Y985906D02*
X1477263Y984859D01*
G01X1482827Y985906D02*
X1484665Y984859D01*
G01X1473575Y1001851D02*
X1475413Y1000804D01*
G01X1480976Y989095D02*
X1482814Y988048D01*
G01X1480976Y995473D02*
X1482814Y994426D01*
G01X1471724Y992284D02*
X1473562Y991237D01*
G01X1471724Y998662D02*
X1473562Y997615D01*
G01X1473575Y989095D02*
X1475413Y988048D01*
G01X1473575Y995473D02*
X1475413Y994426D01*
G01X1475425Y992284D02*
X1477263Y991237D01*
G01X1469874Y989095D02*
X1471712Y988048D01*
G01X1469874Y995473D02*
X1471712Y994426D01*
G01X1475425Y998662D02*
X1477263Y997615D01*
G01X1469874Y1001851D02*
X1471712Y1000804D01*
G01X1480976Y1001851D02*
X1482814Y1000804D01*
G01X1480976Y1008229D02*
X1482814Y1007182D01*
G01X1471724Y1005040D02*
X1473562Y1003993D01*
G01X1471724Y1011418D02*
X1473562Y1010371D01*
G01X1473575Y1008229D02*
X1475413Y1007182D01*
G01X1469874Y1008229D02*
X1471712Y1007182D01*
G01X1475425Y1011418D02*
X1477263Y1010371D01*
G01X1475425Y1005040D02*
X1477263Y1003993D01*
G01X1476606Y1027008D02*
X1478444Y1028055D01*
G01X1469205Y1027008D02*
X1471043Y1028055D01*
G01X1471055Y1030197D02*
X1472893Y1031244D01*
G01X1482157Y1030197D02*
X1483995Y1031244D01*
G01X1472905Y1027008D02*
X1474743Y1028055D01*
G01X1474756Y1030197D02*
X1476594Y1031244D01*
G01X1476606Y1033386D02*
X1478444Y1034433D01*
G01X1474756Y1036575D02*
X1476594Y1037622D01*
G01X1472905Y1039764D02*
X1474743Y1040811D01*
G01X1474756Y1042953D02*
X1476594Y1044000D01*
G01X1469205Y1033386D02*
X1471043Y1034433D01*
G01X1482157Y1036575D02*
X1483995Y1037622D01*
G01X1482157Y1042953D02*
X1483995Y1044000D01*
G01X1471055Y1042953D02*
X1472893Y1044000D01*
G01X1471055Y1036575D02*
X1472893Y1037622D01*
G01X1469205Y1039764D02*
X1471043Y1040811D01*
G01X1476606Y1039764D02*
X1478444Y1040811D01*
G01X1472905Y1033386D02*
X1474743Y1034433D01*
G01X1472905Y1046142D02*
X1474743Y1047189D01*
G01X1478457Y1055709D02*
X1480295Y1056756D01*
G01X1480307Y1058898D02*
X1482145Y1059945D01*
G01X1474756Y1049331D02*
X1476594Y1050378D01*
G01X1474756Y1055709D02*
X1476594Y1056756D01*
G01X1472905Y1052520D02*
X1474743Y1053567D01*
G01X1476606Y1058898D02*
X1478444Y1059945D01*
G01X1482157Y1049331D02*
X1483995Y1050378D01*
G01X1482157Y1055709D02*
X1483995Y1056756D01*
G01X1471055Y1049331D02*
X1472893Y1050378D01*
G01X1476606Y1052520D02*
X1478444Y1053567D01*
G01X1469205Y1046142D02*
X1471043Y1047189D01*
G01X1476606Y1046142D02*
X1478444Y1047189D01*
G01X1469205Y1058898D02*
X1471043Y1059945D01*
G01X1472905Y1058898D02*
X1474743Y1059945D01*
G01X1469205Y1052520D02*
X1471043Y1053567D01*
G01X1471055Y1055709D02*
X1472893Y1056756D01*
G01X1474756Y1062087D02*
X1476594Y1063134D01*
G01X1476606Y1071654D02*
X1478444Y1072701D01*
G01X1474756Y1068465D02*
X1476594Y1069512D01*
G01X1472905Y1065276D02*
X1474743Y1066323D01*
G01X1469205Y1065276D02*
X1471043Y1066323D01*
G01X1482157Y1062087D02*
X1483995Y1063134D01*
G01X1482157Y1068465D02*
X1483995Y1069512D01*
G01X1474756Y1074843D02*
X1476594Y1075890D01*
G01X1482157Y1074843D02*
X1483995Y1075890D01*
G01X1476606Y1065276D02*
X1478444Y1066323D01*
G01X1472905Y1071654D02*
X1474743Y1072701D01*
G01X1469205Y1071654D02*
X1471043Y1072701D01*
G01X1472905Y1078032D02*
X1474743Y1079079D01*
G01X1469205Y1078032D02*
X1471043Y1079079D01*
G01X1476606Y1084410D02*
X1478444Y1085457D01*
G01X1474756Y1087599D02*
X1476594Y1088646D01*
G01X1474756Y1081221D02*
X1476594Y1082268D01*
G01X1482157Y1087599D02*
X1483995Y1088646D01*
G01X1482157Y1081221D02*
X1483995Y1082268D01*
G01X1476606Y1078032D02*
X1478444Y1079079D01*
G01X1469205Y1084410D02*
X1471043Y1085457D01*
G01X1472905Y1084410D02*
X1474743Y1085457D01*
G01X1472905Y1090788D02*
X1474743Y1091835D01*
G01X1469205Y1090788D02*
X1471043Y1091835D01*
G01X1474756Y1093977D02*
X1476594Y1095024D01*
G01X1476606Y1097166D02*
X1478444Y1098213D01*
G01X1476606Y1103544D02*
X1478444Y1104591D01*
G01X1472905Y1103544D02*
X1474743Y1104591D01*
G01X1469205Y1103544D02*
X1471043Y1104591D01*
G01X1471055Y1100355D02*
X1472893Y1101402D01*
G01X1482157Y1093977D02*
X1483995Y1095024D01*
G01X1482157Y1100355D02*
X1483995Y1101402D01*
G01X1476606Y1090788D02*
X1478444Y1091835D01*
G01X1474756Y1100355D02*
X1476594Y1101402D01*
G01X1469205Y1097166D02*
X1471043Y1098213D01*
G01X1472905Y1097166D02*
X1474743Y1098213D01*
G01X1474756Y1106733D02*
X1476594Y1107780D01*
G01X1472905Y1109922D02*
X1474743Y1110969D01*
G01X1469205Y1109922D02*
X1471043Y1110969D01*
G01X1474756Y1113111D02*
X1476594Y1114158D01*
G01X1476606Y1116300D02*
X1478444Y1117347D01*
G01X1482157Y1106733D02*
X1483995Y1107780D01*
G01X1482157Y1113111D02*
X1483995Y1114158D01*
G01X1474756Y1119489D02*
X1476594Y1120536D01*
G01X1482157Y1119489D02*
X1483995Y1120536D01*
G01X1476606Y1109922D02*
X1478444Y1110969D01*
G01X1469205Y1116300D02*
X1471043Y1117347D01*
G01X1472905Y1116300D02*
X1474743Y1117347D01*
G01X1474756Y1125867D02*
X1476594Y1126914D01*
G01X1472905Y1122678D02*
X1474743Y1123725D01*
G01X1469205Y1122678D02*
X1471043Y1123725D01*
G01X1476606Y1129056D02*
X1478444Y1130102D01*
G01X1474756Y1132245D02*
X1476594Y1133292D01*
G01X1482157Y1125867D02*
X1483995Y1126914D01*
G01X1482157Y1132245D02*
X1483995Y1133292D01*
G01X1476606Y1122678D02*
X1478444Y1123725D01*
G01X1469205Y1129056D02*
X1471043Y1130102D01*
G01X1472905Y1129056D02*
X1474743Y1130102D01*
G01X1474756Y1138622D02*
X1476594Y1139669D01*
G01X1472905Y1135433D02*
X1474743Y1136480D01*
G01X1469205Y1135433D02*
X1471043Y1136480D01*
G01X1476606Y1141811D02*
X1478444Y1142858D01*
G01X1474756Y1145000D02*
X1476594Y1146047D01*
G01X1472905Y1148189D02*
X1474743Y1149236D01*
G01X1469205Y1148189D02*
X1471043Y1149236D01*
G01X1482157Y1138622D02*
X1483995Y1139669D01*
G01X1482157Y1145000D02*
X1483995Y1146047D01*
G01X1476606Y1135433D02*
X1478444Y1136480D01*
G01X1469205Y1141811D02*
X1471043Y1142858D01*
G01X1476606Y1148189D02*
X1478444Y1149236D01*
G01X1472905Y1141811D02*
X1474743Y1142858D01*
G01X1472905Y1154567D02*
X1474743Y1155614D01*
G01X1476606Y1154567D02*
X1478444Y1155614D01*
G01X1471055Y1151378D02*
X1472893Y1152425D01*
G01X1478457Y1157756D02*
X1480295Y1158803D01*
G01X1482157Y1151378D02*
X1483995Y1152425D01*
G01X1482157Y1157756D02*
X1483995Y1158803D01*
G01X1472905Y1160945D02*
X1474743Y1161992D01*
G01X1476606Y1160945D02*
X1478444Y1161992D01*
G01X1474756Y1151378D02*
X1476594Y1152425D01*
G01X1490228Y877481D02*
X1492066Y876434D01*
G01X1486527Y877481D02*
X1488365Y876434D01*
G01X1488378Y887048D02*
X1490216Y886001D01*
G01X1486527Y883859D02*
X1488365Y882812D01*
G01X1493929Y883859D02*
X1495767Y882812D01*
G01X1492079Y887048D02*
X1493917Y886001D01*
G01X1486527Y890237D02*
X1488365Y889190D01*
G01X1493929Y890237D02*
X1495767Y889190D01*
G01X1488378Y893426D02*
X1490216Y892379D01*
G01X1493929Y896615D02*
X1495767Y895568D01*
G01X1497630Y883859D02*
X1499468Y882812D01*
G01X1486527Y896615D02*
X1488365Y895568D01*
G01X1488378Y899804D02*
X1490216Y898757D01*
G01X1486527Y902993D02*
X1488365Y901946D01*
G01X1493929Y902993D02*
X1495767Y901946D01*
G01X1486527Y909370D02*
X1488365Y908324D01*
G01X1488378Y912559D02*
X1490216Y911512D01*
G01X1493929Y909370D02*
X1495767Y908324D01*
G01X1488378Y906181D02*
X1490216Y905134D01*
G01X1493929Y915748D02*
X1495767Y914701D01*
G01X1488378Y918937D02*
X1490216Y917890D01*
G01X1486527Y922126D02*
X1488365Y921079D01*
G01X1493929Y922126D02*
X1495767Y921079D01*
G01X1486527Y915748D02*
X1488365Y914701D01*
G01X1488378Y925315D02*
X1490216Y924268D01*
G01X1488378Y931693D02*
X1490216Y930646D01*
G01X1493929Y934882D02*
X1495767Y933835D01*
G01X1486527Y928504D02*
X1488365Y927457D01*
G01X1493929Y928504D02*
X1495767Y927457D01*
G01X1486527Y941260D02*
X1488365Y940213D01*
G01X1493929Y941260D02*
X1495767Y940213D01*
G01X1488378Y938071D02*
X1490216Y937024D01*
G01X1486527Y934882D02*
X1488365Y933835D01*
G01X1486527Y947638D02*
X1488365Y946591D01*
G01X1488378Y950827D02*
X1490216Y949780D01*
G01X1493929Y947638D02*
X1495767Y946591D01*
G01X1493929Y954016D02*
X1495767Y952969D01*
G01X1488378Y957205D02*
X1490216Y956158D01*
G01X1488378Y944449D02*
X1490216Y943402D01*
G01X1486527Y954016D02*
X1488365Y952969D01*
G01X1486527Y966772D02*
X1488365Y965725D01*
G01X1493929Y960394D02*
X1495767Y959347D01*
G01X1493929Y966772D02*
X1495767Y965725D01*
G01X1486527Y960394D02*
X1488365Y959347D01*
G01X1488378Y969961D02*
X1490216Y968914D01*
G01X1488378Y963583D02*
X1490216Y962536D01*
G01X1493929Y973150D02*
X1495767Y972103D01*
G01X1488378Y976339D02*
X1490216Y975292D01*
G01X1484677Y982717D02*
X1486515Y981670D01*
G01X1486527Y979528D02*
X1488365Y978481D01*
G01X1493929Y979528D02*
X1495767Y978481D01*
G01X1495779Y982717D02*
X1497617Y981670D01*
G01X1486527Y985906D02*
X1488365Y984859D01*
G01X1493929Y985906D02*
X1495767Y984859D01*
G01X1497630Y985906D02*
X1499468Y984859D01*
G01X1488378Y982717D02*
X1490216Y981670D01*
G01X1486527Y973150D02*
X1488365Y972103D01*
G01X1488378Y989095D02*
X1490216Y988048D01*
G01X1486527Y998662D02*
X1488365Y997615D01*
G01X1488378Y995473D02*
X1490216Y994426D01*
G01X1493929Y992284D02*
X1495767Y991237D01*
G01X1493929Y998662D02*
X1495767Y997615D01*
G01X1486527Y992284D02*
X1488365Y991237D01*
G01X1488378Y1001851D02*
X1490216Y1000804D01*
G01X1486527Y1005040D02*
X1488365Y1003993D01*
G01X1488378Y1008229D02*
X1490216Y1007182D01*
G01X1493929Y1005040D02*
X1495767Y1003993D01*
G01X1493929Y1011418D02*
X1495767Y1010371D01*
G01X1486527Y1011418D02*
X1488365Y1010371D01*
G01X1487709Y1027008D02*
X1489547Y1028055D01*
G01X1495110Y1027008D02*
X1496948Y1028055D01*
G01X1489559Y1030197D02*
X1491397Y1031244D01*
G01X1487709Y1039764D02*
X1489547Y1040811D01*
G01X1487709Y1033386D02*
X1489547Y1034433D01*
G01X1489559Y1042953D02*
X1491397Y1044000D01*
G01X1495110Y1033386D02*
X1496948Y1034433D01*
G01X1495110Y1039764D02*
X1496948Y1040811D01*
G01X1489559Y1036575D02*
X1491397Y1037622D01*
G01X1495110Y1046142D02*
X1496948Y1047189D01*
G01X1487709Y1052520D02*
X1489547Y1053567D01*
G01X1493260Y1055709D02*
X1495098Y1056756D01*
G01X1489559Y1049331D02*
X1491397Y1050378D01*
G01X1487709Y1058898D02*
X1489547Y1059945D01*
G01X1491409Y1058898D02*
X1493247Y1059945D01*
G01X1495110Y1052520D02*
X1496948Y1053567D01*
G01X1495110Y1058898D02*
X1496948Y1059945D01*
G01X1489559Y1055709D02*
X1491397Y1056756D01*
G01X1487709Y1046142D02*
X1489547Y1047189D01*
G01X1489559Y1062087D02*
X1491397Y1063134D01*
G01X1487709Y1071654D02*
X1489547Y1072701D01*
G01X1489559Y1068465D02*
X1491397Y1069512D01*
G01X1495110Y1071654D02*
X1496948Y1072701D01*
G01X1495110Y1065276D02*
X1496948Y1066323D01*
G01X1487709Y1065276D02*
X1489547Y1066323D01*
G01X1489559Y1074843D02*
X1491397Y1075890D01*
G01X1487709Y1078032D02*
X1489547Y1079079D01*
G01X1495110Y1078032D02*
X1496948Y1079079D01*
G01X1489559Y1087599D02*
X1491397Y1088646D01*
G01X1495110Y1084410D02*
X1496948Y1085457D01*
G01X1489559Y1081221D02*
X1491397Y1082268D01*
G01X1487709Y1084410D02*
X1489547Y1085457D01*
G01X1487709Y1090788D02*
X1489547Y1091835D01*
G01X1495110Y1090788D02*
X1496948Y1091835D01*
G01X1487709Y1097166D02*
X1489547Y1098213D01*
G01X1489559Y1100355D02*
X1491397Y1101402D01*
G01X1495110Y1097166D02*
X1496948Y1098213D01*
G01X1495110Y1103544D02*
X1496948Y1104591D01*
G01X1487709Y1103544D02*
X1489547Y1104591D01*
G01X1489559Y1093977D02*
X1491397Y1095024D01*
G01X1487709Y1109922D02*
X1489547Y1110969D01*
G01X1495110Y1109922D02*
X1496948Y1110969D01*
G01X1489559Y1106733D02*
X1491397Y1107780D01*
G01X1487709Y1116300D02*
X1489547Y1117347D01*
G01X1495110Y1116300D02*
X1496948Y1117347D01*
G01X1489559Y1119489D02*
X1491397Y1120536D01*
G01X1489559Y1113111D02*
X1491397Y1114158D01*
G01X1495110Y1122678D02*
X1496948Y1123725D01*
G01X1489559Y1125867D02*
X1491397Y1126914D01*
G01X1495110Y1129056D02*
X1496948Y1130102D01*
G01X1487709Y1129056D02*
X1489547Y1130103D01*
G01X1487709Y1122678D02*
X1489547Y1123725D01*
G01X1489559Y1132245D02*
X1491397Y1133292D01*
G01X1487709Y1135433D02*
X1489547Y1136480D01*
G01X1489559Y1138622D02*
X1491397Y1139669D01*
G01X1495110Y1135433D02*
X1496948Y1136480D01*
G01X1495110Y1141811D02*
X1496948Y1142858D01*
G01X1487709Y1148189D02*
X1489547Y1149236D01*
G01X1489559Y1145000D02*
X1491397Y1146047D01*
G01X1495110Y1148189D02*
X1496948Y1149236D01*
G01X1487709Y1141811D02*
X1489547Y1142858D01*
G01X1485858Y1164134D02*
X1487696Y1165181D01*
G01X1496960Y1157756D02*
X1498799Y1158803D01*
G01X1484008Y1154567D02*
X1485846Y1155614D01*
G01X1487709Y1154567D02*
X1489547Y1155614D01*
G01X1491409Y1154567D02*
X1493247Y1155614D01*
G01X1495110Y1154567D02*
X1496948Y1155614D01*
G01X1489559Y1157756D02*
X1491397Y1158803D01*
G01X1491409Y1160945D02*
X1493247Y1161992D01*
G01X1489559Y1151378D02*
X1491397Y1152425D01*
G01X1485858Y1157756D02*
X1487696Y1158803D01*
G01X1484008Y1160945D02*
X1485846Y1161992D01*
G01X1487709Y1160945D02*
X1489547Y1161992D01*
G01X1499480Y874292D02*
X1501318Y873245D01*
G01X1499480Y880670D02*
X1501318Y879623D01*
G01X1508732Y877481D02*
X1510570Y876434D01*
G01X1506882Y880670D02*
X1508720Y879623D01*
G01X1499480Y887048D02*
X1501318Y886001D01*
G01X1508732Y883859D02*
X1510570Y882812D01*
G01X1506882Y887048D02*
X1508720Y886001D01*
G01X1501331Y890237D02*
X1503169Y889190D01*
G01X1501331Y896615D02*
X1503169Y895568D01*
G01X1499480Y893426D02*
X1501318Y892379D01*
G01X1506882Y893426D02*
X1508720Y892379D01*
G01X1503181Y887048D02*
X1505019Y886001D01*
G01X1512433Y883859D02*
X1514271Y882812D01*
G01X1512433Y890237D02*
X1514271Y889190D01*
G01X1499480Y899804D02*
X1501318Y898757D01*
G01X1506882Y899804D02*
X1508720Y898757D01*
G01X1501331Y902993D02*
X1503169Y901946D01*
G01X1499480Y906181D02*
X1501318Y905134D01*
G01X1506882Y906181D02*
X1508720Y905134D01*
G01X1499480Y912559D02*
X1501318Y911512D01*
G01X1506882Y912559D02*
X1508720Y911512D01*
G01X1512433Y902993D02*
X1514271Y901946D01*
G01X1512433Y909370D02*
X1514271Y908324D01*
G01X1501331Y909370D02*
X1503169Y908323D01*
G01X1512433Y896615D02*
X1514271Y895568D01*
G01X1501331Y915748D02*
X1503169Y914701D01*
G01X1499480Y918937D02*
X1501318Y917890D01*
G01X1506882Y918937D02*
X1508720Y917890D01*
G01X1501331Y922126D02*
X1503169Y921079D01*
G01X1499480Y925315D02*
X1501318Y924268D01*
G01X1506882Y925315D02*
X1508720Y924268D01*
G01X1512433Y922126D02*
X1514271Y921079D01*
G01X1512433Y915748D02*
X1514271Y914701D01*
G01X1501331Y928504D02*
X1503169Y927457D01*
G01X1499480Y931693D02*
X1501318Y930646D01*
G01X1501331Y934882D02*
X1503169Y933835D01*
G01X1506882Y931693D02*
X1508720Y930646D01*
G01X1506882Y938071D02*
X1508720Y937024D01*
G01X1501331Y941260D02*
X1503169Y940213D01*
G01X1499480Y938071D02*
X1501318Y937024D01*
G01X1512433Y928504D02*
X1514271Y927457D01*
G01X1512433Y941260D02*
X1514271Y940213D01*
G01X1512433Y934882D02*
X1514271Y933835D01*
G01X1499480Y944449D02*
X1501318Y943402D01*
G01X1506882Y944449D02*
X1508720Y943402D01*
G01X1501331Y947638D02*
X1503169Y946591D01*
G01X1499480Y950827D02*
X1501318Y949780D01*
G01X1506882Y950827D02*
X1508720Y949780D01*
G01X1501331Y954016D02*
X1503169Y952969D01*
G01X1499480Y957205D02*
X1501318Y956158D01*
G01X1506882Y957205D02*
X1508720Y956158D01*
G01X1512433Y947638D02*
X1514271Y946591D01*
G01X1512433Y954016D02*
X1514271Y952969D01*
G01X1501331Y960394D02*
X1503169Y959347D01*
G01X1501331Y966772D02*
X1503169Y965725D01*
G01X1499480Y963583D02*
X1501318Y962536D01*
G01X1506882Y963583D02*
X1508720Y962536D01*
G01X1499480Y969961D02*
X1501318Y968914D01*
G01X1506882Y969961D02*
X1508720Y968914D01*
G01X1512433Y960394D02*
X1514271Y959347D01*
G01X1512433Y966772D02*
X1514271Y965725D01*
G01X1508732Y985906D02*
X1510570Y984859D01*
G01X1510583Y982717D02*
X1512421Y981670D01*
G01X1501331Y973150D02*
X1503169Y972103D01*
G01X1499480Y976339D02*
X1501318Y975292D01*
G01X1501331Y979528D02*
X1503169Y978481D01*
G01X1499480Y982717D02*
X1501318Y981670D01*
G01X1506882Y976339D02*
X1508720Y975292D01*
G01X1506882Y982717D02*
X1508720Y981670D01*
G01X1501331Y985906D02*
X1503169Y984859D01*
G01X1512433Y979528D02*
X1514271Y978481D01*
G01X1512433Y985906D02*
X1514271Y984859D01*
G01X1512433Y973150D02*
X1514271Y972103D01*
G01X1501331Y992284D02*
X1503169Y991237D01*
G01X1499480Y989095D02*
X1501318Y988048D01*
G01X1501331Y998662D02*
X1503169Y997615D01*
G01X1499480Y995473D02*
X1501318Y994426D01*
G01X1506882Y989095D02*
X1508720Y988048D01*
G01X1506882Y995473D02*
X1508720Y994426D01*
G01X1499480Y1001851D02*
X1501318Y1000804D01*
G01X1506882Y1001851D02*
X1508720Y1000804D01*
G01X1512433Y998662D02*
X1514271Y997615D01*
G01X1512433Y992284D02*
X1514271Y991237D01*
G01X1499480Y1008229D02*
X1501318Y1007182D01*
G01X1501331Y1011418D02*
X1503169Y1010371D01*
G01X1506882Y1008229D02*
X1508720Y1007182D01*
G01X1501331Y1005040D02*
X1503169Y1003993D01*
G01X1512433Y1005040D02*
X1514271Y1003993D01*
G01X1512433Y1011418D02*
X1514271Y1010371D01*
G01X1502512Y1027008D02*
X1504350Y1028055D01*
G01X1500661Y1030197D02*
X1502499Y1031244D01*
G01X1508063Y1030197D02*
X1509901Y1031244D01*
G01X1502512Y1039764D02*
X1504350Y1040811D01*
G01X1500661Y1036575D02*
X1502499Y1037622D01*
G01X1502512Y1033386D02*
X1504350Y1034433D01*
G01X1500661Y1042953D02*
X1502499Y1044000D01*
G01X1508063Y1036575D02*
X1509901Y1037622D01*
G01X1508063Y1042953D02*
X1509901Y1044000D01*
G01X1502512Y1046142D02*
X1504350Y1047189D01*
G01X1502512Y1052520D02*
X1504350Y1053567D01*
G01X1500661Y1049331D02*
X1502499Y1050378D01*
G01X1508063Y1055709D02*
X1509901Y1056756D01*
G01X1508063Y1049331D02*
X1509901Y1050378D01*
G01X1502512Y1058898D02*
X1504350Y1059945D01*
G01X1506212Y1058898D02*
X1508050Y1059945D01*
G01X1504362Y1055709D02*
X1506200Y1056756D01*
G01X1500661Y1055709D02*
X1502499Y1056756D01*
G01X1500661Y1062087D02*
X1502499Y1063134D01*
G01X1508063Y1062087D02*
X1509901Y1063134D01*
G01X1500661Y1068465D02*
X1502499Y1069512D01*
G01X1502512Y1071654D02*
X1504350Y1072701D01*
G01X1502512Y1065276D02*
X1504350Y1066323D01*
G01X1508063Y1068465D02*
X1509901Y1069512D01*
G01X1500661Y1074843D02*
X1502499Y1075890D01*
G01X1508063Y1074843D02*
X1509901Y1075890D01*
G01X1502512Y1078032D02*
X1504350Y1079079D01*
G01X1502512Y1084410D02*
X1504350Y1085457D01*
G01X1500661Y1087599D02*
X1502499Y1088646D01*
G01X1508063Y1087599D02*
X1509901Y1088646D01*
G01X1500661Y1081221D02*
X1502499Y1082268D01*
G01X1508063Y1081221D02*
X1509901Y1082268D01*
G01X1502512Y1090788D02*
X1504350Y1091835D01*
G01X1500661Y1093977D02*
X1502499Y1095024D01*
G01X1508063Y1093977D02*
X1509901Y1095024D01*
G01X1502512Y1097166D02*
X1504350Y1098213D01*
G01X1500661Y1100355D02*
X1502499Y1101402D01*
G01X1508063Y1100355D02*
X1509901Y1101402D01*
G01X1502512Y1103544D02*
X1504350Y1104591D01*
G01X1500661Y1106733D02*
X1502499Y1107780D01*
G01X1508063Y1106733D02*
X1509901Y1107780D01*
G01X1502512Y1109922D02*
X1504350Y1110969D01*
G01X1508063Y1113111D02*
X1509901Y1114158D01*
G01X1502512Y1116300D02*
X1504350Y1117347D01*
G01X1500661Y1113111D02*
X1502499Y1114158D01*
G01X1500661Y1119489D02*
X1502499Y1120536D01*
G01X1508063Y1119489D02*
X1509901Y1120536D01*
G01X1502512Y1122678D02*
X1504350Y1123725D01*
G01X1500661Y1125867D02*
X1502499Y1126914D01*
G01X1508063Y1125867D02*
X1509901Y1126914D01*
G01X1508063Y1132245D02*
X1509901Y1133292D01*
G01X1502512Y1129056D02*
X1504350Y1130103D01*
G01X1500661Y1132245D02*
X1502499Y1133292D01*
G01X1500661Y1138622D02*
X1502499Y1139669D01*
G01X1508063Y1138622D02*
X1509901Y1139669D01*
G01X1502512Y1141811D02*
X1504350Y1142858D01*
G01X1502512Y1148189D02*
X1504350Y1149236D01*
G01X1500661Y1145000D02*
X1502499Y1146047D01*
G01X1508063Y1145000D02*
X1509901Y1146047D01*
G01X1502512Y1135433D02*
X1504350Y1136480D01*
G01X1500661Y1164134D02*
X1502480Y1165170D01*
X1502512Y1165289D01*
G01Y1154567D02*
X1504350Y1155614D01*
G01X1500661Y1151378D02*
X1502499Y1152425D01*
G01X1508063Y1151378D02*
X1509901Y1152425D01*
G01X1509913Y1154567D02*
X1511751Y1155614D01*
G01X1500661Y1157756D02*
X1502499Y1158803D01*
G01X1504362Y1157756D02*
X1506200Y1158803D01*
G01X1508063Y1157756D02*
X1509901Y1158803D01*
G01X1519835Y877481D02*
X1521673Y876434D01*
G01X1516134Y877481D02*
X1517972Y876434D01*
G01X1517984Y880670D02*
X1519822Y879623D01*
G01X1525386Y880670D02*
X1527224Y879623D01*
G01X1514283Y880670D02*
X1516121Y879623D01*
G01X1521685Y874292D02*
X1523523Y873245D01*
G01X1527236Y877481D02*
X1529074Y876434D01*
G01X1519835Y883859D02*
X1521673Y882812D01*
G01X1517984Y887048D02*
X1519822Y886001D01*
G01X1523535Y883859D02*
X1525373Y882812D01*
G01X1525386Y887048D02*
X1527224Y886001D01*
G01X1519835Y890237D02*
X1521673Y889190D01*
G01X1519835Y896615D02*
X1521673Y895568D01*
G01X1525386Y893426D02*
X1527224Y892379D01*
G01X1514283Y893426D02*
X1516121Y892379D01*
G01X1527236Y890237D02*
X1529074Y889190D01*
G01X1514283Y887048D02*
X1516121Y886001D01*
G01X1527236Y896615D02*
X1529074Y895568D01*
G01X1519835Y902993D02*
X1521673Y901946D01*
G01X1525386Y899804D02*
X1527224Y898757D01*
G01X1514283Y899804D02*
X1516121Y898757D01*
G01X1525386Y912559D02*
X1527224Y911512D01*
G01X1525386Y906181D02*
X1527224Y905134D01*
G01X1514283Y912559D02*
X1516121Y911512D01*
G01X1527236Y902993D02*
X1529074Y901946D01*
G01X1527236Y909370D02*
X1529074Y908324D01*
G01X1519835Y909370D02*
X1521673Y908323D01*
G01X1514283Y906181D02*
X1516121Y905134D01*
G01X1519835Y915748D02*
X1521673Y914701D01*
G01X1525386Y918937D02*
X1527224Y917890D01*
G01X1514283Y918937D02*
X1516121Y917890D01*
G01X1519835Y922126D02*
X1521673Y921079D01*
G01X1525386Y925315D02*
X1527224Y924268D01*
G01X1527236Y915748D02*
X1529074Y914701D01*
G01X1527236Y922126D02*
X1529074Y921079D01*
G01X1514283Y925315D02*
X1516121Y924268D01*
G01X1514283Y931693D02*
X1516121Y930646D01*
G01X1519835Y928504D02*
X1521673Y927457D01*
G01X1519835Y934882D02*
X1521673Y933835D01*
G01X1525386Y931693D02*
X1527224Y930646D01*
G01X1514283Y938071D02*
X1516121Y937024D01*
G01X1525386Y938071D02*
X1527224Y937024D01*
G01X1519835Y941260D02*
X1521673Y940213D01*
G01X1527236Y928504D02*
X1529074Y927457D01*
G01X1527236Y934882D02*
X1529074Y933835D01*
G01X1527236Y941260D02*
X1529074Y940213D01*
G01X1514283Y950827D02*
X1516121Y949780D01*
G01X1519835Y947638D02*
X1521673Y946591D01*
G01X1525386Y944449D02*
X1527224Y943402D01*
G01X1525386Y950827D02*
X1527224Y949780D01*
G01X1519835Y954016D02*
X1521673Y952969D01*
G01X1525386Y957205D02*
X1527224Y956158D01*
G01X1514283Y957205D02*
X1516121Y956158D01*
G01X1527236Y947638D02*
X1529074Y946591D01*
G01X1527236Y954016D02*
X1529074Y952969D01*
G01X1514283Y944449D02*
X1516121Y943402D01*
G01X1519835Y960394D02*
X1521673Y959347D01*
G01X1519835Y966772D02*
X1521673Y965725D01*
G01X1525386Y963583D02*
X1527224Y962536D01*
G01X1525386Y969961D02*
X1527224Y968914D01*
G01X1514283Y969961D02*
X1516121Y968914D01*
G01X1527236Y960394D02*
X1529074Y959347D01*
G01X1527236Y966772D02*
X1529074Y965725D01*
G01X1514283Y963583D02*
X1516121Y962536D01*
G01X1519835Y973150D02*
X1521673Y972103D01*
G01X1521685Y982717D02*
X1523523Y981670D01*
G01X1519835Y979528D02*
X1521673Y978481D01*
G01X1525386Y976339D02*
X1527224Y975292D01*
G01X1525386Y982717D02*
X1527224Y981670D01*
G01X1514283Y976339D02*
X1516121Y975292D01*
G01X1519835Y985906D02*
X1521673Y984859D01*
G01X1523535Y985906D02*
X1525373Y984859D01*
G01X1527236Y973150D02*
X1529074Y972103D01*
G01X1527236Y979528D02*
X1529074Y978481D01*
G01X1527236Y985906D02*
X1529074Y984859D01*
G01X1514283Y982717D02*
X1516121Y981670D01*
G01X1519835Y992284D02*
X1521673Y991237D01*
G01X1519835Y998662D02*
X1521673Y997615D01*
G01X1525386Y989095D02*
X1527224Y988048D01*
G01X1525386Y995473D02*
X1527224Y994426D01*
G01X1514283Y989095D02*
X1516121Y988048D01*
G01X1514283Y995473D02*
X1516121Y994426D01*
G01X1525386Y1001851D02*
X1527224Y1000804D01*
G01X1527236Y992284D02*
X1529074Y991237D01*
G01X1527236Y998662D02*
X1529074Y997615D01*
G01X1514283Y1001851D02*
X1516121Y1000804D01*
G01X1514283Y1008229D02*
X1516121Y1007182D01*
G01X1519835Y1005040D02*
X1521673Y1003993D01*
G01X1519835Y1011418D02*
X1521673Y1010371D01*
G01X1525386Y1008229D02*
X1527224Y1007182D01*
G01X1527236Y1005040D02*
X1529074Y1003993D01*
G01X1527236Y1011418D02*
X1529074Y1010371D01*
G01X1521016Y1027008D02*
X1522854Y1028055D01*
G01X1513614Y1027008D02*
X1515452Y1028055D01*
G01X1528417Y1027008D02*
X1530255Y1028055D01*
G01X1515464Y1030197D02*
X1517302Y1031244D01*
G01X1526567Y1030197D02*
X1528405Y1031244D01*
G01X1521016Y1033386D02*
X1522854Y1034433D01*
G01X1521016Y1039764D02*
X1522854Y1040811D01*
G01X1515464Y1042953D02*
X1517302Y1044000D01*
G01X1526567Y1036575D02*
X1528405Y1037622D01*
G01X1526567Y1042953D02*
X1528405Y1044000D01*
G01X1513614Y1039764D02*
X1515452Y1040811D01*
G01X1513614Y1033386D02*
X1515452Y1034433D01*
G01X1528417Y1033386D02*
X1530255Y1034433D01*
G01X1528417Y1039764D02*
X1530255Y1040811D01*
G01X1515464Y1036575D02*
X1517302Y1037622D01*
G01X1513614Y1052520D02*
X1515452Y1053567D01*
G01X1513614Y1058898D02*
X1515452Y1059945D01*
G01X1521016Y1046142D02*
X1522854Y1047189D01*
G01X1521016Y1052520D02*
X1522854Y1053567D01*
G01X1519165Y1055709D02*
X1521003Y1056756D01*
G01X1515464Y1049331D02*
X1517302Y1050378D01*
G01X1521016Y1058898D02*
X1522854Y1059945D01*
G01X1517315Y1058898D02*
X1519153Y1059945D01*
G01X1526567Y1049331D02*
X1528405Y1050378D01*
G01X1526567Y1055709D02*
X1528405Y1056756D01*
G01X1528417Y1046142D02*
X1530255Y1047189D01*
G01X1528417Y1052520D02*
X1530255Y1053567D01*
G01X1528417Y1058898D02*
X1530255Y1059945D01*
G01X1513614Y1046142D02*
X1515452Y1047189D01*
G01X1515464Y1055709D02*
X1517302Y1056756D01*
G01X1515464Y1062087D02*
X1517302Y1063134D01*
G01X1526567Y1062087D02*
X1528405Y1063134D01*
G01X1513614Y1071654D02*
X1515452Y1072701D01*
G01X1521016Y1065276D02*
X1522854Y1066323D01*
G01X1521016Y1071654D02*
X1522854Y1072701D01*
G01X1515464Y1068465D02*
X1517302Y1069512D01*
G01X1526567Y1068465D02*
X1528405Y1069512D01*
G01X1528417Y1065276D02*
X1530255Y1066323D01*
G01X1528417Y1071654D02*
X1530255Y1072701D01*
G01X1526567Y1074843D02*
X1528405Y1075890D01*
G01X1513614Y1065276D02*
X1515452Y1066323D01*
G01X1515464Y1074843D02*
X1517302Y1075890D01*
G01X1513614Y1078032D02*
X1515452Y1079079D01*
G01X1521016Y1078032D02*
X1522854Y1079079D01*
G01X1515464Y1081221D02*
X1517302Y1082268D01*
G01X1526567Y1081221D02*
X1528405Y1082268D01*
G01X1521016Y1084410D02*
X1522854Y1085457D01*
G01X1515464Y1087599D02*
X1517302Y1088646D01*
G01X1526567Y1087599D02*
X1528405Y1088646D01*
G01X1528417Y1078032D02*
X1530255Y1079079D01*
G01X1528417Y1084410D02*
X1530255Y1085457D01*
G01X1513614Y1084410D02*
X1515452Y1085457D01*
G01X1513614Y1090788D02*
X1515452Y1091835D01*
G01X1521016Y1090788D02*
X1522854Y1091835D01*
G01X1526567Y1093977D02*
X1528405Y1095024D01*
G01X1521016Y1103544D02*
X1522854Y1104591D01*
G01X1526567Y1100355D02*
X1528405Y1101402D01*
G01X1513614Y1097166D02*
X1515452Y1098213D01*
G01X1521016Y1097166D02*
X1522854Y1098213D01*
G01X1515464Y1100355D02*
X1517302Y1101402D01*
G01X1528417Y1097166D02*
X1530255Y1098213D01*
G01X1528417Y1103544D02*
X1530255Y1104591D01*
G01X1528417Y1090788D02*
X1530255Y1091835D01*
G01X1515464Y1093977D02*
X1517302Y1095024D01*
G01X1513614Y1103544D02*
X1515452Y1104591D01*
G01X1515464Y1106733D02*
X1517302Y1107780D01*
G01X1526567Y1106733D02*
X1528405Y1107780D01*
G01X1521016Y1109922D02*
X1522854Y1110969D01*
G01X1513614Y1109922D02*
X1515452Y1110969D01*
G01X1521016Y1116300D02*
X1522854Y1117347D01*
G01X1526567Y1113111D02*
X1528405Y1114158D01*
G01X1513614Y1116300D02*
X1515452Y1117347D01*
G01X1528417Y1109922D02*
X1530255Y1110969D01*
G01X1528417Y1116300D02*
X1530255Y1117347D01*
G01X1515464Y1119489D02*
X1517302Y1120536D01*
G01X1526567Y1119489D02*
X1528405Y1120536D01*
G01X1515464Y1113111D02*
X1517302Y1114158D01*
G01X1521016Y1122678D02*
X1522854Y1123725D01*
G01X1515464Y1125867D02*
X1517302Y1126914D01*
G01X1526567Y1125867D02*
X1528405Y1126914D01*
G01X1526567Y1132245D02*
X1528405Y1133292D01*
G01X1513614Y1129056D02*
X1515452Y1130102D01*
G01X1528417Y1122678D02*
X1530255Y1123725D01*
G01X1528417Y1129056D02*
X1530255Y1130102D01*
G01X1521016Y1129056D02*
X1522854Y1130103D01*
G01X1513614Y1122678D02*
X1515452Y1123725D01*
G01X1515464Y1132245D02*
X1517302Y1133292D01*
G01X1521016Y1141811D02*
X1522854Y1142858D01*
G01X1521016Y1135433D02*
X1522854Y1136480D01*
G01X1515464Y1138622D02*
X1517302Y1139669D01*
G01X1526567Y1138622D02*
X1528405Y1139669D01*
G01X1513614Y1135433D02*
X1515452Y1136480D01*
G01X1526567Y1145000D02*
X1528405Y1146047D01*
G01X1513614Y1148189D02*
X1515452Y1149236D01*
G01X1521016Y1148189D02*
X1522854Y1149236D01*
G01X1515464Y1145000D02*
X1517302Y1146047D01*
G01X1528417Y1141811D02*
X1530255Y1142858D01*
G01X1528417Y1135433D02*
X1530255Y1136480D01*
G01X1528417Y1148189D02*
X1530255Y1149236D01*
G01X1513614Y1141811D02*
X1515452Y1142858D01*
G01X1526567Y1151378D02*
X1528405Y1152425D01*
G01X1522866Y1157756D02*
X1524704Y1158803D01*
G01X1526567Y1157756D02*
X1528405Y1158803D01*
G01X1513614Y1154567D02*
X1515452Y1155614D01*
G01X1517315Y1154567D02*
X1519153Y1155614D01*
G01X1521016Y1154567D02*
X1522854Y1155614D01*
G01X1517315Y1160945D02*
X1519153Y1161992D01*
G01X1528417Y1154567D02*
X1530255Y1155614D01*
G01X1515464Y1151378D02*
X1517302Y1152425D01*
G01X1529074Y876434D02*
X1530937Y877481D01*
G01X1536488Y880670D02*
X1538326Y879623D01*
G01X1540189Y880670D02*
X1542027Y879623D01*
G01X1538338Y877481D02*
X1540176Y876434D01*
G01X1529086Y887048D02*
X1530925Y886001D01*
G01X1538338Y883859D02*
X1540176Y882812D01*
G01X1534638Y883859D02*
X1536476Y882812D01*
G01X1532787Y887048D02*
X1534625Y886001D01*
G01X1538338Y890237D02*
X1540176Y889190D01*
G01X1540189Y893426D02*
X1542027Y892379D01*
G01X1532787Y893426D02*
X1534625Y892379D01*
G01X1538338Y896615D02*
X1540176Y895568D01*
G01X1540189Y887048D02*
X1542027Y886001D01*
G01X1540189Y899804D02*
X1542027Y898757D01*
G01X1538338Y902993D02*
X1540176Y901946D01*
G01X1532787Y899804D02*
X1534625Y898757D01*
G01X1538338Y909370D02*
X1540176Y908324D01*
G01X1540189Y912559D02*
X1542027Y911512D01*
G01X1532787Y906181D02*
X1534625Y905134D01*
G01X1532787Y912559D02*
X1534625Y911512D01*
G01X1540189Y906181D02*
X1542027Y905134D01*
G01X1540189Y918937D02*
X1542027Y917890D01*
G01X1532787Y918937D02*
X1534625Y917890D01*
G01X1538338Y922126D02*
X1540176Y921079D01*
G01X1532787Y925315D02*
X1534625Y924268D01*
G01X1540189Y925315D02*
X1542027Y924268D01*
G01X1538338Y915748D02*
X1540176Y914701D01*
G01X1538338Y928504D02*
X1540176Y927457D01*
G01X1540189Y931693D02*
X1542027Y930646D01*
G01X1532787Y931693D02*
X1534625Y930646D01*
G01X1540189Y938071D02*
X1542027Y937024D01*
G01X1538338Y941260D02*
X1540176Y940213D01*
G01X1532787Y938071D02*
X1534625Y937024D01*
G01X1538338Y934882D02*
X1540176Y933835D01*
G01X1538338Y947638D02*
X1540176Y946591D01*
G01X1540189Y950827D02*
X1542027Y949780D01*
G01X1532787Y944449D02*
X1534625Y943402D01*
G01X1532787Y950827D02*
X1534625Y949780D01*
G01X1532787Y957205D02*
X1534625Y956158D01*
G01X1540189Y957205D02*
X1542027Y956158D01*
G01X1538338Y954016D02*
X1540176Y952969D01*
G01X1540189Y944449D02*
X1542027Y943402D01*
G01X1538338Y960394D02*
X1540176Y959347D01*
G01X1538338Y966772D02*
X1540176Y965725D01*
G01X1532787Y963583D02*
X1534625Y962536D01*
G01X1540189Y969961D02*
X1542027Y968914D01*
G01X1532787Y969961D02*
X1534625Y968914D01*
G01X1540189Y963583D02*
X1542027Y962536D01*
G01X1536488Y982717D02*
X1538326Y981670D01*
G01X1540189Y976339D02*
X1542027Y975292D01*
G01X1538338Y979528D02*
X1540176Y978481D01*
G01X1532787Y976339D02*
X1534625Y975292D01*
G01X1532787Y982717D02*
X1534625Y981670D01*
G01X1534638Y985906D02*
X1536476Y984859D01*
G01X1538338Y985906D02*
X1540176Y984859D01*
G01X1542039Y985906D02*
X1543877Y984859D01*
G01X1540189Y982717D02*
X1542027Y981670D01*
G01X1538338Y973150D02*
X1540176Y972103D01*
G01X1540189Y989095D02*
X1542027Y988048D01*
G01X1538338Y998662D02*
X1540176Y997615D01*
G01X1540189Y995473D02*
X1542027Y994426D01*
G01X1532787Y989095D02*
X1534625Y988048D01*
G01X1532787Y995473D02*
X1534625Y994426D01*
G01X1532787Y1001851D02*
X1534625Y1000804D01*
G01X1540189Y1001851D02*
X1542027Y1000804D01*
G01X1538338Y992284D02*
X1540176Y991237D01*
G01X1540189Y1008229D02*
X1542027Y1007182D01*
G01X1532787Y1008229D02*
X1534625Y1007182D01*
G01X1538338Y1005040D02*
X1540176Y1003993D01*
G01X1538338Y1011418D02*
X1540176Y1010371D01*
G01X1539520Y1027008D02*
X1541358Y1028055D01*
G01X1541370Y1030197D02*
X1543208Y1031244D01*
G01X1533968Y1030197D02*
X1535806Y1031244D01*
G01X1539520Y1039764D02*
X1541357Y1040811D01*
G01X1539520Y1033386D02*
X1541357Y1034433D01*
G01X1541370Y1042953D02*
X1543208Y1044000D01*
G01X1533968Y1036575D02*
X1535806Y1037622D01*
G01X1533968Y1042953D02*
X1535806Y1044000D01*
G01X1541370Y1036575D02*
X1543208Y1037622D01*
G01X1539520Y1052520D02*
X1541357Y1053567D01*
G01X1539520Y1058898D02*
X1541357Y1059945D01*
G01X1541370Y1049331D02*
X1543208Y1050378D01*
G01X1530268Y1055709D02*
X1532106Y1056756D01*
G01X1533968Y1055709D02*
X1535806Y1056756D01*
G01X1533968Y1049331D02*
X1535806Y1050378D01*
G01X1532118Y1058898D02*
X1533956Y1059945D01*
G01X1543220Y1058898D02*
X1545058Y1059945D01*
G01X1541370Y1055709D02*
X1543208Y1056756D01*
G01X1539520Y1046142D02*
X1541357Y1047189D01*
G01X1541370Y1062087D02*
X1543208Y1063134D01*
G01X1533968Y1062087D02*
X1535806Y1063134D01*
G01X1541370Y1068465D02*
X1543208Y1069512D01*
G01X1539520Y1071654D02*
X1541357Y1072701D01*
G01X1533968Y1068465D02*
X1535806Y1069512D01*
G01X1533968Y1074843D02*
X1535806Y1075890D01*
G01X1539520Y1065276D02*
X1541357Y1066323D01*
G01X1541370Y1074843D02*
X1543208Y1075890D01*
G01X1539520Y1078032D02*
X1541357Y1079079D01*
G01X1541370Y1081221D02*
X1543208Y1082268D01*
G01X1541370Y1087599D02*
X1543208Y1088646D01*
G01X1533968Y1087599D02*
X1535806Y1088646D01*
G01X1533968Y1081221D02*
X1535806Y1082268D01*
G01X1539520Y1084410D02*
X1541357Y1085457D01*
G01X1539520Y1090788D02*
X1541357Y1091835D01*
G01X1533968Y1093977D02*
X1535806Y1095024D01*
G01X1541370Y1100355D02*
X1543208Y1101402D01*
G01X1539520Y1097166D02*
X1541357Y1098213D01*
G01X1533968Y1100355D02*
X1535806Y1101402D01*
G01X1541370Y1093977D02*
X1543208Y1095024D01*
G01X1539520Y1103544D02*
X1541357Y1104591D01*
G01X1541370Y1106733D02*
X1543208Y1107780D01*
G01X1533968Y1106733D02*
X1535806Y1107780D01*
G01X1539520Y1109922D02*
X1541357Y1110969D01*
G01X1539520Y1116300D02*
X1541357Y1117347D01*
G01X1533968Y1113111D02*
X1535806Y1114158D01*
G01X1541370Y1119489D02*
X1543208Y1120536D01*
G01X1533968Y1119489D02*
X1535806Y1120536D01*
G01X1541370Y1113111D02*
X1543208Y1114158D01*
G01X1541370Y1125867D02*
X1543208Y1126914D01*
G01X1533968Y1125867D02*
X1535806Y1126914D01*
G01X1539520Y1129056D02*
X1541357Y1130102D01*
G01X1533968Y1132245D02*
X1535806Y1133292D01*
G01X1539520Y1122678D02*
X1541357Y1123725D01*
G01X1541370Y1132245D02*
X1543208Y1133292D01*
G01X1539520Y1135433D02*
X1541357Y1136480D01*
G01X1541370Y1138622D02*
X1543208Y1139669D01*
G01X1533968Y1138622D02*
X1535806Y1139669D01*
G01X1541370Y1145000D02*
X1543208Y1146047D01*
G01X1539520Y1148189D02*
X1541357Y1149236D01*
G01X1533968Y1145000D02*
X1535806Y1146047D01*
G01X1539520Y1141811D02*
X1541357Y1142858D01*
G01X1535819Y1154567D02*
X1537657Y1155614D01*
G01X1539520Y1154567D02*
X1541357Y1155614D01*
G01X1533968Y1151378D02*
X1535806Y1152425D01*
G01X1530268Y1157756D02*
X1532106Y1158803D01*
G01X1533968Y1157756D02*
X1535806Y1158803D01*
G01X1539520Y1160945D02*
X1541357Y1161992D01*
G01X1530268Y1164134D02*
X1532106Y1165181D01*
G01X1543220Y1154567D02*
X1545058Y1155614D01*
G01X1537669Y1157756D02*
X1539507Y1158803D01*
G01X1541370Y1151378D02*
X1543208Y1152425D01*
G01X1543890Y874292D02*
X1545728Y873245D01*
G01X1551291Y880670D02*
X1553129Y879623D01*
G01X1543890Y887048D02*
X1545728Y886001D01*
G01X1545740Y883859D02*
X1547578Y882812D01*
G01X1551291Y887048D02*
X1553129Y886001D01*
G01X1549441Y883859D02*
X1551279Y882812D01*
G01X1545740Y890237D02*
X1547578Y889190D01*
G01X1545740Y896615D02*
X1547578Y895568D01*
G01X1551291Y893426D02*
X1553129Y892379D01*
G01X1545740Y902993D02*
X1547578Y901946D01*
G01X1551291Y899804D02*
X1553129Y898757D01*
G01X1545740Y909370D02*
X1547578Y908324D01*
G01X1551291Y906181D02*
X1553870D01*
G01X1551291Y912559D02*
X1553870D01*
G01X1545740Y915748D02*
X1547578Y914701D01*
G01X1551291Y918937D02*
X1553870D01*
G01X1545740Y922126D02*
X1547578Y921079D01*
G01X1551291Y925315D02*
X1553870D01*
G01X1545740Y928504D02*
X1547578Y927457D01*
G01X1545740Y934882D02*
X1547578Y933835D01*
G01X1551291Y931693D02*
X1553870D01*
G01X1545740Y941260D02*
X1547578Y940213D01*
G01X1551291Y938071D02*
X1553870D01*
G01X1545740Y947638D02*
X1547578Y946591D01*
G01X1551291Y944449D02*
X1553870D01*
G01X1551291Y950827D02*
X1553870D01*
G01X1545740Y954016D02*
X1547578Y952969D01*
G01X1545740Y960394D02*
X1547578Y959347D01*
G01X1545740Y966772D02*
X1547578Y965725D01*
G01X1551291Y957205D02*
X1553870D01*
G01X1551291Y963583D02*
X1553870D01*
G01X1551291Y969961D02*
X1553870D01*
G01X1545740Y973150D02*
X1547578Y972103D01*
G01X1545740Y979528D02*
X1547578Y978481D01*
G01X1551291Y976339D02*
X1553870D01*
G01X1551291Y982717D02*
X1553870D01*
G01X1545740Y985906D02*
X1547578Y984859D01*
G01X1543890Y989095D02*
X1545728Y988048D01*
G01X1545740Y992284D02*
X1547578Y991237D01*
G01X1545740Y998662D02*
X1547578Y997615D01*
G01X1551291Y989095D02*
X1553870D01*
G01X1551291Y995473D02*
X1553870D01*
G01X1545740Y1005040D02*
X1547578Y1003993D01*
G01X1545740Y1011418D02*
X1547578Y1010371D01*
G01X1551291Y1008229D02*
X1553870D01*
G01X1551291Y1001851D02*
X1553870D01*
G01X1546921Y1027008D02*
X1548759Y1028055D01*
G01X1552472Y1030197D02*
X1555051D01*
G01X1546921Y1039764D02*
X1548759Y1040811D01*
G01X1546921Y1033386D02*
X1548759Y1034433D01*
G01X1552472Y1042953D02*
X1555051D01*
G01X1552472Y1036575D02*
X1555051D01*
G01X1545071Y1055709D02*
X1546909Y1056756D01*
G01X1546921Y1046142D02*
X1548759Y1047189D01*
G01X1552472Y1049331D02*
X1555051D01*
G01X1546921Y1052520D02*
X1548759Y1053567D01*
G01X1546921Y1058898D02*
X1548759Y1059945D01*
G01X1552472Y1055709D02*
X1555051D01*
G01X1552472Y1062087D02*
X1555051D01*
G01X1546921Y1071654D02*
X1548759Y1072701D01*
G01X1546921Y1065276D02*
X1548759Y1066323D01*
G01X1552472Y1068465D02*
X1555051D01*
G01X1552472Y1074843D02*
X1555051D01*
G01X1546921Y1078032D02*
X1548759Y1079079D01*
G01X1552472Y1081221D02*
X1555051D01*
G01X1546921Y1084410D02*
X1548759Y1085457D01*
G01X1552472Y1087599D02*
X1555051D01*
G01X1546921Y1090788D02*
X1548759Y1091835D01*
G01X1552472Y1093977D02*
X1555051D01*
G01X1546921Y1097166D02*
X1548759Y1098213D01*
G01X1546921Y1103544D02*
X1548759Y1104591D01*
G01X1552472Y1100355D02*
X1555051D01*
G01X1552472Y1106733D02*
X1555051D01*
G01X1546921Y1109922D02*
X1548759Y1110969D01*
G01X1552472Y1113111D02*
X1555051D01*
G01X1546921Y1116300D02*
X1548759Y1117347D01*
G01X1552472Y1119489D02*
X1555051D01*
G01X1552472Y1132245D02*
X1555051D01*
G01X1546921Y1122678D02*
X1548759Y1123725D01*
G01X1552472Y1125867D02*
X1555051D01*
G01X1546921Y1129056D02*
X1548759Y1130102D01*
G01X1546921Y1135433D02*
X1548759Y1136480D01*
G01X1552472Y1138622D02*
X1555051D01*
G01X1546921Y1141811D02*
X1548759Y1142858D01*
G01X1552472Y1145000D02*
X1555051D01*
G01X1546921Y1148189D02*
X1548759Y1149236D01*
G01X1546921Y1154567D02*
X1548759Y1155614D01*
G01X1552472Y1151378D02*
X1555051D01*
G01X1548771Y1157756D02*
X1550609Y1158803D01*
G01X1552472Y1157756D02*
X1554310Y1158803D01*
G54D163*
X385443Y256059D03*
Y271807D03*
X846352Y256772D03*
Y272520D03*
X974408Y153162D03*
Y168910D03*
G54D118*
X220523Y594408D03*
X252019D03*
X1322165Y577505D03*
Y609001D03*
G54D262*
X841742Y105951D03*
Y99651D03*
X850088Y105951D03*
Y99651D03*
G54D61*
X59767Y1615405D03*
X638695Y1372257D03*
X1649283Y1425541D03*
X1749329Y1668956D03*
G54D325*
X1795796Y222241D03*
Y266533D03*
G54D253*
X789583Y1336044D03*
X791945Y1346280D03*
Y1336044D03*
X909949Y1143551D03*
X912311Y1153787D03*
X909949D03*
X956974Y1143551D03*
X959336Y1153787D03*
X956974D03*
X1319742Y549491D03*
X1322104Y559727D03*
X1319742D03*
X1625867Y549146D03*
X1628229Y559382D03*
X1625867D03*
G54D25*
X27048Y1533228D03*
X79590Y1369350D03*
X137284Y1533228D03*
X215418Y658055D03*
X276440Y1357539D03*
X420125Y656008D03*
X443764Y1339823D03*
X523173Y578174D03*
X681440Y1385138D03*
X791678D03*
X873622Y1145275D03*
X983858D03*
X1052960Y1369350D03*
X1249812Y1357539D03*
X1370284Y582303D03*
X1417134Y1339823D03*
X1533552Y682342D03*
X1629732Y1383523D03*
X1664890Y642972D03*
X1714330Y1570984D03*
X1739968Y1383527D03*
X1761575Y159134D03*
X1824566Y1570988D03*
X1838150Y201929D03*
G54D217*
X606890Y461348D03*
X617204D03*
X606890Y465088D03*
Y468828D03*
X617204D03*
Y465088D03*
G54D145*
X306753Y112844D03*
Y124262D03*
X1021924Y150805D03*
Y162223D03*
X1776878Y113968D03*
Y125386D03*
G54D226*
X705660Y588934D03*
X697392D03*
Y606060D03*
X705660D03*
G54D235*
X716780Y1643326D03*
X721898D03*
X719339D03*
X714221D03*
Y1666358D03*
X716780D03*
X721898D03*
X719339D03*
X737253Y1643326D03*
X734694D03*
X732135D03*
X729576D03*
X727017D03*
X724457D03*
Y1666358D03*
X727017D03*
X729576D03*
X732135D03*
X734694D03*
X737253D03*
G54D271*
X901650Y1175243D03*
Y1219735D03*
X956504Y1175243D03*
Y1219735D03*
G54D208*
X572297Y149226D03*
Y157494D03*
X589423Y149226D03*
Y157494D03*
X842562Y168064D03*
Y176332D03*
X859688D03*
Y168064D03*
X1594537Y295328D03*
Y303596D03*
X1611663Y295328D03*
Y303596D03*
G54D280*
X961084Y1541966D03*
Y1559682D03*
X992696Y1541982D03*
Y1559698D03*
X1024296Y1541982D03*
Y1559698D03*
X1055896Y1541982D03*
Y1559698D03*
G54D307*
X1592133Y581522D03*
G54D34*
X45876Y384395D03*
Y386364D03*
Y388333D03*
Y390301D03*
Y392269D03*
Y394238D03*
Y396207D03*
X64872Y388333D03*
Y386364D03*
Y384395D03*
Y396207D03*
Y394238D03*
Y392269D03*
Y390301D03*
G54D52*
X59201Y1529938D03*
X94944D03*
X106597Y1364060D03*
X139197D03*
X171897D03*
X204797D03*
X237597D03*
X264459Y666057D03*
X271197Y1317914D03*
X297189Y700298D03*
X304093Y1317886D03*
X329959Y720448D03*
X336997Y1317829D03*
X363019Y720180D03*
X369797Y1318029D03*
X396059Y720248D03*
X402379Y1337360D03*
X429059Y702448D03*
X461459Y677848D03*
X494059Y651348D03*
X527359Y617248D03*
X714153Y1382069D03*
X746935Y1382169D03*
X1078335Y1364041D03*
X1110935D03*
X1143635D03*
X1176535D03*
X1209335D03*
X1247326Y1317895D03*
X1280222Y1317867D03*
X1313126Y1317810D03*
X1345926Y1318010D03*
X1375011Y635391D03*
X1378508Y1337341D03*
X1407711Y668291D03*
X1440311Y700871D03*
X1473229Y720448D03*
X1506311Y720616D03*
X1539111Y720448D03*
X1572241Y698508D03*
X1605011Y664739D03*
X1638011Y645739D03*
X1661886Y1381358D03*
X1694668Y1381458D03*
X1746484Y1562974D03*
X1782227D03*
G54D244*
X782624Y1573554D03*
X780656D03*
Y1591172D03*
X782624D03*
X790498Y1573554D03*
X788530D03*
X786561D03*
X784593D03*
Y1591172D03*
X786561D03*
X788530D03*
X790498D03*
X826593Y1573554D03*
X824624D03*
X822656D03*
Y1591172D03*
X824624D03*
X826593D03*
X832498Y1573554D03*
X830530D03*
X828561D03*
Y1591172D03*
X830530D03*
X832498D03*
X870561Y1573554D03*
X868593D03*
X866624D03*
X864656D03*
Y1591172D03*
X866624D03*
X868593D03*
X870561D03*
X874498Y1573554D03*
X872530D03*
Y1591172D03*
X874498D03*
X916498Y1573554D03*
X914530D03*
X912561D03*
X910593D03*
X908624D03*
X906656D03*
Y1591172D03*
X908624D03*
X910593D03*
X912561D03*
X914530D03*
X916498D03*
G54D127*
X256978Y107835D03*
Y111771D03*
X690134Y111960D03*
Y115896D03*
X993943Y194419D03*
Y196387D03*
Y198356D03*
Y200325D03*
Y202293D03*
Y204261D03*
Y206230D03*
Y208199D03*
Y210167D03*
X1004967D03*
Y208199D03*
Y206230D03*
Y204261D03*
Y202293D03*
Y200325D03*
Y198356D03*
Y196387D03*
X1732099Y108959D03*
Y112895D03*
G54D181*
X483967Y213093D03*
G54D190*
X474070Y295282D03*
X561070Y304282D03*
G54D16*
X11782Y171993D03*
X18691Y172165D03*
X33180Y298299D03*
X36524Y392288D03*
X32847Y534557D03*
X36372Y531312D03*
X50304Y58837D03*
X39008Y363429D03*
X51114D03*
X42809D03*
X48502Y504789D03*
X48626Y546777D03*
X52040Y1499314D03*
X50631Y1537188D03*
X48662Y1523352D03*
X51996Y1551459D03*
X50696Y1544386D03*
X46133Y1633413D03*
X51133D03*
X54616Y58837D03*
X63780Y298299D03*
X67681Y363429D03*
X59322D03*
X63429D03*
X56163Y414020D03*
X52902Y504602D03*
X58402D03*
X58633Y1590413D03*
X63633D03*
X56133Y1636513D03*
X61133D03*
X64427Y1646904D03*
X55427D03*
X69523Y414020D03*
X80378Y1409172D03*
X68768Y1547313D03*
X81006Y1596424D03*
X68133Y1590413D03*
X72660D03*
X77427Y1646904D03*
X78127Y1681904D03*
X70127D03*
X74127D03*
X94158Y1308118D03*
X90601Y1382806D03*
X94713Y1382854D03*
X86374Y1537688D03*
X84405Y1523352D03*
X82606Y1604724D03*
X86127Y1681904D03*
X92500Y1698967D03*
X98124Y1356733D03*
X98101Y1374054D03*
X101995Y1382685D03*
X107000Y1407517D03*
X104511Y1547013D03*
X112353Y1649104D03*
X120016Y294714D03*
Y315148D03*
X115590Y1381875D03*
X115353Y1690483D03*
X119353D03*
X130724Y1356733D03*
X130701Y1374054D03*
X134595Y1382685D03*
X141028Y1449129D03*
X137120Y1449175D03*
X133120D03*
X132353Y1649104D03*
X136353D03*
X132420Y1701528D03*
X139353Y1690604D03*
X131353D03*
X135353D03*
X144610Y424097D03*
X148190Y1381875D03*
X148000Y1414517D03*
X151000Y1442517D03*
X145028Y1449129D03*
X149028D03*
X152353Y1649104D03*
X151353Y1690604D03*
X143353D03*
X155353D03*
X163424Y1356733D03*
X163401Y1374054D03*
X167295Y1382685D03*
X158740Y1707517D03*
X183890Y390677D03*
X180890Y1381875D03*
X185760Y1707405D03*
X181760Y1725893D03*
X195979Y98159D03*
X190861Y125594D03*
X197645Y130704D03*
X196324Y1356733D03*
X196301Y1374054D03*
X200195Y1382685D03*
X189760Y1725893D03*
X208179Y98159D03*
X203061Y125594D03*
X213790Y1381875D03*
X229516Y152076D03*
X225090Y153487D03*
X229124Y1356733D03*
X229101Y1374054D03*
X243487Y104777D03*
X246297Y124060D03*
X242297D03*
X233595Y152088D03*
X244125Y663255D03*
X232995Y1382685D03*
X247487Y104777D03*
X261297Y124060D03*
X254297D03*
X250297D03*
X260100Y153979D03*
X254756Y156819D03*
X251424Y645276D03*
X246590Y1381875D03*
X271797Y124060D03*
X268297Y127560D03*
X275500Y231017D03*
X273069Y582087D03*
X272955Y663597D03*
X262724Y1310587D03*
X262701Y1327908D03*
X266595Y1336539D03*
X273597Y1519937D03*
X289357Y116020D03*
X284154Y679517D03*
X276855Y697496D03*
X280190Y1335729D03*
X279499Y1519937D03*
X302500Y250517D03*
X297815Y582971D03*
X305685Y697838D03*
X295620Y1310559D03*
X295597Y1327880D03*
X299491Y1336511D03*
X314602Y271108D03*
X316924Y699667D03*
X309655Y717356D03*
X313086Y1335701D03*
X325617Y81260D03*
X328524Y1310502D03*
X328501Y1327823D03*
X332395Y1336454D03*
X339811Y123194D03*
X346153Y270403D03*
X349984Y699399D03*
X342710Y717329D03*
X338455Y717988D03*
X345990Y1335644D03*
X352628Y283807D03*
X357582Y555307D03*
X353582D03*
X361324Y1310702D03*
X361301Y1328023D03*
X365195Y1336654D03*
X370064Y239653D03*
X371412Y272094D03*
X371962Y534184D03*
X375704Y717480D03*
X371515Y717720D03*
X378790Y1335844D03*
X395048Y123695D03*
X382184Y468868D03*
X393376Y469214D03*
X383024Y699467D03*
X393906Y1330033D03*
X393883Y1347354D03*
X384824Y1624230D03*
X394824D03*
X389824D03*
X384824Y1661637D03*
X394824D03*
X389824D03*
X406243Y102593D03*
X399264Y123661D03*
X400632Y141242D03*
X399299Y214588D03*
X402184Y468986D03*
Y501618D03*
X408739Y699611D03*
X404771Y693155D03*
X404555Y717788D03*
X397777Y1355985D03*
X401659Y1519937D03*
X407561D03*
X402969Y1622841D03*
X399824Y1661637D03*
X405000Y1677517D03*
X411299Y206637D03*
Y214588D03*
X415984Y468909D03*
Y501541D03*
X412771Y531155D03*
X416024Y681667D03*
X423921Y1006440D03*
X411372Y1355175D03*
X417000Y1665017D03*
Y1677517D03*
X433673Y77217D03*
X429997Y160642D03*
X433997Y153642D03*
X437997D03*
X439299Y214588D03*
X429784Y468832D03*
X439500Y493517D03*
X437309Y674944D03*
X437555Y699988D03*
X435141Y1006440D03*
X438882D03*
X427661D03*
X431401D03*
X427251Y1286211D03*
X441997Y160642D03*
X451299Y214588D03*
X443500Y486517D03*
X448424Y657067D03*
X441137Y674930D03*
X450102Y1006440D03*
X442622D03*
X446362D03*
X453842D03*
X453085Y1643950D03*
X466600Y142892D03*
X457997Y160642D03*
X465997D03*
X461931Y215195D03*
X458115Y241045D03*
X469038Y300655D03*
X469881Y648554D03*
X469955Y675388D03*
X457582Y1006440D03*
X461000Y1644017D03*
X475435Y206652D03*
X484754Y223469D03*
X481024Y630567D03*
X473732Y648556D03*
X483500Y1264879D03*
X478500Y1265017D03*
X474500D03*
X498314Y115435D03*
X485997Y160642D03*
X489997D03*
X494144Y215744D03*
X487107Y285246D03*
X488538Y298720D03*
X488544Y292041D03*
X487500Y1264879D03*
X492500D03*
X496500D03*
X501500Y419517D03*
Y426517D03*
X512000Y429517D03*
X514324Y596467D03*
X502998Y614430D03*
X506964Y614438D03*
X502555Y648888D03*
X515539Y82659D03*
X522088Y204377D03*
X543131Y123347D03*
X536177Y243722D03*
X535855Y614788D03*
X537770Y1519937D03*
X543672D03*
X554196Y184773D03*
X556038Y309655D03*
X566460Y157586D03*
X574107Y294246D03*
X570216Y764529D03*
X582193Y90190D03*
Y83190D03*
X588194Y175067D03*
X575538Y307720D03*
X575567Y301185D03*
X585585Y374569D03*
X579385Y376519D03*
Y387319D03*
X585585D03*
X579385Y401250D03*
X575216Y764529D03*
X595260Y157586D03*
X602293Y206278D03*
X598294Y198278D03*
X602294D03*
X608793Y206278D03*
X608794Y198278D03*
X618705Y292822D03*
X615385Y387319D03*
Y376519D03*
Y406938D03*
X625310Y175626D03*
X626705Y292822D03*
X622705D03*
X621585Y374569D03*
Y387319D03*
X619500Y439017D03*
X626703Y1350201D03*
X630000Y1401517D03*
X635060Y143160D03*
X646231Y150068D03*
X642500Y419017D03*
X638000Y422517D03*
X643563Y1386914D03*
X647445Y1386938D03*
X635000Y1401517D03*
X637794Y1718487D03*
X653821Y84279D03*
X649500Y376517D03*
X655702Y1385440D03*
X659559Y1385382D03*
X651877Y1385407D03*
X652800Y1691317D03*
X656800D03*
X675843Y104202D03*
X666885Y405272D03*
X665832Y1527517D03*
X673113Y1729778D03*
Y1719116D03*
X680623Y108902D03*
X687453Y128185D03*
X683453D03*
X689440Y363421D03*
X690800Y376879D03*
X687500Y393379D03*
X687310Y507879D03*
X692500D03*
X679500Y521017D03*
X688500Y540379D03*
X688120Y1516543D03*
X704953Y128185D03*
X694453D03*
X700963Y128245D03*
X707545Y363338D03*
X703520Y363421D03*
X708300Y376879D03*
X704300D03*
X700300D03*
X707500Y393379D03*
X699500D03*
X695500D03*
X703500D03*
X700500Y507879D03*
X696500D03*
Y524379D03*
X700500Y540379D03*
X704500Y550379D03*
X704056Y577598D03*
X698996D03*
X708056D03*
X694996D03*
X698699Y1345887D03*
X705680Y1374742D03*
X705657Y1392063D03*
X701661Y1392085D03*
X697731Y1392055D03*
X698500Y1591017D03*
X696030Y1627794D03*
X699799Y1627710D03*
X723500Y363379D03*
X715395Y363369D03*
X712300Y376879D03*
X720300D03*
X715500Y393379D03*
X711500D03*
X720500Y550379D03*
Y540379D03*
X720787Y630848D03*
X716721Y630784D03*
X711702Y649273D03*
X709551Y1400694D03*
X723146Y1399694D03*
X710217Y1435755D03*
X723050Y1599450D03*
X717110Y1599540D03*
X715152Y1627598D03*
X729380Y75035D03*
X734380D03*
X723933Y135505D03*
X731500Y363379D03*
X727564Y376879D03*
X735500Y393379D03*
X732500Y507879D03*
X728500D03*
X736500D03*
X728500Y540379D03*
X736500D03*
X732500Y540517D03*
X738462Y1374842D03*
X738439Y1392163D03*
X732723Y1627037D03*
X736723D03*
X728723D03*
X732434Y1685190D03*
X728454Y1685021D03*
X737468Y1687220D03*
X745500Y199517D03*
X747500Y376879D03*
X743500Y393379D03*
X747500D03*
X751500D03*
X739652Y393361D03*
X744500Y507879D03*
X752500D03*
X748500D03*
X740895Y524398D03*
X748500Y524379D03*
X752500D03*
X744500D03*
X752500Y540379D03*
X742333Y1400794D03*
X740723Y1627037D03*
X752187Y1685511D03*
X741326Y1683829D03*
X760193Y100745D03*
X761000Y212517D03*
X759500Y376879D03*
Y393379D03*
X755500D03*
X764500Y507879D03*
X756500D03*
X760500D03*
X756500Y524379D03*
X760500D03*
X764500D03*
X765000Y540379D03*
X755928Y1399794D03*
X757770Y1628300D03*
X761770D03*
X754030Y1656100D03*
X767381Y1670258D03*
X754030Y1663100D03*
X762030D03*
X767368Y1662579D03*
X773766Y281339D03*
X781456Y378134D03*
X775500Y393379D03*
X771500D03*
X773000Y540379D03*
X768700Y540517D03*
X779447Y1334273D03*
X770450Y1581050D03*
X789277Y1524346D03*
X809817Y561954D03*
X807669Y1301733D03*
X812750Y1581950D03*
X819114Y117715D03*
X823114D03*
X827114D03*
X826614Y147215D03*
X824500Y508517D03*
X820500D03*
X831114Y117715D03*
X839360Y117599D03*
X840221Y184879D03*
X840220Y197879D03*
X839000Y386017D03*
X841872Y535202D03*
X844936Y90268D03*
X844221Y184879D03*
X844220Y197879D03*
X848500Y455017D03*
X852000Y486017D03*
X848762Y524505D03*
X854750Y1581950D03*
X871500Y316517D03*
X867190Y384777D03*
X871190D03*
X864065Y516053D03*
X886503Y278804D03*
X876923Y1242437D03*
X889368Y1141595D03*
X893368D03*
X895394Y1159848D03*
X896750Y1581950D03*
X916268Y272376D03*
X945263Y274673D03*
X936393Y1141595D03*
X940393D03*
X942419Y1159848D03*
X935907Y1242437D03*
X965442Y171902D03*
X981445Y179600D03*
X977195Y207940D03*
X1005699Y171360D03*
X999915Y179090D03*
X996415D03*
X1005395Y218440D03*
X1009735Y157960D03*
X1014828Y261782D03*
Y270944D03*
X1015334Y291328D03*
X1007011Y542016D03*
X1019961Y557449D03*
X1023220Y186116D03*
X1024961Y557449D03*
X1039000Y557517D03*
X1064915Y1308005D03*
X1066363Y1382567D03*
X1062405Y1382535D03*
X1064221Y1656937D03*
X1063751Y1648011D03*
X1069322Y401065D03*
X1069862Y1356714D03*
X1073733Y1382666D03*
X1069839Y1374035D03*
X1068094Y1648012D03*
X1068221Y1656937D03*
X1087328Y1381856D03*
X1094514Y1722933D03*
X1102462Y1356714D03*
X1102439Y1374035D03*
X1106333Y1382666D03*
X1108747Y1528897D03*
X1109558Y1544603D03*
X1105000Y1676517D03*
X1098514Y1715933D03*
X1119928Y1381856D03*
X1114617Y1528897D03*
X1115005Y1579568D03*
X1116000Y1665517D03*
X1120303Y1676452D03*
X1119361Y1716251D03*
X1135162Y1356714D03*
X1135139Y1374035D03*
X1139033Y1382666D03*
X1129846Y1456465D03*
X1131256Y1569044D03*
X1140117Y1665669D03*
X1152628Y1381856D03*
X1144107Y1665583D03*
X1168062Y1356714D03*
X1168039Y1374035D03*
X1180849Y461707D03*
X1178340Y469682D03*
X1171933Y1382666D03*
X1185528Y1381856D03*
X1195488Y88067D03*
X1215581Y85863D03*
X1200862Y1356714D03*
X1200839Y1374035D03*
X1204733Y1382666D03*
X1208000Y1394017D03*
X1210254Y1713953D03*
Y1706953D03*
Y1727953D03*
Y1720953D03*
X1206254Y1724803D03*
X1223455Y85863D03*
X1218328Y1381856D03*
X1238853Y1310568D03*
X1238830Y1327889D03*
X1242724Y1336520D03*
X1245000Y1427017D03*
Y1434017D03*
Y1441017D03*
X1241000D03*
X1253152Y87412D03*
Y98042D03*
X1256319Y1335710D03*
X1247000Y1403517D03*
X1256859Y1420017D03*
X1249000Y1427017D03*
Y1434017D03*
X1253000D03*
X1263472Y87381D03*
X1271749Y1310540D03*
X1271726Y1327861D03*
X1275620Y1336492D03*
X1289215Y1335682D03*
X1281470Y1552937D03*
X1287372D03*
X1296386Y545340D03*
X1299986D03*
X1296156Y555965D03*
X1304653Y1310483D03*
X1304630Y1327804D03*
X1307857Y105870D03*
X1305187Y565788D03*
X1308524Y1336435D03*
X1331930Y61462D03*
X1322119Y1335625D03*
X1343840Y61428D03*
X1337453Y1310683D03*
X1337430Y1328004D03*
X1341324Y1336635D03*
X1355750Y61428D03*
X1361976Y614610D03*
X1350261Y632598D03*
X1354597D03*
X1354919Y1335825D03*
X1367950Y61428D03*
X1370035Y1330014D03*
X1373906Y1355966D03*
X1370012Y1347335D03*
X1383507Y632931D03*
X1387297Y665498D03*
X1387501Y1355156D03*
X1394676Y647510D03*
X1407543Y1006439D03*
X1403803D03*
X1400063D03*
X1416207Y665831D03*
X1420007Y697748D03*
X1415024Y1006439D03*
X1411283D03*
X1418764D03*
X1422504D03*
X1417711Y1258883D03*
X1421211D03*
X1409532Y1552937D03*
X1415434D03*
X1415622Y1610284D03*
X1410622D03*
X1413622Y1637859D03*
X1434262Y55409D03*
X1439049Y109960D03*
X1429169Y109830D03*
X1427276Y680090D03*
X1433724Y1006439D03*
X1429984D03*
X1426244D03*
X1438532Y1275277D03*
X1448549Y117160D03*
X1443049Y109960D03*
X1448807Y698411D03*
X1452765Y717424D03*
X1449334Y1272009D03*
X1453334D03*
X1442532Y1275277D03*
X1450500Y1627017D03*
X1445500D03*
X1440500D03*
X1450500Y1617517D03*
X1442579Y1667820D03*
X1447579D03*
X1452579D03*
X1459896Y58505D03*
X1454549Y109960D03*
X1460194Y699667D03*
X1457579Y1667820D03*
X1481725Y717988D03*
X1493276Y699667D03*
X1485897Y717655D03*
X1513644Y246442D03*
X1505477Y1270905D03*
X1526076Y699667D03*
X1518697Y717655D03*
X1514807Y717988D03*
X1533454Y88238D03*
X1537454D03*
X1542697Y562104D03*
X1547827Y695547D03*
X1551827D03*
X1547607Y717988D03*
X1556178Y1262880D03*
X1558077Y1273305D03*
X1554377D03*
X1545644Y1552937D03*
X1551546D03*
X1559206Y677727D03*
X1560157Y1262880D03*
X1584597Y661946D03*
X1580597D03*
X1580737Y696048D03*
X1583177Y1262305D03*
X1587177D03*
X1575680Y1299996D03*
X1588800Y303688D03*
X1591976Y643958D03*
X1591177Y1262305D03*
X1617400Y303688D03*
X1617506Y564943D03*
X1617597Y642946D03*
X1613597D03*
X1613507Y662279D03*
X1629000Y386017D03*
Y393017D03*
X1624976Y624958D03*
X1646510Y428561D03*
X1646507Y643279D03*
X1645155Y1391337D03*
X1634327Y1406457D03*
X1662000Y218017D03*
X1651910Y230004D03*
X1652610Y397219D03*
X1661110Y428719D03*
X1653413Y1374031D03*
X1657284Y1399983D03*
X1653390Y1391352D03*
X1649197Y1391285D03*
X1653667Y1440258D03*
X1658167D03*
X1662465Y1438691D03*
X1657892Y1452377D03*
X1653614Y1452356D03*
X1650513Y1708701D03*
Y1715701D03*
Y1723851D03*
Y1730851D03*
X1673872Y428162D03*
X1670879Y1398983D03*
X1666290Y1438724D03*
X1670147Y1438666D03*
X1673706Y1560517D03*
X1675360Y1709019D03*
Y1723769D03*
X1684942Y228429D03*
X1686154Y428702D03*
X1686195Y1374131D03*
X1690066Y1400083D03*
X1686172Y1391452D03*
X1688243Y1666319D03*
X1692415Y1666257D03*
X1679816Y1666320D03*
X1685513Y1715701D03*
Y1708701D03*
X1704624Y428192D03*
X1701124D03*
X1703661Y1399083D03*
X1718608Y101101D03*
X1721418Y125184D03*
X1717418D03*
X1713312Y138239D03*
X1715044Y407062D03*
X1718931Y407054D03*
X1710408Y420462D03*
X1720845Y1673851D03*
X1710360Y1709019D03*
X1722608Y105901D03*
X1736418Y125184D03*
X1729418D03*
X1725418D03*
X1730364Y171468D03*
X1722500Y368879D03*
X1725500Y377879D03*
X1735945Y1556388D03*
X1728633Y1705207D03*
X1724633Y1712207D03*
Y1705207D03*
Y1720357D03*
Y1727357D03*
X1746918Y125184D03*
X1743418Y128684D03*
X1740688Y1531121D03*
X1737914Y1570224D03*
X1737979Y1577422D03*
X1739279Y1584495D03*
X1750380Y1710325D03*
X1749480Y1720675D03*
X1764478Y117144D03*
X1756051Y1580349D03*
X1758963Y1685982D03*
X1763463D03*
X1771688Y1556388D03*
X1773657Y1570724D03*
X1790738Y82384D03*
X1784133Y162916D03*
Y155827D03*
X1783448Y207474D03*
X1791794Y1580049D03*
X1819705Y163889D03*
G54D70*
X91454Y156791D03*
X286253Y154803D03*
X610229Y224877D03*
X823514Y136898D03*
X847479Y214391D03*
X1279902Y406725D03*
X1556217Y300416D03*
X1689073Y1686245D03*
X1734992Y370384D03*
G54D154*
X326731Y653394D03*
X363731D03*
X433624Y594259D03*
X754645Y1426892D03*
X1166535Y1412479D03*
X1291146Y1375715D03*
X1320516D03*
X1415690Y601230D03*
X1487677Y640145D03*
X1524437Y640365D03*
X1701285Y198612D03*
X1700840Y1424519D03*
X1731660Y198612D03*
X1770442Y284934D03*
X1800002D03*
G54D172*
X444090Y124007D03*
G54D43*
X57646Y12480D03*
X137272D03*
X186622D03*
X266858D03*
X315598D03*
X502528Y33267D03*
X582154D03*
X631504D03*
X711740D03*
X760480D03*
X1183858Y207205D03*
Y217205D03*
X1173858D03*
X1193858Y207205D03*
Y217205D03*
X1351260Y164213D03*
Y174213D03*
X1361260Y164213D03*
Y174213D03*
X1371260Y164213D03*
X1381260D03*
X1371260Y174213D03*
X1381260D03*
X1391260Y164213D03*
X1532055Y12480D03*
X1611681D03*
X1661031D03*
X1741267D03*
X1790007D03*
G54D136*
X275005Y594223D03*
X273430D03*
X271855D03*
X270281D03*
X279729D03*
X278155D03*
X276580D03*
X483967Y218408D03*
X485541D03*
Y212896D03*
X512076Y209742D03*
X510501D03*
Y216828D03*
X512076D03*
X513651D03*
X576672Y222740D03*
X575098D03*
Y228252D03*
G54D109*
G01X65710Y376042D02*
Y373984D01*
X67580Y372114D01*
Y366588D01*
X67681Y366487D01*
G01X61280Y380803D02*
Y378342D01*
X63580Y376042D01*
X65710D01*
G01X254470Y1553240D02*
Y1550971D01*
X254396Y1550897D01*
G01X399625Y483094D02*
Y479119D01*
G01X404743Y490476D02*
Y494451D01*
G01X400905Y1598560D02*
Y1596091D01*
G01X413425Y483017D02*
Y479042D01*
G01X418543Y490399D02*
Y494374D01*
G01X410379Y1569803D02*
Y1564460D01*
X411319Y1563520D01*
G01D02*
Y1561817D01*
X410672Y1561170D01*
G01X413419Y1563520D02*
Y1561750D01*
X414202Y1560967D01*
Y1559396D01*
G01X415379Y1569803D02*
Y1565480D01*
X413419Y1563520D01*
G01X427225Y482940D02*
Y478965D01*
G01X432343Y490322D02*
Y494297D01*
G01X433661Y680765D02*
X435025D01*
X436130Y681870D01*
Y683281D01*
G01X434558Y1563907D02*
Y1565569D01*
X435374Y1566385D01*
Y1569803D01*
G01X440374D02*
Y1568615D01*
X436658Y1564899D01*
Y1563907D01*
G01X443040Y1557908D02*
X441088D01*
X437910Y1554730D01*
Y1553910D01*
G01X435374Y1569803D02*
Y1573764D01*
X438136Y1576526D01*
X440846D01*
G01X429391Y1596983D02*
X428371Y1598003D01*
X426688D01*
G01X457317Y1557509D02*
X455196Y1559630D01*
X447962D01*
X446240Y1557908D01*
G01D02*
X443040D01*
G01X450749Y1573204D02*
X451651D01*
X454288Y1575841D01*
Y1576826D01*
G01X526193Y1558650D02*
X523643Y1561200D01*
X482480D01*
X478789Y1557509D01*
X457317D01*
G01X531580Y1551520D02*
X528490D01*
X528470Y1551500D01*
G01X528940Y1548260D02*
X528470Y1548730D01*
Y1551500D01*
G01X646556Y1692156D02*
Y1688605D01*
X645832Y1687881D01*
X642366D01*
X641355Y1686870D01*
Y1685970D01*
G01D02*
Y1685120D01*
X639284Y1683049D01*
G01X649750Y1652400D02*
X649284Y1652866D01*
Y1658333D01*
G01X649750Y1652400D02*
Y1650610D01*
X649266Y1650126D01*
G01X651850Y1652400D02*
Y1654815D01*
X654284Y1657249D01*
Y1658333D01*
G01X654712Y1653813D02*
X653299Y1652400D01*
X651850D01*
G01X663439Y1640404D02*
X666729D01*
G01D02*
X669148D01*
X669648Y1640904D01*
Y1640917D01*
G01X1188192Y585629D02*
Y589263D01*
G01X1262269Y1583897D02*
Y1586184D01*
X1262253Y1586200D01*
G01X1726334Y660931D02*
Y656313D01*
X1726409Y656238D01*
G01X1726334Y667545D02*
Y670345D01*
G01X1780929Y182463D02*
Y179408D01*
G01X1778500Y186911D02*
Y183790D01*
X181503Y1516264D03*
Y1518626D03*
Y1520988D03*
Y1513902D03*
X179598Y1511505D03*
X181961D03*
X183548Y1517445D03*
Y1519807D03*
Y1522169D03*
X184323Y1511505D03*
X181503Y1530437D03*
Y1525713D03*
Y1532799D03*
Y1523351D03*
Y1528075D03*
X183548Y1531618D03*
Y1533980D03*
Y1536343D03*
Y1524532D03*
X181503Y1535162D03*
X179598Y1538431D03*
X181961D03*
X184323D03*
X189047Y1511505D03*
X189254Y1522200D03*
X193772Y1511505D03*
X193979Y1522200D03*
X198496Y1511505D03*
X198703Y1522200D03*
X186685Y1511505D03*
X191409D03*
X196134D03*
X200858D03*
X189254Y1524169D03*
Y1526137D03*
X193979Y1524169D03*
Y1526137D03*
X198703Y1524169D03*
Y1526137D03*
X189254Y1528106D03*
X193979D03*
X198703D03*
X189047Y1538431D03*
X193772D03*
X198496D03*
X186685D03*
X191409D03*
X196134D03*
X200858D03*
X203221Y1511505D03*
X203428Y1522200D03*
X207945Y1511505D03*
X208152Y1522200D03*
X212669Y1511505D03*
X212876Y1522200D03*
X215032Y1511505D03*
X205583D03*
X210307D03*
X212876Y1524169D03*
Y1526137D03*
X203428Y1524169D03*
Y1526137D03*
X208152Y1524169D03*
Y1526137D03*
X203428Y1528106D03*
X208152D03*
X212876D03*
X203221Y1538431D03*
X207945D03*
X212669D03*
X215032D03*
X205583D03*
X210307D03*
X217394Y1511505D03*
X217601Y1522200D03*
X222118Y1511505D03*
X222325Y1522200D03*
X226843Y1511505D03*
X227050Y1522200D03*
X219756Y1511505D03*
X224480D03*
X229205D03*
X227050Y1526137D03*
X217601Y1524169D03*
Y1526137D03*
X222325Y1524169D03*
Y1526137D03*
X227050Y1524169D03*
X217601Y1528106D03*
X222325D03*
X227050D03*
X217394Y1538431D03*
X222118D03*
X226843D03*
X219756D03*
X224480D03*
X229205D03*
X231567Y1511505D03*
X231774Y1522200D03*
X236291Y1511505D03*
X236498Y1522200D03*
X241016Y1511505D03*
X241223Y1522200D03*
X245740Y1511505D03*
X245947Y1522200D03*
X233929Y1511505D03*
X238654D03*
X243378D03*
X231774Y1524169D03*
Y1526137D03*
X236498Y1524169D03*
Y1526137D03*
X241223Y1524169D03*
Y1526137D03*
X245947Y1524169D03*
Y1526137D03*
X231774Y1528106D03*
X236498D03*
X241223D03*
X245947D03*
X231567Y1538431D03*
X236291D03*
X241016D03*
X245740D03*
X233929D03*
X238654D03*
X243378D03*
X255189Y1511505D03*
X255396Y1522200D03*
X259913Y1511505D03*
X260121Y1522200D03*
X261082Y1515083D03*
X250465Y1511505D03*
X250672Y1522200D03*
X248102Y1511505D03*
X252827D03*
X257551D03*
X255396Y1524169D03*
Y1526137D03*
X250672Y1524169D03*
Y1526137D03*
X255396Y1528106D03*
X261082Y1524532D03*
Y1526894D03*
Y1529256D03*
X250672Y1528106D03*
X255189Y1538431D03*
X259913D03*
X250465D03*
X248102D03*
X252827D03*
X257551D03*
X263128Y1516264D03*
X262276Y1511505D03*
X264638D03*
X263128Y1513902D03*
Y1518626D03*
Y1530437D03*
Y1525713D03*
Y1532799D03*
Y1528075D03*
X262276Y1538431D03*
X264638D03*
X309565Y1516264D03*
Y1518626D03*
Y1520988D03*
Y1513902D03*
X307660Y1511505D03*
X310023D03*
X311610Y1517445D03*
Y1519807D03*
Y1522169D03*
X312385Y1511505D03*
X317109D03*
X317316Y1522200D03*
X314747Y1511505D03*
X319471D03*
X309565Y1530437D03*
Y1525713D03*
X317316Y1524169D03*
Y1526137D03*
X309565Y1532799D03*
Y1523351D03*
Y1528075D03*
X311610Y1531618D03*
Y1533980D03*
Y1536343D03*
Y1524532D03*
X317316Y1528106D03*
X309565Y1535162D03*
X307660Y1538431D03*
X310023D03*
X312385D03*
X317109D03*
X314747D03*
X319471D03*
X321834Y1511505D03*
X322041Y1522200D03*
X326558Y1511505D03*
X326765Y1522200D03*
X331283Y1511505D03*
X331490Y1522200D03*
X324196Y1511505D03*
X328920D03*
X333645D03*
X322041Y1524169D03*
Y1526137D03*
X326765Y1524169D03*
Y1526137D03*
X331490Y1524169D03*
Y1526137D03*
X322041Y1528106D03*
X326765D03*
X331490D03*
X321834Y1538431D03*
X326558D03*
X331283D03*
X324196D03*
X328920D03*
X333645D03*
X336007Y1511505D03*
X336214Y1522200D03*
X340731Y1511505D03*
X340938Y1522200D03*
X345456Y1511505D03*
X345663Y1522200D03*
X350180Y1511505D03*
X350387Y1522200D03*
X343094Y1511505D03*
X347818D03*
X338369D03*
X340938Y1524169D03*
Y1526137D03*
X336214Y1524169D03*
Y1526137D03*
X345663Y1524169D03*
Y1526137D03*
X350387Y1524169D03*
Y1526137D03*
X336214Y1528106D03*
X340938D03*
X345663D03*
X350387D03*
X336007Y1538431D03*
X340731D03*
X345456D03*
X350180D03*
X343094D03*
X347818D03*
X338369D03*
X354905Y1511505D03*
X355112Y1522200D03*
X359629Y1511505D03*
X359836Y1522200D03*
X364353Y1511505D03*
X364560Y1522200D03*
X352542Y1511505D03*
X357267D03*
X361991D03*
X359836Y1524169D03*
Y1526137D03*
X364560Y1524169D03*
Y1526137D03*
X355112D03*
Y1524169D03*
Y1528106D03*
X359836D03*
X364560D03*
X354905Y1538431D03*
X359629D03*
X364353D03*
X352542D03*
X357267D03*
X361991D03*
X369078Y1511505D03*
X369285Y1522200D03*
X373802Y1511505D03*
X374009Y1522200D03*
X378527Y1511505D03*
X378734Y1522200D03*
X366716Y1511505D03*
X371440D03*
X376164D03*
X369285Y1524169D03*
Y1526137D03*
X374009Y1524169D03*
Y1526137D03*
X378734Y1524169D03*
Y1526137D03*
X369285Y1528106D03*
X374009D03*
X378734D03*
X369078Y1538431D03*
X373802D03*
X378527D03*
X366716D03*
X371440D03*
X376164D03*
X391190Y1516264D03*
X390338Y1511505D03*
X392700D03*
X383251D03*
X383458Y1522200D03*
X387975Y1511505D03*
X388183Y1522200D03*
X389144Y1515083D03*
X391190Y1513902D03*
Y1518626D03*
X380889Y1511505D03*
X385613D03*
X391190Y1530437D03*
Y1525713D03*
X383458Y1524169D03*
Y1526137D03*
X391190Y1532799D03*
X383458Y1528106D03*
X389144Y1524532D03*
Y1526894D03*
Y1529256D03*
X391190Y1528075D03*
X390338Y1538431D03*
X392700D03*
X383251D03*
X387975D03*
X380889D03*
X385613D03*
X445676Y1516264D03*
Y1518626D03*
Y1520988D03*
Y1513902D03*
X443771Y1511505D03*
X446134D03*
X447721Y1517445D03*
Y1519807D03*
Y1522169D03*
X448496Y1511505D03*
X453220D03*
X453427Y1522200D03*
X450858Y1511505D03*
X445676Y1530437D03*
Y1525713D03*
X453427Y1524169D03*
Y1526137D03*
X445676Y1532799D03*
Y1523351D03*
Y1528075D03*
X447721Y1531618D03*
Y1533980D03*
Y1536343D03*
Y1524532D03*
X453427Y1528106D03*
X445676Y1535162D03*
X443771Y1538431D03*
X446134D03*
X448496D03*
X453220D03*
X450858D03*
X457945Y1511505D03*
X458152Y1522200D03*
X462669Y1511505D03*
X462876Y1522200D03*
X467394Y1511505D03*
X467601Y1522200D03*
X455582Y1511505D03*
X460307D03*
X465031D03*
X469756D03*
X458152Y1524169D03*
Y1526137D03*
X462876Y1524169D03*
Y1526137D03*
X467601Y1524169D03*
Y1526137D03*
X458152Y1528106D03*
X462876D03*
X467601D03*
X457945Y1538431D03*
X462669D03*
X467394D03*
X455582D03*
X460307D03*
X465031D03*
X469756D03*
X472118Y1511505D03*
X472325Y1522200D03*
X476842Y1511505D03*
X477049Y1522200D03*
X481567Y1511505D03*
X481774Y1522200D03*
X479205Y1511505D03*
X483929D03*
X474480D03*
X477049Y1524169D03*
Y1526137D03*
X472325Y1524169D03*
Y1526137D03*
X481774Y1524169D03*
Y1526137D03*
X472325Y1528106D03*
X477049D03*
X481774D03*
X472118Y1538431D03*
X476842D03*
X481567D03*
X479205D03*
X483929D03*
X474480D03*
X486291Y1511505D03*
X486498Y1522200D03*
X491016Y1511505D03*
X491223Y1522200D03*
X495740Y1511505D03*
X495947Y1522200D03*
X488653Y1511505D03*
X493378D03*
X498102D03*
X495947Y1524169D03*
Y1526137D03*
X491223D03*
X486498Y1524169D03*
Y1526137D03*
X491223Y1524169D03*
X486498Y1528106D03*
X491223D03*
X495947D03*
X486291Y1538431D03*
X491016D03*
X495740D03*
X488653D03*
X493378D03*
X498102D03*
X500464Y1511505D03*
X500671Y1522200D03*
X505189Y1511505D03*
X505396Y1522200D03*
X509913Y1511505D03*
X510120Y1522200D03*
X502827Y1511505D03*
X507551D03*
X512275D03*
X500671Y1524169D03*
Y1526137D03*
X505396Y1524169D03*
Y1526137D03*
X510120Y1524169D03*
Y1526137D03*
X500671Y1528106D03*
X505396D03*
X510120D03*
X500464Y1538431D03*
X505189D03*
X509913D03*
X502827D03*
X507551D03*
X512275D03*
X527301Y1516264D03*
X526449Y1511505D03*
X528811D03*
X519362D03*
X519569Y1522200D03*
X524086Y1511505D03*
X524294Y1522200D03*
X525255Y1515083D03*
X527301Y1513902D03*
Y1518626D03*
X514638Y1511505D03*
X514845Y1522200D03*
X517000Y1511505D03*
X521724D03*
X527301Y1530437D03*
Y1525713D03*
X519569Y1524169D03*
Y1526137D03*
X514845Y1524169D03*
Y1526137D03*
X527301Y1532799D03*
X519569Y1528106D03*
X525255Y1524532D03*
Y1526894D03*
Y1529256D03*
X527301Y1528075D03*
X514845Y1528106D03*
X526449Y1538431D03*
X528811D03*
X519362D03*
X524086D03*
X514638D03*
X517000D03*
X521724D03*
X573738Y1516264D03*
Y1518626D03*
Y1520988D03*
Y1513902D03*
X571833Y1511505D03*
X573738Y1530437D03*
Y1525713D03*
Y1532799D03*
Y1523351D03*
Y1528075D03*
Y1535162D03*
X571833Y1538431D03*
X574196Y1511505D03*
X575783Y1517445D03*
Y1519807D03*
Y1522169D03*
X576558Y1511505D03*
X581282D03*
X581489Y1522200D03*
X586007Y1511505D03*
X586214Y1522200D03*
X578920Y1511505D03*
X583644D03*
X588369D03*
X581489Y1524169D03*
Y1526137D03*
X586214Y1524169D03*
Y1526137D03*
X575783Y1531618D03*
Y1533980D03*
Y1536343D03*
Y1524532D03*
X581489Y1528106D03*
X586214D03*
X574196Y1538431D03*
X576558D03*
X581282D03*
X586007D03*
X578920D03*
X583644D03*
X588369D03*
X590731Y1511505D03*
X590938Y1522200D03*
X595456Y1511505D03*
X595663Y1522200D03*
X600180Y1511505D03*
X600387Y1522200D03*
X593093Y1511505D03*
X597818D03*
X602542D03*
X590938Y1524169D03*
Y1526137D03*
X595663Y1524169D03*
Y1526137D03*
X600387Y1524169D03*
Y1526137D03*
X590938Y1528106D03*
X595663D03*
X600387D03*
X590731Y1538431D03*
X595456D03*
X600180D03*
X593093D03*
X597818D03*
X602542D03*
X604904Y1511505D03*
X605111Y1522200D03*
X609629Y1511505D03*
X609836Y1522200D03*
X614353Y1511505D03*
X614560Y1522200D03*
X607267Y1511505D03*
X611991D03*
X616715D03*
X605111Y1524169D03*
Y1526137D03*
X609836Y1524169D03*
Y1526137D03*
X614560Y1524169D03*
Y1526137D03*
X605111Y1528106D03*
X609836D03*
X614560D03*
X604904Y1538431D03*
X609629D03*
X614353D03*
X607267D03*
X611991D03*
X616715D03*
X619078Y1511505D03*
X619285Y1522200D03*
X623802Y1511505D03*
X624009Y1522200D03*
X628526Y1511505D03*
X628733Y1522200D03*
X633251Y1511505D03*
X633458Y1522200D03*
X621440Y1511505D03*
X626164D03*
X630889D03*
X624009Y1524169D03*
Y1526137D03*
X628733Y1524169D03*
Y1526137D03*
X633458Y1524169D03*
Y1526137D03*
X619285D03*
Y1524169D03*
Y1528106D03*
X624009D03*
X628733D03*
X633458D03*
X619078Y1538431D03*
X623802D03*
X628526D03*
X633251D03*
X621440D03*
X626164D03*
X630889D03*
X647424Y1511505D03*
X647631Y1522200D03*
X637975Y1511505D03*
X638182Y1522200D03*
X642700Y1511505D03*
X642907Y1522200D03*
X635613Y1511505D03*
X640337D03*
X645062D03*
X647631Y1524169D03*
Y1526137D03*
X638182Y1524169D03*
Y1526137D03*
X642907Y1524169D03*
Y1526137D03*
X647631Y1528106D03*
X638182D03*
X642907D03*
X647424Y1538431D03*
X637975D03*
X642700D03*
X635613D03*
X640337D03*
X645062D03*
X655363Y1516264D03*
X654511Y1511505D03*
X656873D03*
X652148D03*
X652356Y1522200D03*
X653317Y1515083D03*
X655363Y1513902D03*
Y1518626D03*
X649786Y1511505D03*
X655363Y1530437D03*
Y1525713D03*
Y1532799D03*
X653317Y1524532D03*
Y1526894D03*
Y1529256D03*
X655363Y1528075D03*
X654511Y1538431D03*
X656873D03*
X652148D03*
X649786D03*
X1189376Y1549264D03*
Y1551626D03*
Y1546902D03*
X1187471Y1544505D03*
X1189834D03*
X1191421Y1550445D03*
X1192196Y1544505D03*
X1196920D03*
X1194558D03*
X1199282D03*
X1189376Y1553988D03*
Y1563437D03*
Y1558713D03*
X1197127Y1557169D03*
Y1559137D03*
X1189376Y1565799D03*
Y1556351D03*
Y1561075D03*
X1191421Y1564618D03*
Y1566980D03*
Y1552807D03*
Y1555169D03*
Y1557532D03*
X1197127Y1555200D03*
Y1561106D03*
X1187471Y1571431D03*
X1189834D03*
X1191421Y1569343D03*
X1192196Y1571431D03*
X1196920D03*
X1189376Y1568162D03*
X1194558Y1571431D03*
X1199282D03*
X1201645Y1544505D03*
X1206369D03*
X1211094D03*
X1204007D03*
X1208731D03*
X1213456D03*
X1201852Y1557169D03*
Y1559137D03*
X1206576Y1557169D03*
Y1559137D03*
X1211301Y1557169D03*
Y1559137D03*
X1201852Y1555200D03*
Y1561106D03*
X1206576Y1555200D03*
Y1561106D03*
X1211301Y1555200D03*
Y1561106D03*
X1201645Y1571431D03*
X1206369D03*
X1211094D03*
X1204007D03*
X1208731D03*
X1213456D03*
X1215818Y1544505D03*
X1220542D03*
X1225267D03*
X1229991D03*
X1222905D03*
X1227629D03*
X1218180D03*
X1220749Y1557169D03*
Y1559137D03*
X1216025Y1557169D03*
Y1559137D03*
X1225474Y1557169D03*
Y1559137D03*
X1216025Y1555200D03*
Y1561106D03*
X1220749Y1555200D03*
Y1561106D03*
X1225474Y1555200D03*
Y1561106D03*
X1215818Y1571431D03*
X1220542D03*
X1225267D03*
X1229991D03*
X1222905D03*
X1227629D03*
X1218180D03*
X1234716Y1544505D03*
X1239440D03*
X1244164D03*
X1232353D03*
X1237078D03*
X1241802D03*
X1239647Y1557169D03*
Y1559137D03*
X1244371Y1557169D03*
Y1559137D03*
X1234923D03*
X1230198Y1557169D03*
Y1559137D03*
X1234923Y1557169D03*
X1230198Y1555200D03*
Y1561106D03*
X1234923Y1555200D03*
Y1561106D03*
X1239647Y1555200D03*
Y1561106D03*
X1244371Y1555200D03*
Y1561106D03*
X1234716Y1571431D03*
X1239440D03*
X1244164D03*
X1232353D03*
X1237078D03*
X1241802D03*
X1248889Y1544505D03*
X1253613D03*
X1258338D03*
X1246527D03*
X1251251D03*
X1255975D03*
X1249096Y1557169D03*
Y1559137D03*
X1253820Y1557169D03*
Y1559137D03*
X1258545Y1557169D03*
Y1559137D03*
X1249096Y1555200D03*
Y1561106D03*
X1253820Y1555200D03*
Y1561106D03*
X1258545Y1555200D03*
Y1561106D03*
X1248889Y1571431D03*
X1253613D03*
X1258338D03*
X1246527D03*
X1251251D03*
X1255975D03*
X1271001Y1549264D03*
X1270149Y1544505D03*
X1272511D03*
X1263062D03*
X1267786D03*
X1268955Y1548083D03*
X1271001Y1546902D03*
Y1551626D03*
X1260700Y1544505D03*
X1265424D03*
X1271001Y1563437D03*
Y1558713D03*
X1263269Y1557169D03*
Y1559137D03*
X1271001Y1565799D03*
X1263269Y1555200D03*
Y1561106D03*
X1267994Y1555200D03*
X1268955Y1557532D03*
Y1559894D03*
Y1562256D03*
X1271001Y1561075D03*
X1270149Y1571431D03*
X1272511D03*
X1263062D03*
X1267786D03*
X1260700D03*
X1265424D03*
X1317438Y1549264D03*
Y1551626D03*
Y1546902D03*
X1315533Y1544505D03*
X1317896D03*
X1319483Y1550445D03*
X1317438Y1553988D03*
Y1563437D03*
Y1558713D03*
Y1565799D03*
Y1556351D03*
Y1561075D03*
X1319483Y1564618D03*
Y1566980D03*
Y1552807D03*
Y1555169D03*
Y1557532D03*
X1315533Y1571431D03*
X1317896D03*
X1319483Y1569343D03*
X1317438Y1568162D03*
X1320258Y1544505D03*
X1324982D03*
X1329707D03*
X1334431D03*
X1322620D03*
X1327344D03*
X1332069D03*
X1325189Y1557169D03*
Y1559137D03*
X1329914Y1557169D03*
Y1559137D03*
X1325189Y1555200D03*
Y1561106D03*
X1329914Y1555200D03*
Y1561106D03*
X1320258Y1571431D03*
X1324982D03*
X1329707D03*
X1334431D03*
X1322620D03*
X1327344D03*
X1332069D03*
X1339156Y1544505D03*
X1343880D03*
X1348604D03*
X1336793D03*
X1341518D03*
X1346242D03*
X1348811Y1557169D03*
Y1559137D03*
X1334638Y1557169D03*
Y1559137D03*
X1339363Y1557169D03*
Y1559137D03*
X1344087Y1557169D03*
Y1559137D03*
X1334638Y1555200D03*
Y1561106D03*
X1339363Y1555200D03*
Y1561106D03*
X1344087Y1555200D03*
Y1561106D03*
X1348811Y1555200D03*
Y1561106D03*
X1339156Y1571431D03*
X1343880D03*
X1348604D03*
X1336793D03*
X1341518D03*
X1346242D03*
X1353329Y1544505D03*
X1358053D03*
X1362778D03*
X1350967D03*
X1355691D03*
X1360415D03*
X1362985Y1559137D03*
X1353536Y1557169D03*
Y1559137D03*
X1358260Y1557169D03*
Y1559137D03*
X1362985Y1557169D03*
X1353536Y1555200D03*
Y1561106D03*
X1358260Y1555200D03*
Y1561106D03*
X1362985Y1555200D03*
Y1561106D03*
X1353329Y1571431D03*
X1358053D03*
X1362778D03*
X1350967D03*
X1355691D03*
X1360415D03*
X1367502Y1544505D03*
X1372226D03*
X1376951D03*
X1365140D03*
X1369864D03*
X1374589D03*
X1367709Y1557169D03*
Y1559137D03*
X1372433Y1557169D03*
Y1559137D03*
X1377158Y1557169D03*
Y1559137D03*
X1367709Y1555200D03*
Y1561106D03*
X1372433Y1555200D03*
Y1561106D03*
X1377158Y1555200D03*
Y1561106D03*
X1367502Y1571431D03*
X1372226D03*
X1376951D03*
X1365140D03*
X1369864D03*
X1374589D03*
X1391124Y1544505D03*
X1381675D03*
X1386400D03*
X1379313D03*
X1384037D03*
X1388762D03*
X1393486D03*
X1391331Y1557169D03*
Y1559137D03*
X1381882Y1557169D03*
Y1559137D03*
X1386607Y1557169D03*
Y1559137D03*
X1391331Y1555200D03*
Y1561106D03*
X1381882Y1555200D03*
Y1561106D03*
X1386607Y1555200D03*
Y1561106D03*
X1391124Y1571431D03*
X1381675D03*
X1386400D03*
X1379313D03*
X1384037D03*
X1388762D03*
X1393486D03*
X1399063Y1549264D03*
X1398211Y1544505D03*
X1400573D03*
X1395848D03*
X1397017Y1548083D03*
X1399063Y1546902D03*
Y1551626D03*
Y1563437D03*
Y1558713D03*
Y1565799D03*
X1396056Y1555200D03*
X1397017Y1557532D03*
Y1559894D03*
Y1562256D03*
X1399063Y1561075D03*
X1398211Y1571431D03*
X1400573D03*
X1395848D03*
X1453550Y1549264D03*
Y1551626D03*
Y1546902D03*
X1451645Y1544505D03*
X1453550Y1553988D03*
Y1563437D03*
Y1558713D03*
Y1565799D03*
Y1556351D03*
Y1561075D03*
X1451645Y1571431D03*
X1453550Y1568162D03*
X1454008Y1544505D03*
X1455595Y1550445D03*
X1456370Y1544505D03*
X1461094D03*
X1465819D03*
X1458732D03*
X1463456D03*
X1468181D03*
X1461301Y1557169D03*
Y1559137D03*
X1466026Y1557169D03*
Y1559137D03*
X1455595Y1564618D03*
Y1566980D03*
Y1552807D03*
Y1555169D03*
Y1557532D03*
X1461301Y1555200D03*
Y1561106D03*
X1466026Y1555200D03*
Y1561106D03*
X1454008Y1571431D03*
X1455595Y1569343D03*
X1456370Y1571431D03*
X1461094D03*
X1465819D03*
X1458732D03*
X1463456D03*
X1468181D03*
X1470543Y1544505D03*
X1475268D03*
X1479992D03*
X1472905D03*
X1477630D03*
X1482354D03*
X1470750Y1557169D03*
Y1559137D03*
X1475475Y1557169D03*
Y1559137D03*
X1480199Y1557169D03*
Y1559137D03*
X1470750Y1555200D03*
Y1561106D03*
X1475475Y1555200D03*
Y1561106D03*
X1480199Y1555200D03*
Y1561106D03*
X1470543Y1571431D03*
X1475268D03*
X1479992D03*
X1472905D03*
X1477630D03*
X1482354D03*
X1484716Y1544505D03*
X1489441D03*
X1494165D03*
X1487079D03*
X1491803D03*
X1496527D03*
X1484923Y1557169D03*
Y1559137D03*
X1489648Y1557169D03*
Y1559137D03*
X1494372Y1557169D03*
Y1559137D03*
X1484923Y1555200D03*
Y1561106D03*
X1489648Y1555200D03*
Y1561106D03*
X1494372Y1555200D03*
Y1561106D03*
X1484716Y1571431D03*
X1489441D03*
X1494165D03*
X1487079D03*
X1491803D03*
X1496527D03*
X1498890Y1544505D03*
X1503614D03*
X1508338D03*
X1513063D03*
X1501252D03*
X1505976D03*
X1510701D03*
X1503821Y1557169D03*
Y1559137D03*
X1508545Y1557169D03*
Y1559137D03*
X1513270Y1557169D03*
Y1559137D03*
X1499097D03*
Y1557169D03*
Y1555200D03*
Y1561106D03*
X1503821Y1555200D03*
Y1561106D03*
X1508545Y1555200D03*
Y1561106D03*
X1513270Y1555200D03*
Y1561106D03*
X1498890Y1571431D03*
X1503614D03*
X1508338D03*
X1513063D03*
X1501252D03*
X1505976D03*
X1510701D03*
X1527236Y1544505D03*
X1517787D03*
X1522512D03*
X1515425D03*
X1520149D03*
X1524874D03*
X1527443Y1557169D03*
Y1559137D03*
X1517994Y1557169D03*
Y1559137D03*
X1522719Y1557169D03*
Y1559137D03*
X1527443Y1555200D03*
Y1561106D03*
X1517994Y1555200D03*
Y1561106D03*
X1522719Y1555200D03*
Y1561106D03*
X1527236Y1571431D03*
X1517787D03*
X1522512D03*
X1515425D03*
X1520149D03*
X1524874D03*
X1535175Y1549264D03*
X1534323Y1544505D03*
X1536685D03*
X1531960D03*
X1533129Y1548083D03*
X1535175Y1546902D03*
Y1551626D03*
X1529598Y1544505D03*
X1535175Y1563437D03*
Y1558713D03*
Y1565799D03*
X1532168Y1555200D03*
X1533129Y1557532D03*
Y1559894D03*
Y1562256D03*
X1535175Y1561075D03*
X1534323Y1571431D03*
X1536685D03*
X1531960D03*
X1529598D03*
X1581612Y1549264D03*
Y1551626D03*
Y1546902D03*
X1579707Y1544505D03*
X1582070D03*
X1583657Y1550445D03*
X1584432Y1544505D03*
X1586794D03*
X1581612Y1553988D03*
Y1563437D03*
Y1558713D03*
Y1565799D03*
Y1556351D03*
Y1561075D03*
X1583657Y1564618D03*
Y1566980D03*
Y1552807D03*
Y1555169D03*
Y1557532D03*
X1579707Y1571431D03*
X1582070D03*
X1583657Y1569343D03*
X1584432Y1571431D03*
X1581612Y1568162D03*
X1586794Y1571431D03*
X1589156Y1544505D03*
X1593881D03*
X1598605D03*
X1591518D03*
X1596243D03*
X1600967D03*
X1589363Y1557169D03*
Y1559137D03*
X1594088Y1557169D03*
Y1559137D03*
X1598812Y1557169D03*
Y1559137D03*
X1589363Y1555200D03*
Y1561106D03*
X1594088Y1555200D03*
Y1561106D03*
X1598812Y1555200D03*
Y1561106D03*
X1589156Y1571431D03*
X1593881D03*
X1598605D03*
X1591518D03*
X1596243D03*
X1600967D03*
X1603330Y1544505D03*
X1608054D03*
X1612778D03*
X1617503D03*
X1615141D03*
X1605692D03*
X1610416D03*
X1612985Y1557169D03*
Y1559137D03*
X1603537Y1557169D03*
Y1559137D03*
X1608261Y1557169D03*
Y1559137D03*
X1603537Y1555200D03*
Y1561106D03*
X1608261Y1555200D03*
Y1561106D03*
X1612985Y1555200D03*
Y1561106D03*
X1603330Y1571431D03*
X1608054D03*
X1612778D03*
X1617503D03*
X1615141D03*
X1605692D03*
X1610416D03*
X1622227Y1544505D03*
X1626952D03*
X1631676D03*
X1619865D03*
X1624589D03*
X1629314D03*
X1631883Y1557169D03*
Y1559137D03*
X1627159D03*
X1617710Y1557169D03*
Y1559137D03*
X1622434Y1557169D03*
Y1559137D03*
X1627159Y1557169D03*
X1617710Y1555200D03*
Y1561106D03*
X1622434Y1555200D03*
Y1561106D03*
X1627159Y1555200D03*
Y1561106D03*
X1631883Y1555200D03*
Y1561106D03*
X1622227Y1571431D03*
X1626952D03*
X1631676D03*
X1619865D03*
X1624589D03*
X1629314D03*
X1636400Y1544505D03*
X1641125D03*
X1645849D03*
X1634038D03*
X1638763D03*
X1643487D03*
X1636607Y1557169D03*
Y1559137D03*
X1641332Y1557169D03*
Y1559137D03*
X1646056Y1557169D03*
Y1559137D03*
X1636607Y1555200D03*
Y1561106D03*
X1641332Y1555200D03*
Y1561106D03*
X1646056Y1555200D03*
Y1561106D03*
X1636400Y1571431D03*
X1641125D03*
X1645849D03*
X1634038D03*
X1638763D03*
X1643487D03*
X1662385Y1544505D03*
X1655298D03*
X1660022D03*
X1661191Y1548083D03*
X1650574Y1544505D03*
X1648211D03*
X1652936D03*
X1657660D03*
X1655505Y1557169D03*
Y1559137D03*
X1650781Y1557169D03*
Y1559137D03*
X1655505Y1555200D03*
Y1561106D03*
X1660230Y1555200D03*
X1661191Y1557532D03*
Y1559894D03*
Y1562256D03*
X1650781Y1555200D03*
Y1561106D03*
X1662385Y1571431D03*
X1655298D03*
X1660022D03*
X1650574D03*
X1648211D03*
X1652936D03*
X1657660D03*
X1663237Y1549264D03*
X1664747Y1544505D03*
X1663237Y1546902D03*
Y1551626D03*
Y1563437D03*
Y1558713D03*
Y1565799D03*
Y1561075D03*
X1664747Y1571431D03*
G54D316*
X1762824Y709079D03*
G54D344*
G01X68133Y1593471D02*
X70460Y1595798D01*
Y1600665D01*
G01X69216Y1608318D02*
X70207D01*
X70460Y1608065D01*
Y1600665D01*
G01X74133Y1610896D02*
X73527D01*
X71380Y1613043D01*
X69216D01*
G01X72255Y1616730D02*
X71218Y1617767D01*
X69216D01*
G01X74134Y1621396D02*
X72080Y1619342D01*
X69216D01*
G01X79058Y1625396D02*
X76832Y1627622D01*
X75380D01*
G01D02*
Y1625627D01*
X70670Y1620917D01*
X69216D01*
G01X1734962Y1662965D02*
X1737016Y1665019D01*
X1739880D01*
G01X1734500Y1656965D02*
Y1659518D01*
X1738426Y1663444D01*
X1739880D01*
G01X1730038Y1658965D02*
X1732038Y1656965D01*
X1734500D01*
G01X1735463Y1684165D02*
Y1688890D01*
G01Y1684165D02*
X1738636Y1680992D01*
Y1676296D01*
X1738889Y1676043D01*
X1739880D01*
G01X1734963Y1673465D02*
X1735569D01*
X1737716Y1671318D01*
X1739880D01*
G01X1729436Y1690240D02*
X1731861D01*
X1731936Y1690165D01*
G54D335*
G01X306842Y890238D02*
G02X305250Y888646I-1592J0D01*
G01X303781D01*
X300295Y885160D01*
G01X312393Y893427D02*
X312768Y892781D01*
Y892415D01*
G02X312318Y891961I-454J0D01*
G02X311690Y892138I74J1466D01*
G01X311657Y892157D01*
G03X309429I-1114J-1919D01*
G01X309396Y892138D01*
G02X307956Y892157I-703J1289D01*
G03X305273Y891807I-1114J-1919D01*
G01X304393Y890926D01*
X301982D01*
X300645Y889589D01*
G01X306842Y902994D02*
X307219Y902345D01*
G02X306644Y901539I-500J-252D01*
G02X306139Y901705I198J1455D01*
G01X306106Y901724D01*
G03X304419Y902216I-1687J-2646D01*
G01X301261D01*
X300451Y901406D01*
G01X314244Y896616D02*
G03X312197Y897594I-2337J-2261D01*
G02X311279Y897886I198J2210D01*
G03X309807I-736J-1270D01*
G02X307579I-1114J1919D01*
G03X306105I-737J-1270D01*
G03X305804Y897654I738J-1269D01*
G01X304738Y896589D01*
X300596D01*
X299991Y895984D01*
X299992Y895616D01*
X299939Y895563D01*
G01X312393Y899805D02*
X312790Y899122D01*
G02X312215Y898348I-508J-223D01*
G02X311690Y898516I177J1458D01*
G01X311657Y898535D01*
G03X309429I-1114J-1919D01*
G01X309396Y898516D01*
G02X307956Y898535I-703J1289D01*
G03X305273Y898185I-1114J-1919D01*
G01X304427Y897339D01*
X300285D01*
X299460Y896514D01*
X299092D01*
X299039Y896461D01*
G01X306842Y909371D02*
X307208Y908741D01*
G02X306689Y907911I-463J-288D01*
G02X306139Y908082I152J1460D01*
G01X306106Y908101D01*
G03X303006Y908936I-3100J-5337D01*
G01X300389D01*
G01X312393Y906182D02*
X312790Y905500D01*
G02X312215Y904726I-508J-223D01*
G02X311690Y904894I177J1458D01*
G01X311657Y904913D01*
G03X309429I-1114J-1919D01*
G01X309396Y904894D01*
G02X307956Y904913I-703J1289D01*
G03X305728I-1114J-1919D01*
G02X305114Y904719I-739J1269D01*
G02X304992Y904714I-121J1464D01*
G01X299443D01*
X299435Y904706D01*
G01X312393Y912560D02*
X312807Y911848D01*
G02X312399Y911093I-541J-195D01*
G02X311690Y911272I-7J1466D01*
G01X311686Y911274D01*
X311657Y911291D01*
G03X309429I-1114J-1919D01*
G01X309396Y911272D01*
G02X307956Y911291I-703J1288D01*
G03X305728I-1114J-1919D01*
G02X304992Y911091I-740J1268D01*
G01X301584D01*
X300869Y911806D01*
G01X314244Y915749D02*
G03X312197Y916727I-2337J-2261D01*
G02X311279Y917019I198J2210D01*
G03X309807I-736J-1270D01*
G02X307579I-1114J1919D01*
G03X306139Y917038I-737J-1270D01*
G01X306106Y917019D01*
G02X305178Y916726I-1116J1918D01*
G02X304993Y916719I-176J2212D01*
G01X301044D01*
X300624Y917139D01*
X299374D01*
X299114Y916879D01*
X299039D01*
G01X312393Y918938D02*
X312790Y918255D01*
G02X312215Y917481I-508J-223D01*
G02X311690Y917649I177J1458D01*
G01X311657Y917668D01*
G03X309429I-1114J-1919D01*
G01X309396Y917649D01*
G02X307956Y917668I-703J1289D01*
G03X305728I-1114J-1919D01*
G02X305114Y917474I-739J1269D01*
G02X304992Y917469I-121J1464D01*
G01X301355D01*
X300935Y917889D01*
X299374D01*
X299114Y918149D01*
X299039D01*
G01X306842Y922127D02*
X307208Y921497D01*
G02X306689Y920667I-463J-288D01*
G02X306139Y920838I152J1460D01*
G01X306106Y920857D01*
G03X302880Y921726I-3226J-5555D01*
G01X299669D01*
X299329Y922066D01*
G01X312393Y925316D02*
Y925315D01*
X312807Y924603D01*
G02X312399Y923848I-541J-195D01*
G02X311690Y924027I-7J1466D01*
G01X311686Y924029D01*
X311657Y924046D01*
G03X309429I-1114J-1919D01*
G01X309396Y924027D01*
G02X307956Y924046I-703J1289D01*
G03X305728I-1114J-1919D01*
G02X304992Y923847I-738J1269D01*
G01X301378D01*
X299699Y925526D01*
X299459D01*
G01X306842Y928505D02*
X307208Y927875D01*
G02X306689Y927045I-463J-288D01*
G02X306139Y927216I152J1460D01*
G01X306106Y927235D01*
G03X304097Y927776I-2009J-3458D01*
G01X301039D01*
X299799Y929016D01*
X298999D01*
G01X312393Y931694D02*
Y931693D01*
X312807Y930981D01*
G02X312399Y930226I-541J-195D01*
G02X311690Y930405I-7J1466D01*
G01X311686Y930407D01*
X311657Y930424D01*
G03X309429I-1114J-1919D01*
G01X309396Y930405D01*
G02X307956Y930424I-703J1289D01*
G03X305728I-1114J-1919D01*
G02X304919Y930206I-809J1391D01*
G01X301639D01*
X300009Y931836D01*
X298959D01*
G01X306842Y941261D02*
X307208Y940631D01*
G02X306689Y939801I-463J-288D01*
G02X306139Y939972I152J1460D01*
G03X303537Y940696I-2602J-4313D01*
G01X301069D01*
X299539Y942226D01*
X299089D01*
G01X314244Y934883D02*
G03X312197Y935861I-2337J-2261D01*
G02X311279Y936153I198J2210D01*
G03X309807I-736J-1270D01*
G02X307579I-1114J1919D01*
G03X306139Y936172I-737J-1270D01*
G01X306106Y936153D01*
G02X305178Y935860I-1116J1918D01*
G02X304993Y935853I-176J2212D01*
G01X301364D01*
X300615Y936602D01*
X300465Y936786D01*
X299496D01*
X299236Y936526D01*
X299161D01*
G01X312393Y938072D02*
X312790Y937389D01*
G02X312215Y936615I-508J-223D01*
G02X311690Y936783I177J1458D01*
G01X311657Y936802D01*
G03X309429I-1114J-1919D01*
G01X309396Y936783D01*
G02X307956Y936802I-703J1289D01*
G03X305728I-1114J-1919D01*
G02X305114Y936608I-739J1269D01*
G02X304992Y936603I-121J1464D01*
G01X301675D01*
X301172Y937106D01*
X300821Y937536D01*
X299496D01*
X299236Y937796D01*
X299161D01*
G01X312393Y944450D02*
Y944449D01*
X312807Y943737D01*
G02X312399Y942982I-541J-195D01*
G02X311690Y943161I-7J1466D01*
G01X311686Y943163D01*
X311657Y943180D01*
G03X309429I-1114J-1919D01*
G01X309396Y943161D01*
G02X307956Y943180I-703J1289D01*
G03X305728I-1114J-1919D01*
G02X304897Y942956I-831J1429D01*
G01X301926D01*
X299966Y944916D01*
X299079D01*
G01X306842Y947639D02*
X307208Y947009D01*
G02X306689Y946179I-463J-288D01*
G02X306139Y946350I152J1460D01*
G03X302452Y947376I-3687J-6112D01*
G01X300919D01*
X300229Y948066D01*
X299099D01*
G01X312393Y950828D02*
Y950827D01*
X312807Y950115D01*
G02X312399Y949360I-541J-195D01*
G02X311690Y949539I-7J1466D01*
G01X311686Y949541D01*
X311657Y949558D01*
G03X309429I-1114J-1919D01*
G01X309396Y949539D01*
G02X307956Y949558I-703J1289D01*
G03X305728I-1114J-1919D01*
G02X304905Y949336I-823J1416D01*
G01X301749D01*
X300296Y950789D01*
G01X314244Y954017D02*
G03X312197Y954995I-2337J-2261D01*
G02X311279Y955287I198J2210D01*
G03X309807I-736J-1270D01*
G02X307579I-1114J1919D01*
G03X306139Y955306I-737J-1270D01*
G01X306106Y955287D01*
G02X305178Y954994I-1116J1918D01*
G02X304993Y954987I-176J2212D01*
G01X301465D01*
X300838Y955614D01*
X300673Y955786D01*
X299368D01*
X299108Y955526D01*
X299033D01*
G01X312393Y957206D02*
X312790Y956523D01*
G02X312215Y955749I-508J-223D01*
G02X311690Y955917I177J1458D01*
G01X311657Y955936D01*
G03X309429I-1114J-1919D01*
G01X309396Y955917D01*
G02X307956Y955936I-703J1289D01*
G03X305728I-1114J-1919D01*
G02X305114Y955742I-739J1269D01*
G02X304992Y955737I-121J1464D01*
G01X301776D01*
X301374Y956139D01*
X300994Y956536D01*
X299368D01*
X299108Y956796D01*
X299033D01*
G01X306842Y960395D02*
X307208Y959765D01*
G02X306689Y958935I-463J-288D01*
G02X306139Y959106I152J1460D01*
G01X306106Y959125D01*
G03X305780Y959280I-1113J-1920D01*
G03X303877Y959792I-3447J-9020D01*
G03X303577Y959816I-299J-1848D01*
G01X299159D01*
X299149Y959806D01*
G01X312393Y963584D02*
Y963583D01*
X312807Y962871D01*
G02X312399Y962116I-541J-195D01*
G02X311690Y962295I-7J1466D01*
G01X311686Y962297D01*
X311657Y962314D01*
G03X309429I-1114J-1919D01*
G01X309396Y962295D01*
G02X307956Y962314I-703J1289D01*
G03X305728I-1114J-1919D01*
G02X304919Y962096I-809J1391D01*
G01X301199D01*
X300799Y962496D01*
G01X306842Y966773D02*
X307208Y966143D01*
G02X306689Y965313I-463J-288D01*
G02X306139Y965484I152J1460D01*
G01X306106Y965503D01*
G03X305722Y965680I-1117J-1918D01*
G03X303562Y966046I-2160J-6188D01*
G01X300349D01*
X300009Y965706D01*
G01X312393Y969962D02*
Y969961D01*
X312807Y969249D01*
G02X312399Y968494I-541J-195D01*
G02X311690Y968673I-7J1466D01*
G01X311686Y968675D01*
X311657Y968692D01*
G03X309429I-1114J-1919D01*
G01X309396Y968673D01*
G02X307956Y968692I-703J1289D01*
G03X305728I-1114J-1919D01*
G02X304927Y968476I-801J1378D01*
G01X301349D01*
X300969Y968856D01*
G01X306842Y979529D02*
X307229Y978863D01*
G02X306687Y978069I-484J-251D01*
G02X306139Y978240I155J1460D01*
G01X306106Y978259D01*
G03X304992Y978559I-1114J-1918D01*
G01X300786D01*
X299599Y979746D01*
X299139D01*
G01X314244Y973151D02*
G03X312197Y974129I-2337J-2261D01*
G02X311279Y974421I198J2210D01*
G03X309807I-736J-1270D01*
G02X307579I-1114J1919D01*
G03X306139Y974440I-737J-1270D01*
G01X306106Y974421D01*
G02X305178Y974128I-1116J1918D01*
G02X304993Y974121I-176J2212D01*
G01X301242D01*
X300624Y974739D01*
X299374D01*
X299114Y974479D01*
X299039D01*
G01X312393Y976340D02*
X312790Y975657D01*
G02X312215Y974883I-508J-223D01*
G02X311690Y975051I177J1458D01*
G01X311657Y975070D01*
G03X309429I-1114J-1919D01*
G01X309396Y975051D01*
G02X307956Y975070I-703J1289D01*
G03X305728I-1114J-1919D01*
G02X305114Y974876I-739J1269D01*
G02X304992Y974871I-121J1464D01*
G01X301553D01*
X300935Y975489D01*
X299374D01*
X299114Y975749D01*
X299039D01*
G01X308693Y982718D02*
G03X306655Y983695I-2310J-2204D01*
G02X306209Y983779I186J2211D01*
G02X305933Y983899I368J1224D01*
G01X304955Y984466D01*
G03X302349Y985166I-2605J-4498D01*
G01X312393Y982718D02*
Y982717D01*
X312807Y982005D01*
G02X312399Y981250I-541J-195D01*
G02X311690Y981429I-7J1466D01*
G01X311686Y981431D01*
X311657Y981448D01*
G03X309429I-1114J-1919D01*
G01X309396Y981429D01*
G02X307956Y981448I-703J1289D01*
G03X305728I-1114J-1919D01*
G02X304905Y981226I-823J1416D01*
G01X301719D01*
X300429Y982516D01*
G01X306842Y998663D02*
X307208Y998033D01*
G02X306689Y997203I-463J-288D01*
G02X306139Y997374I152J1460D01*
G01X306106Y997393D01*
G03X303351Y998136I-2755J-4736D01*
G01X299539D01*
X299174Y998501D01*
G01X312393Y1001852D02*
Y1001851D01*
X312807Y1001139D01*
G02X312399Y1000384I-541J-195D01*
G02X311690Y1000563I-7J1466D01*
G01X311686Y1000565D01*
X311657Y1000582D01*
G03X309429I-1114J-1919D01*
G01X309396Y1000563D01*
G02X307956Y1000582I-703J1289D01*
G03X305728I-1114J-1919D01*
G02X304927Y1000366I-801J1378D01*
G01X301109D01*
X300224Y1001251D01*
G01X312393Y995474D02*
Y995473D01*
X312807Y994761D01*
G02X312399Y994006I-541J-195D01*
G02X311690Y994185I-7J1466D01*
G01X311686Y994187D01*
X311657Y994204D01*
G03X309429I-1114J-1919D01*
G01X309396Y994185D01*
G02X307956Y994204I-703J1289D01*
G03X305728I-1114J-1919D01*
G02X304882Y993976I-846J1454D01*
G01X301919D01*
G01X306842Y1011419D02*
X307208Y1010789D01*
G02X306689Y1009959I-463J-288D01*
G02X306139Y1010130I152J1460D01*
G01X306106Y1010149D01*
G03X305178Y1010442I-1116J-1918D01*
G01X305175Y1010446D01*
G03X304622Y1010468I-553J-6934D01*
G01X304238D01*
X304234Y1010464D01*
X302521Y1012177D01*
Y1012594D01*
X302468Y1012647D01*
G01X308693Y1008230D02*
G03X306655Y1009207I-2310J-2204D01*
G02X305728Y1009500I189J2211D01*
G03X305114Y1009694I-739J-1269D01*
G03X304630Y1009714I-484J-5854D01*
G01X303923D01*
X301991Y1011646D01*
X301573D01*
X301520Y1011699D01*
G01X306842Y1005041D02*
X307229Y1004375D01*
G02X306687Y1003581I-484J-251D01*
G02X306139Y1003752I155J1460D01*
G01X306106Y1003771D01*
G03X304992Y1004071I-1114J-1918D01*
G01X301294D01*
X297653Y1007712D01*
G01X315425Y1033387D02*
G02X313629Y1032417I-1746J1085D01*
G03X312460Y1032117I-54J-2218D01*
G02X310988I-736J1270D01*
G03X308760I-1114J-1919D01*
G02X307320Y1032098I-737J1270D01*
G01X307287Y1032117D01*
G03X306359Y1032410I-1116J-1918D01*
G03X306183Y1032417I-176J-2207D01*
G01X301368D01*
X300778Y1033007D01*
X299599D01*
G01X309874Y1036576D02*
G02X307798Y1035595I-2427J2450D01*
G03X306909Y1035306I226J-2207D01*
G02X306173Y1035107I-738J1269D01*
G01X302298D01*
X301641Y1035764D01*
X299599D01*
G01X315425Y1039765D02*
G02X313629Y1038795I-1746J1085D01*
G03X312460Y1038495I-54J-2218D01*
G02X310988I-736J1270D01*
G03X308760I-1114J-1919D01*
G02X307320Y1038476I-737J1270D01*
G01X307287Y1038495D01*
G03X306359Y1038788I-1116J-1918D01*
G03X306174Y1038795I-176J-2212D01*
G01X305800D01*
X305509Y1039086D01*
X302199D01*
X301557Y1038444D01*
X299599D01*
G01X309874Y1049332D02*
G02X308107Y1048361I-1694J989D01*
G03X306909Y1048062I-83J-2217D01*
G02X306173Y1047863I-738J1269D01*
G01X302772D01*
X301969Y1048666D01*
G01X309874Y1042954D02*
G02X307798Y1041973I-2427J2450D01*
G03X306909Y1041684I226J-2207D01*
G02X306173Y1041485I-738J1269D01*
G01X301070D01*
X301069Y1041486D01*
G01X309874Y1062088D02*
G02X307798Y1061107I-2427J2450D01*
G03X306909Y1060818I226J-2207D01*
G02X306173Y1060619I-738J1269D01*
G01X300367D01*
X299550Y1061436D01*
G01X315425Y1065277D02*
G02X313378Y1064299I-2337J2261D01*
G03X312460Y1064007I198J-2210D01*
G02X310988I-736J1270D01*
G03X308760I-1114J-1919D01*
G02X307320Y1063988I-737J1270D01*
G01X307287Y1064007D01*
G03X306359Y1064300I-1116J-1918D01*
G03X306174Y1064307I-176J-2212D01*
G01X301400D01*
X301209Y1064116D01*
X298768D01*
G01X313574Y1068466D02*
X313971Y1069149D01*
G03X313396Y1069923I-508J223D01*
G03X312871Y1069755I177J-1458D01*
G01X312838Y1069736D01*
G02X310610I-1114J1919D01*
G01X310577Y1069755D01*
G03X309137Y1069736I-703J-1289D01*
G02X306909I-1114J1919D01*
G03X306295Y1069930I-739J-1269D01*
G03X306173Y1069935I-121J-1464D01*
G01X302528D01*
X301800Y1069207D01*
X300183D01*
X299923Y1068947D01*
X299848D01*
G01X309874Y1074844D02*
G02X307798Y1073863I-2427J2450D01*
G03X306909Y1073574I226J-2207D01*
G02X306173Y1073375I-738J1269D01*
G01X302731D01*
X302542Y1073186D01*
X299038D01*
G01X315425Y1078033D02*
G02X313378Y1077055I-2337J2261D01*
G03X312460Y1076763I198J-2210D01*
G02X310988I-736J1270D01*
G03X308760I-1114J-1919D01*
G02X307320Y1076744I-737J1270D01*
G01X307287Y1076763D01*
G03X306359Y1077056I-1116J-1918D01*
G03X306174Y1077063I-176J-2212D01*
G01X302095D01*
X301268Y1076236D01*
X299089D01*
G01X315425Y1071655D02*
G02X313378Y1070677I-2337J2261D01*
G03X312460Y1070385I198J-2210D01*
G02X310988I-736J1270D01*
G03X308760I-1114J-1919D01*
G02X307320Y1070366I-737J1270D01*
G01X307287Y1070385D01*
G03X306359Y1070678I-1116J-1918D01*
G03X306174Y1070685I-176J-2212D01*
G01X302217D01*
X301489Y1069957D01*
X300183D01*
X299923Y1070217D01*
X299848D01*
G01X309874Y1081222D02*
G02X307798Y1080241I-2427J2450D01*
G03X306909Y1079952I226J-2207D01*
G02X306173Y1079753I-738J1269D01*
G01X300319D01*
X300132Y1079566D01*
X299059D01*
G01X315425Y1084411D02*
G02X313378Y1083433I-2337J2261D01*
G03X312460Y1083141I198J-2210D01*
G02X310988I-736J1270D01*
G03X308760I-1114J-1919D01*
G02X307320Y1083122I-737J1270D01*
G01X307287Y1083141D01*
G03X306359Y1083434I-1116J-1918D01*
G03X306174Y1083441I-176J-2212D01*
G01X301922D01*
X300727Y1082246D01*
G01X309874Y1093978D02*
G02X307798Y1092997I-2427J2450D01*
G03X306909Y1092708I226J-2207D01*
G02X306173Y1092509I-738J1269D01*
G01X300722D01*
X300337Y1092124D01*
X299860D01*
G01X313574Y1087600D02*
X313971Y1088283D01*
G03X313396Y1089057I-508J223D01*
G03X312871Y1088889I177J-1458D01*
G01X312838Y1088870D01*
G02X310610I-1114J1919D01*
G01X310577Y1088889D01*
G03X309137Y1088870I-703J-1289D01*
G02X306909I-1114J1919D01*
G03X306295Y1089064I-739J-1269D01*
G03X306173Y1089069I-121J-1464D01*
G01X302759D01*
X301817Y1088127D01*
X299374D01*
X299114Y1087867D01*
X299039D01*
G01X315425Y1090789D02*
G02X313378Y1089811I-2337J2261D01*
G03X312460Y1089519I198J-2210D01*
G02X310988I-736J1270D01*
G03X308760I-1114J-1919D01*
G02X307320Y1089500I-737J1270D01*
G01X307287Y1089519D01*
G03X306359Y1089812I-1116J-1918D01*
G03X306174Y1089819I-176J-2212D01*
G01X302448D01*
X301506Y1088877D01*
X299299D01*
X299039Y1089137D01*
G01X309874Y1100356D02*
G02X307798Y1099375I-2427J2450D01*
G03X306909Y1099086I226J-2207D01*
G02X306173Y1098887I-738J1269D01*
G01X301444D01*
X301020Y1099311D01*
X299079D01*
G01X315425Y1097167D02*
G02X313378Y1096189I-2337J2261D01*
G03X312460Y1095897I198J-2210D01*
G02X310988I-736J1270D01*
G03X308760I-1114J-1919D01*
G02X307320Y1095878I-737J1270D01*
G01X307287Y1095897D01*
G03X306359Y1096190I-1116J-1918D01*
G03X306174Y1096197I-176J-2212D01*
G01X301861D01*
X301746Y1096082D01*
X299059D01*
G01X315425Y1103545D02*
G02X313378Y1102567I-2337J2261D01*
G03X312460Y1102275I198J-2210D01*
G02X310988I-736J1270D01*
G03X308760I-1114J-1919D01*
G02X307320Y1102256I-737J1270D01*
G01X307287Y1102275D01*
G03X306359Y1102568I-1116J-1918D01*
G03X306174Y1102575I-176J-2212D01*
G01X300784D01*
X300200Y1101991D01*
G01X313574Y1106734D02*
X313971Y1107417D01*
G03X313396Y1108191I-508J223D01*
G03X312871Y1108023I177J-1458D01*
G01X312838Y1108004D01*
G02X310610I-1114J1919D01*
G01X310577Y1108023D01*
G03X309137Y1108004I-703J-1289D01*
G02X306909I-1114J1919D01*
G03X306295Y1108198I-739J-1269D01*
G03X306173Y1108203I-121J-1464D01*
G01X302696D01*
X301459Y1106966D01*
X299337D01*
X299077Y1106706D01*
X299039D01*
G01X315425Y1109923D02*
G02X313378Y1108945I-2337J2261D01*
G03X312460Y1108653I198J-2210D01*
G02X310988I-736J1270D01*
G03X308760I-1114J-1919D01*
G02X307320Y1108634I-737J1270D01*
G01X307287Y1108653D01*
G03X306359Y1108946I-1116J-1918D01*
G03X306174Y1108953I-176J-2212D01*
G01X302385D01*
X301148Y1107716D01*
X299299D01*
X299039Y1107976D01*
G01X309874Y1113112D02*
G02X307798Y1112131I-2427J2450D01*
G03X306909Y1111842I226J-2207D01*
G02X306173Y1111643I-738J1269D01*
G01X300675D01*
X299996Y1110964D01*
X299264D01*
G01X315425Y1116301D02*
G02X313378Y1115323I-2337J2261D01*
G03X312460Y1115031I198J-2210D01*
G02X310988I-736J1270D01*
G03X308760I-1114J-1919D01*
G02X307320Y1115012I-737J1270D01*
G01X307287Y1115031D01*
G03X306359Y1115324I-1116J-1918D01*
G03X306174Y1115331I-176J-2212D01*
G01X301072D01*
X300867Y1115536D01*
X298859D01*
G01X309874Y1119490D02*
G02X307798Y1118509I-2427J2450D01*
G03X306909Y1118220I226J-2207D01*
G02X306173Y1118021I-738J1269D01*
G01X301392D01*
X300702Y1118711D01*
X299059D01*
G01X315425Y1122679D02*
G02X313378Y1121701I-2337J2261D01*
G03X312460Y1121409I198J-2210D01*
G02X310988I-736J1270D01*
G03X308760I-1114J-1919D01*
G02X307320Y1121390I-737J1270D01*
G01X307287Y1121409D01*
G03X306359Y1121702I-1116J-1918D01*
G03X306174Y1121709I-176J-2212D01*
G01X299602D01*
X299284Y1121391D01*
G01X309874Y1132246D02*
G02X307798Y1131265I-2427J2450D01*
G03X306909Y1130976I226J-2207D01*
G02X306173Y1130777I-738J1269D01*
G01X299270D01*
X299059Y1130566D01*
G01X313574Y1125868D02*
X313971Y1126551D01*
G03X313396Y1127325I-508J223D01*
G03X312871Y1127157I177J-1458D01*
G01X312838Y1127138D01*
G02X310610I-1114J1919D01*
G01X310577Y1127157D01*
G03X309137Y1127138I-703J-1289D01*
G02X306909I-1114J1919D01*
G03X306295Y1127332I-739J-1269D01*
G03X306173Y1127337I-121J-1464D01*
G01X302430D01*
X301298Y1126205D01*
X299374D01*
X299114Y1125945D01*
X299039D01*
G01X315425Y1129057D02*
G02X313378Y1128079I-2337J2261D01*
G03X312460Y1127787I198J-2210D01*
G02X310988I-736J1270D01*
G03X308760I-1114J-1919D01*
G02X307320Y1127768I-737J1270D01*
G01X307287Y1127787D01*
G03X306359Y1128080I-1116J-1918D01*
G03X306174Y1128087I-176J-2212D01*
G01X302119D01*
X300987Y1126955D01*
X299374D01*
X299114Y1127215D01*
X299039D01*
G01X315425Y1135434D02*
G02X313378Y1134457I-2337J2264D01*
G03X312460Y1134165I198J-2210D01*
G02X310988I-736J1270D01*
G03X308760I-1114J-1919D01*
G02X307320Y1134146I-737J1270D01*
G01X307287Y1134165D01*
G03X306359Y1134458I-1116J-1918D01*
G03X306174Y1134465I-176J-2212D01*
G01X301958D01*
X301259Y1133766D01*
X299159D01*
G01X309874Y1138623D02*
G02X307798Y1137642I-2427J2450D01*
G03X306909Y1137353I226J-2207D01*
G02X306173Y1137154I-738J1269D01*
G01X299347D01*
X299159Y1136966D01*
G01X315425Y1141812D02*
G02X313378Y1140834I-2337J2261D01*
G03X312460Y1140542I198J-2210D01*
G02X310988I-736J1270D01*
G03X308760I-1114J-1919D01*
G02X307320Y1140523I-737J1270D01*
G01X307287Y1140542D01*
G03X306359Y1140835I-1116J-1918D01*
G03X306174Y1140842I-176J-2212D01*
G01X300535D01*
X299859Y1140166D01*
X299159D01*
G01X313574Y1145001D02*
X313971Y1145684D01*
G03X313396Y1146458I-508J223D01*
G03X312871Y1146290I177J-1458D01*
G01X312838Y1146271D01*
G02X310610I-1114J1919D01*
G01X310577Y1146290D01*
G03X309137Y1146271I-703J-1289D01*
G02X306909I-1114J1919D01*
G03X306295Y1146465I-739J-1269D01*
G03X306173Y1146470I-121J-1464D01*
G01X299781D01*
X299320Y1146931D01*
X298952D01*
X298899Y1146984D01*
G01X315425Y1148190D02*
G02X313378Y1147212I-2337J2261D01*
G03X312460Y1146920I198J-2210D01*
G02X310988I-736J1270D01*
G03X308760I-1114J-1919D01*
G02X307320Y1146901I-737J1270D01*
G01X307287Y1146920D01*
G03X306359Y1147213I-1116J-1918D01*
G03X306174Y1147220I-176J-2212D01*
G01X300092D01*
X299852Y1147460D01*
Y1147830D01*
X299799Y1147883D01*
G01X309874Y1151379D02*
G02X307798Y1150398I-2427J2450D01*
G03X306909Y1150109I226J-2207D01*
G02X306173Y1149910I-738J1269D01*
G01X301935D01*
X299069Y1152776D01*
G01X308023Y1154568D02*
X302719D01*
X301859Y1155428D01*
G01X308693Y887049D02*
G02X306898Y885883I-3585J3554D01*
G01X306186D01*
X305079Y884776D01*
X304689D01*
X303369Y883456D01*
X302609D01*
X301635Y882482D01*
G01X314244Y890238D02*
G03X312358Y891208I-1886J-1349D01*
G02X311279Y891508I36J2219D01*
G03X309807I-736J-1270D01*
G02X307579I-1114J1919D01*
G03X305804Y891276I-737J-1270D01*
G01X304424Y889896D01*
X302929D01*
X301702Y888669D01*
G01X308693Y893427D02*
G03X306617Y894408I-2427J-2450D01*
G02X305728Y894697I226J2207D01*
G03X304992Y894896I-738J-1269D01*
G01X303219D01*
X301159Y892836D01*
Y892467D01*
X301106Y892414D01*
G01X308693Y899805D02*
G03X306653Y900783I-2312J-2206D01*
G02X305728Y901075I189J2211D01*
G03X304619Y901366I-1109J-1968D01*
G01X302169D01*
X301309Y900506D01*
G01X306842Y896616D02*
X307229Y895950D01*
G02X306687Y895156I-484J-251D01*
G02X306139Y895327I155J1460D01*
G01X306106Y895346D01*
G03X304992Y895646I-1114J-1918D01*
G01X302908D01*
X300629Y893367D01*
X300261D01*
X300208Y893314D01*
G01X314244Y902994D02*
G03X312197Y903972I-2337J-2261D01*
G02X311279Y904264I198J2210D01*
G03X309807I-736J-1270D01*
G02X307579I-1114J1919D01*
G03X306139Y904283I-737J-1270D01*
G01X306106Y904264D01*
G02X305178Y903971I-1116J1918D01*
G02X304993Y903964I-176J2212D01*
G01X301010D01*
X300033Y902987D01*
G01X308693Y906182D02*
G03X306655Y907159I-2310J-2204D01*
G02X305728Y907452I189J2211D01*
G03X304898Y907676I-830J-1426D01*
G01X301129D01*
X300609Y907156D01*
G01X314244Y909371D02*
G03X312399Y910340I-1845J-1272D01*
G02X311279Y910641I-4J2219D01*
G03X309807I-736J-1269D01*
G02X307579I-1114J1919D01*
G03X306139Y910660I-737J-1269D01*
G01X306106Y910641D01*
G02X304992Y910341I-1114J1918D01*
G01X300024D01*
G01X306842Y915749D02*
X307229Y915083D01*
G02X306687Y914289I-484J-251D01*
G02X306139Y914460I155J1460D01*
G01X306106Y914479D01*
G03X304992Y914779I-1114J-1918D01*
G01X300249D01*
X299989Y915039D01*
X299914D01*
G01X308693Y912560D02*
G03X306617Y913541I-2427J-2450D01*
G02X305728Y913830I226J2207D01*
G03X304992Y914029I-738J-1269D01*
G01X300249D01*
X299989Y913769D01*
X299914D01*
G01X308693Y918938D02*
G03X306655Y919915I-2310J-2204D01*
G02X305728Y920208I189J2211D01*
G03X304883Y920436I-845J-1452D01*
G01X299069D01*
G01X314244Y922127D02*
G03X312399Y923095I-1845J-1274D01*
G02X311279Y923396I-4J2219D01*
G01Y923397D01*
G03X309807I-736J-1270D01*
G02X307579I-1114J1919D01*
G03X306139Y923416I-737J-1270D01*
G01X306106Y923397D01*
G02X304992Y923097I-1114J1918D01*
G01X300458D01*
X299719Y923836D01*
X299029D01*
G01X308693Y925316D02*
G03X306655Y926293I-2310J-2204D01*
G02X305728Y926586I189J2211D01*
G03X304913Y926806I-815J-1401D01*
G01X300749D01*
X300059Y927496D01*
X299119D01*
G01X314244Y928505D02*
G03X312399Y929473I-1845J-1274D01*
G02X311279Y929774I-4J2219D01*
G01Y929775D01*
G03X309807I-736J-1270D01*
G02X307579I-1114J1919D01*
G03X306139Y929794I-737J-1270D01*
G01X306106Y929775D01*
G02X303436Y929056I-2670J4598D01*
G01X301369D01*
X299939Y930486D01*
X298969D01*
G01X308693Y931694D02*
G03X306617Y932675I-2427J-2450D01*
G02X305728Y932964I226J2207D01*
G03X304992Y933163I-738J-1269D01*
G01X301180D01*
X300607Y933736D01*
X300134D01*
X299874Y933476D01*
X299799D01*
G01X308693Y938072D02*
G03X306655Y939049I-2310J-2204D01*
G02X305728Y939342I189J2211D01*
G03X304858Y939576I-870J-1500D01*
G01X300169D01*
X298939Y940806D01*
G01X314244Y941261D02*
G03X312399Y942229I-1845J-1274D01*
G02X311279Y942530I-4J2219D01*
G01Y942531D01*
G03X309807I-736J-1270D01*
G02X307579I-1114J1919D01*
G03X306139Y942550I-737J-1270D01*
G01X306106Y942531D01*
G02X303562Y941846I-2544J4380D01*
G01X301639D01*
X299919Y943566D01*
X299119D01*
G01X306842Y934883D02*
X307229Y934217D01*
G02X306687Y933423I-484J-251D01*
G02X306139Y933594I155J1460D01*
G01X306106Y933613D01*
G03X304992Y933913I-1114J-1918D01*
G01X301491D01*
X300918Y934486D01*
X300134D01*
X299874Y934746D01*
X299799D01*
G01X308693Y944450D02*
G03X306655Y945427I-2310J-2204D01*
G02X305728Y945720I189J2211D01*
G03X304182Y946136I-1546J-2666D01*
G01X300779D01*
X300199Y946716D01*
X299099D01*
G01X314244Y947639D02*
G03X312399Y948607I-1845J-1274D01*
G02X311279Y948908I-4J2219D01*
G01Y948909D01*
G03X309807I-736J-1270D01*
G02X307579I-1114J1919D01*
G03X306139Y948928I-737J-1270D01*
G01X306106Y948909D01*
G02X304869Y948576I-1237J2129D01*
G01X301099D01*
X300229Y949446D01*
X299079D01*
G01X308693Y957206D02*
G03X306655Y958183I-2310J-2204D01*
G02X305728Y958476I189J2211D01*
G03X305114Y958670I-739J-1269D01*
G03X304727Y958686I-387J-4683D01*
G01X300059D01*
X299839Y958466D01*
G01X306842Y954017D02*
X307229Y953351D01*
G02X306687Y952557I-484J-251D01*
G02X306139Y952728I155J1460D01*
G01X306106Y952747D01*
G03X304992Y953047I-1114J-1918D01*
G01X301999D01*
X301499Y953547D01*
X299374D01*
X299114Y953807D01*
X299039D01*
G01X308693Y950828D02*
G03X306617Y951809I-2427J-2450D01*
G02X305728Y952098I226J2207D01*
G03X304992Y952297I-738J-1269D01*
G01X301688D01*
X301188Y952797D01*
X299374D01*
X299114Y952537D01*
X299039D01*
G01X308693Y963584D02*
G03X306655Y964561I-2310J-2204D01*
G02X305728Y964854I189J2211D01*
G03X305114Y965048I-739J-1269D01*
G03X304678Y965066I-436J-5268D01*
G01X301479D01*
X300779Y964366D01*
G01X314244Y960395D02*
G03X312399Y961363I-1845J-1274D01*
G02X311279Y961664I-4J2219D01*
G01Y961665D01*
G03X309807I-736J-1270D01*
G02X307579I-1114J1919D01*
G03X306139Y961684I-737J-1270D01*
G01X306106Y961665D01*
G02X303733Y961026I-2373J4086D01*
G01X300879D01*
X300759Y961146D01*
X299099D01*
G01X314244Y966773D02*
G03X312399Y967741I-1845J-1274D01*
G02X311279Y968042I-4J2219D01*
G01Y968043D01*
G03X309807I-736J-1270D01*
G02X307579I-1114J1919D01*
G03X306139Y968062I-737J-1270D01*
G01X306106Y968043D01*
G02X303815Y967426I-2291J3945D01*
G01X299319D01*
X299199Y967306D01*
G01X306842Y973151D02*
X307229Y972485D01*
G02X306687Y971691I-484J-251D01*
G02X306139Y971862I155J1460D01*
G01X306106Y971881D01*
G03X304992Y972181I-1114J-1918D01*
G01X301239D01*
X300979Y972441D01*
X300904D01*
G01X308693Y969962D02*
G03X306617Y970943I-2427J-2450D01*
G02X305728Y971232I226J2207D01*
G03X304992Y971431I-738J-1269D01*
G01X301239D01*
X300979Y971171D01*
X300904D01*
G01X308693Y976340D02*
G03X306617Y977321I-2427J-2450D01*
G02X305728Y977610I226J2207D01*
G03X304992Y977809I-738J-1269D01*
G01X300474D01*
X300101Y977436D01*
G01X314244Y979529D02*
G03X312399Y980497I-1845J-1274D01*
G02X311279Y980798I-4J2219D01*
G01Y980799D01*
G03X309807I-736J-1270D01*
G02X307579I-1114J1919D01*
G03X306139Y980818I-737J-1270D01*
G01X306106Y980799D01*
G02X303347Y980056I-2759J4751D01*
G01X300979D01*
X299919Y981116D01*
G01X306842Y992285D02*
X307208Y991655D01*
G02X306689Y990825I-463J-288D01*
G02X306139Y990996I152J1460D01*
G01X306106Y991015D01*
G03X303915Y991606I-2191J-3767D01*
G01X300429D01*
G01X308693Y995474D02*
G03X306655Y996451I-2310J-2204D01*
G02X305728Y996744I189J2211D01*
G03X304905Y996966I-823J-1414D01*
G01X298669D01*
G01X314244Y998663D02*
G03X312399Y999631I-1845J-1274D01*
G02X311279Y999932I-4J2219D01*
G01Y999933D01*
G03X309807I-736J-1270D01*
G02X307579I-1114J1919D01*
G03X306139Y999952I-737J-1270D01*
G01X306106Y999933D01*
G02X303815Y999316I-2291J3945D01*
G01X300259D01*
X299304Y1000271D01*
G01X308693Y1001852D02*
G03X306617Y1002833I-2427J-2450D01*
G02X305728Y1003122I226J2207D01*
G03X304992Y1003321I-738J-1269D01*
G01X300064D01*
X300011Y1003374D01*
G01X314244Y1005041D02*
G03X312399Y1006009I-1845J-1274D01*
G02X311279Y1006310I-4J2219D01*
G01Y1006311D01*
G03X309807I-736J-1270D01*
G02X307579I-1114J1919D01*
G03X306139Y1006330I-737J-1270D01*
G01X306106Y1006311D01*
G02X304527Y1005740I-2361J4059D01*
G02X304227Y1005716I-293J1780D01*
G01X301619D01*
X299529Y1007806D01*
G01X312393Y1008230D02*
Y1008229D01*
X312807Y1007517D01*
G02X312399Y1006762I-541J-195D01*
G02X311690Y1006941I-7J1466D01*
G01X311686Y1006943D01*
X311657Y1006960D01*
G03X309429I-1114J-1919D01*
G01X309396Y1006941D01*
G02X307956Y1006960I-703J1289D01*
G03X305728I-1114J-1919D01*
G02X304897Y1006736I-831J1429D01*
G01X301909D01*
X301013Y1007632D01*
Y1008772D01*
G01X313574Y1030198D02*
X314001Y1030933D01*
G03X313404Y1031656I-533J168D01*
G03X312871Y1031487I169J-1458D01*
G01X312838Y1031468D01*
G02X310610I-1114J1919D01*
G01X310577Y1031487D01*
G03X309137Y1031468I-703J-1289D01*
G02X306909I-1114J1919D01*
G03X306173Y1031667I-738J-1269D01*
G01X299599D01*
G01X308023Y1033387D02*
X308410Y1034053D01*
G03X307868Y1034847I-484J251D01*
G03X307320Y1034676I155J-1460D01*
G01X307287Y1034657D01*
G02X306173Y1034357I-1114J1918D01*
G01X304576D01*
X304566Y1034347D01*
X299599D01*
G01X313574Y1036576D02*
X314001Y1037311D01*
G03X313404Y1038034I-533J168D01*
G03X312871Y1037865I169J-1458D01*
G01X312838Y1037846D01*
G02X310610I-1114J1919D01*
G01X310577Y1037865D01*
G03X309137Y1037846I-703J-1289D01*
G02X306909I-1114J1919D01*
G03X306173Y1038045I-738J-1269D01*
G01X302818D01*
X301877Y1037104D01*
X299599D01*
G01X308023Y1039765D02*
X308410Y1040431D01*
G03X307868Y1041225I-484J251D01*
G03X307320Y1041054I155J-1460D01*
G01X307287Y1041035D01*
G02X306173Y1040735I-1114J1918D01*
G01X302148D01*
X301197Y1039784D01*
X299829D01*
G01X313574Y1049332D02*
X314001Y1050067D01*
G03X313404Y1050790I-533J168D01*
G03X312871Y1050621I169J-1458D01*
G01X312838Y1050602D01*
G02X310610I-1114J1919D01*
G01X310577Y1050621D01*
G03X309137Y1050602I-703J-1289D01*
G02X306909I-1114J1919D01*
G03X306173Y1050801I-738J-1269D01*
G01X302889D01*
X302094Y1050006D01*
G01X315425Y1046143D02*
G02X313629Y1045173I-1746J1085D01*
G03X312460Y1044873I-54J-2218D01*
G02X310988I-736J1270D01*
G03X308760I-1114J-1919D01*
G02X307320Y1044854I-737J1270D01*
G01X307287Y1044873D01*
G03X306359Y1045166I-1116J-1918D01*
G03X303670Y1045273I-2689J-33731D01*
G01X301502D01*
G01X308023Y1052521D02*
X308410Y1053187D01*
G03X307868Y1053981I-484J251D01*
G03X307320Y1053810I155J-1460D01*
G01X307287Y1053791D01*
G02X306173Y1053491I-1114J1918D01*
G01X301384D01*
X301129Y1053236D01*
G01X308023Y1058899D02*
X308410Y1059565D01*
G03X307868Y1060359I-484J251D01*
G03X307320Y1060188I155J-1460D01*
G01X307287Y1060169D01*
G02X306173Y1059869I-1114J1918D01*
G01X299156D01*
X298929Y1060096D01*
G01X313574Y1062088D02*
X313971Y1062771D01*
G03X313396Y1063545I-508J223D01*
G03X312871Y1063377I177J-1458D01*
G01X312838Y1063358D01*
G02X310610I-1114J1919D01*
G01X310577Y1063377D01*
G03X309137Y1063358I-703J-1289D01*
G02X306909I-1114J1919D01*
G03X306295Y1063552I-739J-1269D01*
G03X306173Y1063557I-121J-1464D01*
G01X301750D01*
X300969Y1062776D01*
X298969D01*
G01X309874Y1068466D02*
G02X307798Y1067485I-2427J2450D01*
G03X306909Y1067196I226J-2207D01*
G02X306173Y1066997I-738J1269D01*
G01X301042D01*
X300782Y1067257D01*
X300707D01*
G01X308023Y1065277D02*
X308410Y1065943D01*
G03X307868Y1066737I-484J251D01*
G03X307320Y1066566I155J-1460D01*
G01X307287Y1066547D01*
G02X306173Y1066247I-1114J1918D01*
G01X301042D01*
X300782Y1065987D01*
X300707D01*
G01X308023Y1071655D02*
X308410Y1072321D01*
G03X307868Y1073115I-484J251D01*
G03X307320Y1072944I155J-1460D01*
G01X307287Y1072925D01*
G02X306173Y1072625I-1114J1918D01*
G01X304111D01*
X303332Y1071846D01*
X299138D01*
G01X313574Y1074844D02*
X313971Y1075527D01*
G03X313396Y1076301I-508J223D01*
G03X312871Y1076133I177J-1458D01*
G01X312838Y1076114D01*
G02X310610I-1114J1919D01*
G01X310577Y1076133D01*
G03X309137Y1076114I-703J-1289D01*
G02X306909I-1114J1919D01*
G03X306295Y1076308I-739J-1269D01*
G03X306173Y1076313I-121J-1464D01*
G01X302406D01*
X300619Y1074526D01*
X299059D01*
G01X308023Y1078033D02*
X308410Y1078699D01*
G03X307868Y1079493I-484J251D01*
G03X307320Y1079322I155J-1460D01*
G01X307287Y1079303D01*
G02X306173Y1079003I-1114J1918D01*
G01X300726D01*
X299789Y1078066D01*
G01X313574Y1081222D02*
X313971Y1081905D01*
G03X313396Y1082679I-508J223D01*
G03X312871Y1082511I177J-1458D01*
G01X312838Y1082492D01*
G02X310610I-1114J1919D01*
G01X310577Y1082511D01*
G03X309137Y1082492I-703J-1289D01*
G02X306909I-1114J1919D01*
G03X306295Y1082686I-739J-1269D01*
G03X306173Y1082691I-121J-1464D01*
G01X303008D01*
X301223Y1080906D01*
X299059D01*
G01X309874Y1087600D02*
G02X307798Y1086619I-2427J2450D01*
G03X306909Y1086330I226J-2207D01*
G02X306173Y1086131I-738J1269D01*
G01X302066D01*
X300809Y1084874D01*
X299900D01*
X299640Y1085134D01*
X299565D01*
G01X308023Y1084411D02*
X308410Y1085077D01*
G03X307868Y1085871I-484J251D01*
G03X307320Y1085700I155J-1460D01*
G01X307287Y1085681D01*
G02X306173Y1085381I-1114J1918D01*
G01X302377D01*
X301120Y1084124D01*
X299900D01*
X299640Y1083864D01*
X299565D01*
G01X308023Y1090789D02*
X308410Y1091455D01*
G03X307868Y1092249I-484J251D01*
G03X307320Y1092078I155J-1460D01*
G01X307287Y1092059D01*
G02X306173Y1091759I-1114J1918D01*
G01X302614D01*
X301610Y1090755D01*
X301191D01*
G01X313574Y1093978D02*
X313971Y1094661D01*
G03X313396Y1095435I-508J223D01*
G03X312871Y1095267I177J-1458D01*
G01X312838Y1095248D01*
G02X310610I-1114J1919D01*
G01X310577Y1095267D01*
G03X309137Y1095248I-703J-1289D01*
G02X306909I-1114J1919D01*
G03X306295Y1095442I-739J-1269D01*
G03X306173Y1095447I-121J-1464D01*
G01X302730D01*
X300807Y1093524D01*
X299217D01*
G01X308023Y1097167D02*
X308410Y1097833D01*
G03X307868Y1098627I-484J251D01*
G03X307320Y1098456I155J-1460D01*
G01X307287Y1098437D01*
G02X306173Y1098137I-1114J1918D01*
G01X304576D01*
X304321Y1097882D01*
X298970D01*
G01X313574Y1100356D02*
X313971Y1101039D01*
G03X313396Y1101813I-508J223D01*
G03X312871Y1101645I177J-1458D01*
G01X312838Y1101626D01*
G02X310610I-1114J1919D01*
G01X310577Y1101645D01*
G03X309137Y1101626I-703J-1289D01*
G02X306909I-1114J1919D01*
G03X306295Y1101820I-739J-1269D01*
G03X306173Y1101825I-121J-1464D01*
G01X302075D01*
X300901Y1100651D01*
X299059D01*
G01X309874Y1106734D02*
G02X307798Y1105753I-2427J2450D01*
G03X306909Y1105464I226J-2207D01*
G02X306173Y1105265I-738J1269D01*
G01X304265D01*
X303691Y1104691D01*
X300055D01*
X299299Y1104616D01*
X299039Y1104876D01*
G01X308023Y1103545D02*
X308410Y1104211D01*
G03X307868Y1105005I-484J251D01*
G03X307320Y1104834I155J-1460D01*
G01X307287Y1104815D01*
G02X306173Y1104515I-1114J1918D01*
G01X304576D01*
X304002Y1103941D01*
X300094D01*
X299374Y1103866D01*
X299114Y1103606D01*
X299039D01*
G01X308023Y1109923D02*
X308410Y1110589D01*
G03X307868Y1111383I-484J251D01*
G03X307320Y1111212I155J-1460D01*
G01X307287Y1111193D01*
G02X306173Y1110893I-1114J1918D01*
G01X301589D01*
X300291Y1109595D01*
X299092D01*
G01X313574Y1113112D02*
X313971Y1113795D01*
G03X313396Y1114569I-508J223D01*
G03X312871Y1114401I177J-1458D01*
G01X312838Y1114382D01*
G02X310610I-1114J1919D01*
G01X310577Y1114401D01*
G03X309137Y1114382I-703J-1289D01*
G02X306909I-1114J1919D01*
G03X306295Y1114576I-739J-1269D01*
G03X306173Y1114581I-121J-1464D01*
G01X302274D01*
X301889Y1114196D01*
X299059D01*
G01X308023Y1116301D02*
X308410Y1116967D01*
G03X307868Y1117761I-484J251D01*
G03X307320Y1117590I155J-1460D01*
G01X307287Y1117571D01*
G02X306173Y1117271I-1114J1918D01*
G01X300254D01*
X300154Y1117371D01*
G01X313574Y1119490D02*
X313971Y1120173D01*
G03X313396Y1120947I-508J223D01*
G03X312871Y1120779I177J-1458D01*
G01X312838Y1120760D01*
G02X310610I-1114J1919D01*
G01X310577Y1120779D01*
G03X309137Y1120760I-703J-1289D01*
G02X306909I-1114J1919D01*
G03X306295Y1120954I-739J-1269D01*
G03X306173Y1120959I-121J-1464D01*
G01X302452D01*
X301544Y1120051D01*
X299059D01*
G01X309874Y1125868D02*
G02X307798Y1124887I-2427J2450D01*
G03X306909Y1124598I226J-2207D01*
G02X306173Y1124399I-738J1269D01*
G01X304265D01*
X303882Y1124016D01*
X299374D01*
X299114Y1124276D01*
X299039D01*
G01X308023Y1122679D02*
X308410Y1123345D01*
G03X307868Y1124139I-484J251D01*
G03X307320Y1123968I155J-1460D01*
G01X307287Y1123949D01*
G02X306173Y1123649I-1114J1918D01*
G01X304576D01*
X304193Y1123266D01*
X299374D01*
X299114Y1123006D01*
X299039D01*
G01X308023Y1129057D02*
X308410Y1129723D01*
G03X307868Y1130517I-484J251D01*
G03X307320Y1130346I155J-1460D01*
G01X307287Y1130327D01*
G02X306173Y1130027I-1114J1918D01*
G01X300560D01*
X299599Y1129066D01*
G01X313574Y1132246D02*
X313971Y1132929D01*
G03X313396Y1133703I-508J223D01*
G03X312871Y1133535I177J-1458D01*
G01X312838Y1133516D01*
G02X310610I-1114J1919D01*
G01X310577Y1133535D01*
G03X309137Y1133516I-703J-1289D01*
G02X306909I-1114J1919D01*
G03X306295Y1133710I-739J-1269D01*
G03X306173Y1133715I-121J-1464D01*
G01X302507D01*
X301059Y1132267D01*
X299059D01*
G01X308023Y1135434D02*
X308410Y1136100D01*
G03X307868Y1136894I-484J251D01*
G03X307320Y1136723I155J-1460D01*
G01X307287Y1136704D01*
G02X306173Y1136404I-1114J1918D01*
G01X299997D01*
X299159Y1135566D01*
G01X313574Y1138623D02*
X313971Y1139306D01*
G03X313396Y1140080I-508J223D01*
G03X312871Y1139912I177J-1458D01*
G01X312838Y1139893D01*
G02X310610I-1114J1919D01*
G01X310577Y1139912D01*
G03X309137Y1139893I-703J-1289D01*
G02X306909I-1114J1919D01*
G03X306295Y1140087I-739J-1269D01*
G03X306173Y1140092I-121J-1464D01*
G01X302885D01*
X301559Y1138766D01*
X299059D01*
G01X308023Y1148190D02*
X308410Y1148856D01*
G03X307868Y1149650I-484J251D01*
G03X307320Y1149479I155J-1460D01*
G01X307287Y1149460D01*
G02X306173Y1149160I-1114J1918D01*
G01X301183D01*
X299312Y1151031D01*
G01X309874Y1145001D02*
G02X307798Y1144020I-2427J2450D01*
G03X306909Y1143731I226J-2207D01*
G02X306173Y1143532I-738J1269D01*
G01X304265D01*
X304113Y1143380D01*
X299374D01*
X299114Y1143640D01*
X299039D01*
G01X308023Y1141812D02*
X308410Y1142478D01*
G03X307868Y1143272I-484J251D01*
G03X307320Y1143101I155J-1460D01*
G01X307287Y1143082D01*
G02X306173Y1142782I-1114J1918D01*
G01X304576D01*
X304424Y1142630D01*
X299374D01*
X299114Y1142370D01*
X299039D01*
G01X313574Y1151379D02*
X313564Y1151383D01*
X311673Y1152656D01*
G03X310658Y1152966I-1015J-1508D01*
G01X301319D01*
X300409Y1153876D01*
G01X434519Y887049D02*
X433269D01*
X433060Y886840D01*
G03X433658Y885851I1460J208D01*
G01X433775Y885784D01*
X433780Y885781D01*
X433783Y885779D01*
X433816Y885760D01*
G03X435256Y885779I703J1289D01*
G02X437484I1114J-1919D01*
G02X437939Y885429I-1114J-1919D01*
G01X439054Y884314D01*
X439422D01*
X439475Y884261D01*
X439474D01*
G01X430818Y887049D02*
X432068D01*
X432305Y886812D01*
G03X433251Y885220I2213J238D01*
G01X433395Y885136D01*
X433401Y885132D01*
X433405Y885130D01*
G03X435633I1114J1919D01*
G02X437107I737J-1270D01*
G02X437408Y884898I-738J-1269D01*
G01X438523Y883783D01*
Y883415D01*
X438576Y883362D01*
G01X423417Y887049D02*
X422167D01*
X421958Y886840D01*
G03X422556Y885851I1460J208D01*
G01Y885853D01*
X422830Y885693D01*
X422875Y885661D01*
G02Y882059I-1285J-1801D01*
G01X422828Y882026D01*
X422692Y881948D01*
X422681Y881941D01*
X422678Y881939D01*
X422556Y881869D01*
G03X421942Y880671I862J-1198D01*
G02X420984Y878842I-2225J0D01*
G01X420830Y878752D01*
X420710Y878682D01*
G03X420092Y877482I856J-1200D01*
G02X419134Y875653I-2225J0D01*
G01X418855Y875491D01*
G03X418501Y875129I862J-1197D01*
G03X418240Y874293I1213J-838D01*
G01Y872507D01*
X418500Y872247D01*
Y872172D01*
G01X419716Y887049D02*
X420966D01*
X421203Y886812D01*
G03X422149Y885220I2213J238D01*
G01X422428Y885058D01*
X422444Y885047D01*
G02Y882673I-854J-1187D01*
G01X422428Y882662D01*
X422306Y882592D01*
X422303Y882590D01*
X422299Y882588D01*
X422179Y882518D01*
X422176Y882516D01*
X422149Y882500D01*
G03X421191Y880671I1267J-1829D01*
G02X420573Y879471I-1474J0D01*
G01X420453Y879401D01*
X420299Y879311D01*
G03X419341Y877482I1267J-1829D01*
G02X418727Y876284I-1476J0D01*
G01X418602Y876212D01*
X418448Y876122D01*
G03X417882Y875555I1266J-1830D01*
G03X417490Y874293I1833J-1261D01*
G01Y872507D01*
X417230Y872247D01*
Y872172D01*
G01X416015Y880671D02*
X417265D01*
X417474Y880462D01*
G02X416872Y879471I-1460J209D01*
G01X416869Y879469D01*
X416752Y879401D01*
G02X415312Y879382I-737J1270D01*
G01X415279Y879401D01*
G03X413051I-1114J-1919D01*
G01X413018Y879382D01*
G02X411578Y879401I-703J1289D01*
G03X409350I-1114J-1919D01*
G01X409346Y879399D01*
X409340Y879395D01*
X409336Y879393D01*
X409196Y879311D01*
G03X408238Y877482I1267J-1829D01*
G02X407620Y876282I-1474J0D01*
G01X407352Y876126D01*
G03X406389Y874293I1261J-1832D01*
G01Y871607D01*
X406129Y871347D01*
Y871272D01*
G01X419716Y880671D02*
X418466D01*
X418229Y880434D01*
G02X417283Y878842I-2213J238D01*
G01X417129Y878752D01*
G02X414901I-1114J1919D01*
G03X413429I-736J-1270D01*
G02X411201I-1114J1919D01*
G03X409761Y878771I-737J-1270D01*
G01X409728Y878752D01*
X409725Y878750D01*
X409714Y878744D01*
X409711Y878742D01*
X409705Y878739D01*
X409702Y878737D01*
X409697Y878734D01*
X409687Y878729D01*
X409603Y878680D01*
G03X408989Y877482I862J-1198D01*
G02X408031Y875653I-2225J0D01*
G01X407877Y875563D01*
X407757Y875493D01*
G03X407139Y874293I856J-1200D01*
G01Y871607D01*
X407399Y871347D01*
Y871272D01*
G01X427118Y880671D02*
X428533D01*
X428593Y880611D01*
G03X429511Y878869I2112J0D01*
G01X429704Y878752D01*
X429829Y878680D01*
G02Y876284I-862J-1198D01*
G01X429825Y876282D01*
X429704Y876212D01*
X429561Y876129D01*
G03X428593Y874293I1257J-1836D01*
G01Y873160D01*
X428333Y872900D01*
Y872825D01*
G01X430818Y880671D02*
X429403D01*
X429343Y880611D01*
G03X429920Y879499I1361J1D01*
G01X430086Y879398D01*
X430233Y879313D01*
G02X430236Y879311I-1233J-1853D01*
G02Y875653I-1267J-1829D01*
G01X430225Y875645D01*
X430203Y875632D01*
X430197Y875628D01*
X429957Y875491D01*
G03X429343Y874293I862J-1198D01*
G01Y873160D01*
X429603Y872900D01*
Y872825D01*
G01X534441Y880671D02*
X535065Y879595D01*
X535388Y879510D01*
G02X537405Y879401I902J-2027D01*
G01X537409Y879399D01*
X537415Y879395D01*
X537559Y879311D01*
G02Y875653I-1267J-1829D01*
G01X537174Y875428D01*
X536060Y874314D01*
Y871731D01*
X536320Y871471D01*
Y871396D01*
G01X536291Y877482D02*
X535667Y878558D01*
X535743Y878843D01*
G02X537027Y878752I549J-1361D01*
G01X537030Y878750D01*
X537035Y878747D01*
X537152Y878680D01*
G02Y876284I-862J-1198D01*
G01X536712Y876027D01*
X535310Y874625D01*
Y871731D01*
X535050Y871471D01*
Y871396D01*
G01X545543Y880671D02*
X546167Y879595D01*
X546490Y879510D01*
G02X548507Y879401I902J-2027D01*
G01X548661Y879311D01*
G02Y875653I-1267J-1829D01*
G01X548659Y875652D01*
X548507Y875563D01*
X548387Y875493D01*
G03X547769Y874293I856J-1200D01*
G01Y873118D01*
X547728Y872200D01*
Y871101D01*
X547988Y870841D01*
Y870766D01*
G01X547393Y877482D02*
X546769Y878558D01*
X546846Y878844D01*
G02X548130Y878752I548J-1362D01*
G01X548250Y878682D01*
X548255Y878679D01*
G02X548233Y876270I-861J-1197D01*
G01X548130Y876212D01*
X547976Y876122D01*
G03X547018Y874293I1267J-1829D01*
G01X547019D01*
Y873135D01*
X546978Y872217D01*
Y871101D01*
X546718Y870841D01*
Y870766D01*
G01X558496Y877482D02*
X558339Y877751D01*
X557871Y878558D01*
X557948Y878844D01*
G02X559232Y878752I548J-1362D01*
G01X559352Y878682D01*
X559357Y878679D01*
G02X559335Y876270I-861J-1197D01*
G01X559232Y876212D01*
X559231Y876211D01*
X559084Y876126D01*
G03X557981Y874277I1463J-2126D01*
G01X557980Y874266D01*
Y871918D01*
X557720Y871658D01*
G01X556645Y880671D02*
X557269Y879595D01*
X557592Y879510D01*
G02X559609Y879401I902J-2027D01*
G01X559763Y879311D01*
G02Y875653I-1267J-1829D01*
G01X559761Y875652D01*
X559488Y875492D01*
G03X558730Y874225I1058J-1493D01*
G01Y871918D01*
X558990Y871658D01*
Y871583D01*
G01X571448Y887049D02*
G03X575032Y885556I3584J3555D01*
G01X577099Y883489D01*
G01X565897Y890238D02*
G02X567783Y891208I1886J-1349D01*
G03X568862Y891508I-36J2219D01*
G02X570334I736J-1270D01*
G03X572562I1114J1919D01*
G02X574002Y891527I737J-1270D01*
G02X574337Y891276I-704J-1288D01*
G01X575597Y890016D01*
X576327D01*
X579875Y886468D01*
Y885368D01*
G01X573299Y890238D02*
G03X575002Y888535I1703J0D01*
G01X576470D01*
X578569Y886436D01*
Y884690D01*
X578891Y884368D01*
G01X567748Y893427D02*
X567373Y892781D01*
Y892415D01*
G03X567823Y891961I454J0D01*
G03X568451Y892138I-74J1466D01*
G01X568484Y892157D01*
G02X570712I1114J-1919D01*
G01X570745Y892138D01*
G03X572185Y892157I703J1289D01*
G02X574868Y891807I1114J-1919D01*
G01X575839Y890836D01*
X576699D01*
X581125Y886410D01*
G01X573299Y896616D02*
X572896Y895922D01*
G03X573553Y895170I556J-177D01*
G03X574002Y895327I-253J1443D01*
G01X574035Y895346D01*
G02X574963Y895639I1116J-1918D01*
G02X575148Y895646I176J-2212D01*
G01X576023D01*
X577287Y895122D01*
X579335Y893074D01*
Y891929D01*
X581006Y890258D01*
X581374D01*
X581427Y890205D01*
G01X571448Y893427D02*
G02X573531Y894409I2450J-2497D01*
G03X573683Y894430I-228J2207D01*
G03X574413Y894697I-385J2185D01*
G02X575027Y894891I739J-1269D01*
G02X575149Y894896I121J-1464D01*
G01X575873D01*
X576862Y894486D01*
X578585Y892763D01*
Y891618D01*
X580476Y889727D01*
X580475Y889359D01*
X580528Y889306D01*
G01X573299Y909371D02*
X572933Y908741D01*
G03X573452Y907911I463J-288D01*
G03X574002Y908082I-152J1460D01*
G01X574035Y908101D01*
G02X577135Y908936I3100J-5337D01*
G01X578738D01*
X579518Y908156D01*
X580640D01*
G01X571448Y899805D02*
G02X573488Y900783I2312J-2206D01*
G03X574413Y901075I-189J2211D01*
G02X574880Y901273I1110J-1967D01*
G02X575178Y901316I297J-1002D01*
G01X578231D01*
X579225Y900322D01*
Y899362D01*
X581992Y896595D01*
G01X565897Y902994D02*
G02X567922Y903970I2272J-2125D01*
G03X568015Y903979I-167J2213D01*
G03X568862Y904264I-270J2203D01*
G02X570334I736J-1270D01*
G03X572562I1114J1919D01*
G02X574002Y904283I737J-1270D01*
G01X574035Y904264D01*
G03X575149Y903964I1114J1918D01*
G01X579019D01*
X581125Y901858D01*
Y901256D01*
X582425Y899956D01*
G01X573299Y902994D02*
X572922Y902345D01*
G03X573497Y901539I500J-252D01*
G03X574002Y901705I-198J1455D01*
G01X574035Y901724D01*
G02X575722Y902216I1687J-2646D01*
G01X579229D01*
X580105Y901340D01*
Y900380D01*
X582185Y898300D01*
G01X567748Y906182D02*
X567347Y905493D01*
G03X567924Y904726I511J-216D01*
G03X568451Y904894I-175J1458D01*
G01X568484Y904913D01*
G02X570712I1114J-1919D01*
G01X570745Y904894D01*
G03X572185Y904913I703J1289D01*
G02X574413I1114J-1919D01*
G03X575149Y904716I734J1270D01*
G01X575151Y904714D01*
X579619D01*
X582385Y901948D01*
G01X571448Y906182D02*
G02X573486Y907159I2310J-2204D01*
G03X574413Y907452I-189J2211D01*
G02X575243Y907676I830J-1426D01*
G01X578280D01*
X579220Y906736D01*
X580164D01*
G01X565897Y909371D02*
G02X567742Y910340I1845J-1272D01*
G03X568862Y910641I4J2219D01*
G02X570334I736J-1269D01*
G03X572562I1114J1919D01*
G02X574002Y910660I737J-1269D01*
G01X574035Y910641D01*
G03X576790Y909899I2755J4745D01*
G01X579089D01*
X579402Y909586D01*
X581106D01*
G01X565897Y896616D02*
G02X567922Y897592I2272J-2125D01*
G03X568015Y897601I-167J2213D01*
G03X568862Y897886I-270J2203D01*
G02X570334I736J-1270D01*
G03X572562I1114J1919D01*
G02X574036I737J-1270D01*
G02X574337Y897654I-738J-1269D01*
G01X575513Y896479D01*
X578241D01*
Y896477D01*
X579911Y894807D01*
X579910Y894441D01*
X579963Y894388D01*
G01X567748Y899805D02*
X567347Y899115D01*
G03X567924Y898348I511J-216D01*
G03X568451Y898516I-175J1458D01*
G01X568484Y898535D01*
G02X570712I1114J-1919D01*
G01X570745Y898516D01*
G03X572185Y898535I703J1289D01*
G02X574413I1114J-1919D01*
G02X574868Y898185I-1114J-1919D01*
G01X575824Y897229D01*
X578552D01*
X580495Y895286D01*
X580862D01*
G01X567748Y912560D02*
X567334Y911848D01*
G03X567742Y911093I541J-195D01*
G03X568451Y911272I7J1466D01*
G01X568455Y911274D01*
X568484Y911291D01*
G02X570712I1114J-1919D01*
G01X570745Y911272D01*
G03X572185Y911291I703J1288D01*
G02X574413I1114J-1919D01*
G03X575149Y911091I740J1268D01*
G01X580677D01*
G01X571448Y918938D02*
G02X573486Y919915I2310J-2204D01*
G03X574413Y920208I-189J2211D01*
G02X575258Y920436I845J-1452D01*
G01X578205D01*
G01X565897Y922127D02*
G02X567742Y923095I1845J-1274D01*
G03X568862Y923396I4J2219D01*
G01Y923397D01*
G02X570334I736J-1270D01*
G03X572562I1114J1919D01*
G02X574002Y923416I737J-1270D01*
G01X574035Y923397D01*
G03X575149Y923097I1114J1918D01*
G01X579582D01*
X580364Y923879D01*
X581725D01*
G01X573299Y922127D02*
X572933Y921497D01*
G03X573452Y920667I463J-288D01*
G03X574002Y920838I-152J1460D01*
G01X574035Y920857D01*
G02X577261Y921726I3226J-5555D01*
G01X579818D01*
X580158Y922066D01*
X581682D01*
G01X567748Y925316D02*
Y925315D01*
X567334Y924603D01*
G03X567742Y923848I541J-195D01*
G03X568451Y924027I7J1466D01*
G01X568455Y924029D01*
X568484Y924046D01*
G02X570712I1114J-1919D01*
G01X570745Y924027D01*
G03X572185Y924046I703J1289D01*
G02X574413I1114J-1919D01*
G03X575149Y923847I738J1269D01*
G01X578763D01*
X580442Y925526D01*
X581742D01*
G01X571448Y925316D02*
G02X573486Y926293I2310J-2204D01*
G03X574413Y926586I-189J2211D01*
G02X575228Y926806I815J-1401D01*
G01X579810D01*
X580330Y927326D01*
X581842D01*
G01X573299Y915749D02*
X572896Y915055D01*
G03X573553Y914303I556J-177D01*
G03X574002Y914460I-253J1443D01*
G01X574035Y914479D01*
G02X574963Y914772I1116J-1918D01*
G02X575148Y914779I176J-2212D01*
G01X578786D01*
X579836Y913729D01*
X581275D01*
X581535Y913989D01*
X581610D01*
G01X565897Y915749D02*
G02X567922Y916725I2272J-2125D01*
G03X568015Y916734I-167J2213D01*
G03X568862Y917019I-270J2203D01*
G02X570334I736J-1270D01*
G03X572562I1114J1919D01*
G02X574002Y917038I737J-1270D01*
G01X574035Y917019D01*
G03X575149Y916719I1114J1918D01*
G01X579672D01*
X579932Y916459D01*
X580007D01*
G01X571448Y912560D02*
G02X573531Y913542I2450J-2497D01*
G03X573683Y913563I-228J2207D01*
G03X574413Y913830I-385J2185D01*
G02X575027Y914024I739J-1269D01*
G02X575149Y914029I121J-1464D01*
G01X578475D01*
X579525Y912979D01*
X581275D01*
X581535Y912719D01*
X581610D01*
G01X567748Y918938D02*
X567347Y918248D01*
G03X567924Y917481I511J-216D01*
G03X568451Y917649I-175J1458D01*
G01X568484Y917668D01*
G02X570712I1114J-1919D01*
G01X570745Y917649D01*
G03X572185Y917668I703J1289D01*
G02X574413I1114J-1919D01*
G03X575149Y917471I734J1270D01*
G01X575151Y917469D01*
X579672D01*
X579932Y917729D01*
X580007D01*
G01X565897Y928505D02*
G02X567742Y929473I1845J-1274D01*
G03X568862Y929774I4J2219D01*
G01Y929775D01*
G02X570334I736J-1270D01*
G03X572562I1114J1919D01*
G02X574002Y929794I737J-1270D01*
G01X574035Y929775D01*
G03X576705Y929056I2670J4598D01*
G01X578602D01*
X579552Y930006D01*
X581792D01*
G01X573299Y928505D02*
X572933Y927875D01*
G03X573452Y927045I463J-288D01*
G03X574002Y927216I-152J1460D01*
G01X574035Y927235D01*
G02X576044Y927776I2009J-3458D01*
G01X579182D01*
X580072Y928666D01*
X581882D01*
G01X567748Y931694D02*
Y931693D01*
X567334Y930981D01*
G03X567742Y930226I541J-195D01*
G03X568451Y930405I7J1466D01*
G01X568455Y930407D01*
X568484Y930424D01*
G02X570712I1114J-1919D01*
G01X570745Y930405D01*
G03X572185Y930424I703J1289D01*
G02X574413I1114J-1919D01*
G03X575222Y930206I809J1391D01*
G01X578242D01*
X579382Y931346D01*
X581662D01*
G01X571448Y938072D02*
G02X573486Y939049I2310J-2204D01*
G03X574413Y939342I-189J2211D01*
G02X575283Y939576I870J-1500D01*
G01X578692D01*
X579002Y939266D01*
X581255D01*
G01X573299Y941261D02*
X572933Y940631D01*
G03X573452Y939801I463J-288D01*
G03X574002Y939972I-152J1460D01*
G02X576604Y940696I2602J-4313D01*
G01X578542D01*
X580082Y942236D01*
G01X573299Y934883D02*
X572896Y934189D01*
G03X573553Y933437I556J-177D01*
G03X574002Y933594I-253J1443D01*
G01X574035Y933613D01*
G02X574963Y933906I1116J-1918D01*
G02X575148Y933913I176J-2212D01*
G01X578568D01*
X579021Y934366D01*
X580367D01*
X580627Y934626D01*
X580702D01*
G01X565897Y934883D02*
G02X567922Y935859I2272J-2125D01*
G03X568015Y935868I-167J2213D01*
G03X568862Y936153I-270J2203D01*
G02X570334I736J-1270D01*
G03X572562I1114J1919D01*
G02X574002Y936172I737J-1270D01*
G01X574035Y936153D01*
G03X575149Y935853I1114J1918D01*
G01X578636D01*
X579389Y936606D01*
X580575D01*
X580835Y936346D01*
X580910D01*
G01X571448Y931694D02*
G02X573531Y932676I2450J-2497D01*
G03X573683Y932697I-228J2207D01*
G03X574413Y932964I-385J2185D01*
G02X575027Y933158I739J-1269D01*
G02X575149Y933163I121J-1464D01*
G01X578879D01*
X579332Y933616D01*
X580367D01*
X580627Y933356D01*
X580702D01*
G01X567748Y938072D02*
X567347Y937382D01*
G03X567924Y936615I511J-216D01*
G03X568451Y936783I-175J1458D01*
G01X568484Y936802D01*
G02X570712I1114J-1919D01*
G01X570745Y936783D01*
G03X572185Y936802I703J1289D01*
G02X574413I1114J-1919D01*
G03X575149Y936605I734J1270D01*
G01X575151Y936603D01*
X578325D01*
X579078Y937356D01*
X580575D01*
X580835Y937616D01*
X580910D01*
G01X565897Y941261D02*
G02X567742Y942229I1845J-1274D01*
G03X568862Y942530I4J2219D01*
G01Y942531D01*
G02X570334I736J-1270D01*
G03X572562I1114J1919D01*
G02X574002Y942550I737J-1270D01*
G01X574035Y942531D01*
G03X576579Y941846I2544J4380D01*
G01X578189D01*
X579919Y943576D01*
X580925D01*
G01X567748Y944450D02*
Y944449D01*
X567334Y943737D01*
G03X567742Y942982I541J-195D01*
G03X568451Y943161I7J1466D01*
G01X568455Y943163D01*
X568484Y943180D01*
G02X570712I1114J-1919D01*
G01X570745Y943161D01*
G03X572185Y943180I703J1289D01*
G02X574413I1114J-1919D01*
G03X575244Y942956I831J1429D01*
G01X578237D01*
X580197Y944916D01*
X581225D01*
G01X571448Y944450D02*
G02X573486Y945427I2310J-2204D01*
G03X574413Y945720I-189J2211D01*
G02X575959Y946136I1546J-2666D01*
G01X579362D01*
X579942Y946716D01*
X581485D01*
G01X565897Y947639D02*
G02X567742Y948607I1845J-1274D01*
G03X568862Y948908I4J2219D01*
G01Y948909D01*
G02X570334I736J-1270D01*
G03X572562I1114J1919D01*
G02X574002Y948928I737J-1270D01*
G01X574035Y948909D01*
G03X575272Y948576I1237J2129D01*
G01X579042D01*
X579054Y948588D01*
X581134Y949449D01*
X581945D01*
G01X573299Y947639D02*
X572933Y947009D01*
G03X573452Y946179I463J-288D01*
G03X574002Y946350I-152J1460D01*
G02X577689Y947376I3687J-6112D01*
G01X579222D01*
X579912Y948066D01*
X581575D01*
G01X567748Y950828D02*
Y950827D01*
X567334Y950115D01*
G03X567742Y949360I541J-195D01*
G03X568451Y949539I7J1466D01*
G01X568455Y949541D01*
X568484Y949558D01*
G02X570712I1114J-1919D01*
G01X570745Y949539D01*
G03X572185Y949558I703J1289D01*
G02X574413I1114J-1919D01*
G03X575236Y949336I823J1416D01*
G01X578392D01*
X579895Y950839D01*
X581885D01*
G01X573299Y954017D02*
X572896Y953323D01*
G03X573553Y952571I556J-177D01*
G03X574002Y952728I-253J1443D01*
G01X574035Y952747D01*
G02X574963Y953040I1116J-1918D01*
G02X575148Y953047I176J-2212D01*
G01X578754D01*
X579554Y953847D01*
X580865D01*
X581125Y954107D01*
X581200D01*
G01X565897Y954017D02*
G02X567922Y954993I2272J-2125D01*
G03X568015Y955002I-167J2213D01*
G03X568862Y955287I-270J2203D01*
G02X570334I736J-1270D01*
G03X572562I1114J1919D01*
G02X574002Y955306I737J-1270D01*
G01X574035Y955287D01*
G03X575149Y954987I1114J1918D01*
G01X578602D01*
X580001Y956386D01*
X581063D01*
X581323Y956126D01*
X581398D01*
G01X571448Y950828D02*
G02X573531Y951810I2450J-2497D01*
G03X573683Y951831I-228J2207D01*
G03X574413Y952098I-385J2185D01*
G02X575027Y952292I739J-1269D01*
G02X575149Y952297I121J-1464D01*
G01X579065D01*
X579865Y953097D01*
X580865D01*
X581125Y952837D01*
X581200D01*
G01X571448Y963584D02*
G02X573486Y964561I2310J-2204D01*
G03X574413Y964854I-189J2211D01*
G02X575027Y965048I739J-1269D01*
G02X575463Y965066I436J-5268D01*
G01X579178D01*
X579278Y964966D01*
X580762D01*
G01X565897Y966773D02*
G02X567742Y967741I1845J-1274D01*
G03X568862Y968042I4J2219D01*
G01Y968043D01*
G02X570334I736J-1270D01*
G03X572562I1114J1919D01*
G02X574002Y968062I737J-1270D01*
G01X574035Y968043D01*
G03X576326Y967426I2291J3945D01*
G01X579782D01*
X580025Y967669D01*
X581738D01*
G01X573299Y966773D02*
X572933Y966143D01*
G03X573452Y965313I463J-288D01*
G03X574002Y965484I-152J1460D01*
G01X574035Y965503D01*
G02X574419Y965680I1117J-1918D01*
G02X578189Y966319I3770J-10804D01*
G01X580755D01*
G01X567748Y969962D02*
Y969961D01*
X567334Y969249D01*
G03X567742Y968494I541J-195D01*
G03X568451Y968673I7J1466D01*
G01X568455Y968675D01*
X568484Y968692D01*
G02X570712I1114J-1919D01*
G01X570745Y968673D01*
G03X572185Y968692I703J1289D01*
G02X574413I1114J-1919D01*
G03X575214Y968476I801J1378D01*
G01X578982D01*
X579535Y969029D01*
X581125D01*
G01X571448Y957206D02*
G02X573486Y958183I2310J-2204D01*
G03X574413Y958476I-189J2211D01*
G02X575027Y958670I739J-1269D01*
G02X575414Y958686I387J-4683D01*
G01X580662D01*
X581002Y959026D01*
X582185D01*
G01X565897Y960395D02*
G02X567742Y961363I1845J-1274D01*
G03X568862Y961664I4J2219D01*
G01Y961665D01*
G02X570334I736J-1270D01*
G03X572562I1114J1919D01*
G02X574002Y961684I737J-1270D01*
G01X574035Y961665D01*
G03X576408Y961026I2373J4086D01*
G01X579292D01*
X580025Y961759D01*
X581715D01*
G01X573299Y960395D02*
X572933Y959765D01*
G03X573452Y958935I463J-288D01*
G03X574002Y959106I-152J1460D01*
G01X574035Y959125D01*
G02X574361Y959280I1113J-1920D01*
G02X577807Y959916I3446J-9020D01*
G01X580212D01*
X580685Y960389D01*
X581995D01*
G01X567748Y963584D02*
Y963583D01*
X567334Y962871D01*
G03X567742Y962116I541J-195D01*
G03X568451Y962295I7J1466D01*
G01X568455Y962297D01*
X568484Y962314D01*
G02X570712I1114J-1919D01*
G01X570745Y962295D01*
G03X572185Y962314I703J1289D01*
G02X574413I1114J-1919D01*
G03X575222Y962096I809J1391D01*
G01X578402D01*
X579412Y963106D01*
X581558D01*
G01X571448Y969962D02*
G02X573531Y970944I2450J-2497D01*
G03X573683Y970965I-228J2207D01*
G03X574413Y971232I-385J2185D01*
G02X575027Y971426I739J-1269D01*
G02X575149Y971431I121J-1464D01*
G01X578693D01*
X579195Y970929D01*
X580055D01*
X580315Y970669D01*
X580390D01*
G01X567748Y957206D02*
X567347Y956516D01*
G03X567924Y955749I511J-216D01*
G03X568451Y955917I-175J1458D01*
G01X568484Y955936D01*
G02X570712I1114J-1919D01*
G01X570745Y955917D01*
G03X572185Y955936I703J1289D01*
G02X574413I1114J-1919D01*
G03X575149Y955739I734J1270D01*
G01X575151Y955737D01*
X578291D01*
X579690Y957136D01*
X581063D01*
X581323Y957396D01*
X581398D01*
G01X571448Y982718D02*
G02X573486Y983695I2310J-2204D01*
G03X573932Y983779I-186J2211D01*
G03X574208Y983899I-368J1224D01*
G01X575186Y984466D01*
G02X577792Y985166I2605J-4498D01*
G01X571448Y976340D02*
G02X573531Y977322I2450J-2497D01*
G03X573683Y977343I-228J2207D01*
G03X574413Y977610I-385J2185D01*
G02X575027Y977804I739J-1269D01*
G02X575149Y977809I121J-1464D01*
G01X578329D01*
X579537Y976601D01*
X580443D01*
G01X565897Y979529D02*
G02X567742Y980497I1845J-1274D01*
G03X568862Y980798I4J2219D01*
G01Y980799D01*
G02X570334I736J-1270D01*
G03X572562I1114J1919D01*
G02X574002Y980818I737J-1270D01*
G01X574035Y980799D01*
G03X576794Y980056I2759J4751D01*
G01X579162D01*
X580669Y981563D01*
G01X573299Y979529D02*
X572896Y978835D01*
G03X573553Y978083I556J-177D01*
G03X574002Y978240I-253J1443D01*
G01X574035Y978259D01*
G02X574963Y978552I1116J-1918D01*
G02X575148Y978559I176J-2212D01*
G01X579355D01*
X581019Y980223D01*
G01X567748Y982718D02*
Y982717D01*
X567334Y982005D01*
G03X567742Y981250I541J-195D01*
G03X568451Y981429I7J1466D01*
G01X568455Y981431D01*
X568484Y981448D01*
G02X570712I1114J-1919D01*
G01X570745Y981429D01*
G03X572185Y981448I703J1289D01*
G02X574413I1114J-1919D01*
G03X575236Y981226I823J1416D01*
G01X578382D01*
X580059Y982903D01*
X580765D01*
G01X573299Y973151D02*
X572896Y972457D01*
G03X573553Y971705I556J-177D01*
G03X574002Y971862I-253J1443D01*
G01X574035Y971881D01*
G02X574963Y972174I1116J-1918D01*
G02X575148Y972181I176J-2212D01*
G01X579004D01*
X579506Y971679D01*
X580055D01*
X580315Y971939D01*
X580390D01*
G01X565897Y973151D02*
G02X567922Y974127I2272J-2125D01*
G03X568015Y974136I-167J2213D01*
G03X568862Y974421I-270J2203D01*
G02X570334I736J-1270D01*
G03X572562I1114J1919D01*
G02X574002Y974440I737J-1270D01*
G01X574035Y974421D01*
G03X575149Y974121I1114J1918D01*
G01X576965D01*
X577125Y973961D01*
X580042D01*
X580302Y973701D01*
X580377D01*
G01X567748Y976340D02*
X567347Y975650D01*
G03X567924Y974883I511J-216D01*
G03X568451Y975051I-175J1458D01*
G01X568484Y975070D01*
G02X570712I1114J-1919D01*
G01X570745Y975051D01*
G03X572185Y975070I703J1289D01*
G02X574413I1114J-1919D01*
G03X575149Y974873I734J1270D01*
G01X575151Y974871D01*
X577276D01*
X577436Y974711D01*
X580042D01*
X580302Y974971D01*
X580377D01*
G01X571448Y995474D02*
G02X573486Y996451I2310J-2204D01*
G03X574413Y996744I-189J2211D01*
G02X575236Y996966I823J-1414D01*
G01X578732D01*
X578902Y996796D01*
X581355D01*
G01X573299Y998663D02*
X572933Y998033D01*
G03X573452Y997203I463J-288D01*
G03X574002Y997374I-152J1460D01*
G01X574035Y997393D01*
G02X576790Y998136I2755J-4736D01*
G01X581442D01*
G01X565897Y998663D02*
G02X567742Y999631I1845J-1274D01*
G03X568862Y999932I4J2219D01*
G01Y999933D01*
G02X570334I736J-1270D01*
G03X572562I1114J1919D01*
G02X574002Y999952I737J-1270D01*
G01X574035Y999933D01*
G03X576326Y999316I2291J3945D01*
G01X581265D01*
X581425Y999476D01*
G01X571448Y989096D02*
G02X573486Y990073I2310J-2204D01*
G03X574413Y990366I-189J2211D01*
G02X575228Y990586I815J-1401D01*
G01X580172D01*
G01X565897Y992285D02*
G02X567742Y993253I1845J-1274D01*
G03X568862Y993554I4J2219D01*
G01Y993555D01*
G02X570334I736J-1270D01*
G03X572562I1114J1919D01*
G02X574002Y993574I737J-1270D01*
G01X574035Y993555D01*
G03X576816Y992806I2781J4789D01*
G01X578592D01*
G01X573299Y1011419D02*
X572933Y1010789D01*
G03X573452Y1009959I463J-288D01*
G03X574002Y1010130I-152J1460D01*
G01X574035Y1010149D01*
G02X574963Y1010442I1116J-1918D01*
G01X574966Y1010446D01*
G02X575519Y1010468I553J-6934D01*
G01X575613D01*
X575617Y1010464D01*
X576324D01*
X577211Y1011351D01*
X578495D01*
X578790Y1011646D01*
X578865D01*
G01X571448Y1008230D02*
G02X573486Y1009207I2310J-2204D01*
G03X574413Y1009500I-189J2211D01*
G02X575027Y1009694I739J-1269D01*
G02X575511Y1009714I484J-5854D01*
G01X576635D01*
X577522Y1010601D01*
X578495D01*
X578790Y1010306D01*
X578865D01*
G01X567748Y1001852D02*
Y1001851D01*
X567334Y1001139D01*
G03X567742Y1000384I541J-195D01*
G03X568451Y1000563I7J1466D01*
G01X568455Y1000565D01*
X568484Y1000582D01*
G02X570712I1114J-1919D01*
G01X570745Y1000563D01*
G03X572185Y1000582I703J1289D01*
G02X574413I1114J-1919D01*
G03X575214Y1000366I801J1378D01*
G01X578832D01*
X579282Y1000816D01*
X581355D01*
G01X571448Y1001852D02*
G02X573486Y1002829I2310J-2204D01*
G03X574413Y1003122I-189J2211D01*
G02X575236Y1003344I823J-1414D01*
G01X579700D01*
X579730Y1003374D01*
X581385D01*
G01X573299Y1005041D02*
X572933Y1004411D01*
G03X573452Y1003581I463J-288D01*
G03X574002Y1003752I-152J1460D01*
G01X574035Y1003771D01*
G02X576790Y1004514I2755J-4736D01*
G01X580020D01*
X580220Y1004714D01*
X581385D01*
G01X565897Y1005041D02*
G02X567742Y1006009I1845J-1274D01*
G03X568862Y1006310I4J2219D01*
G01Y1006311D01*
G02X570334I736J-1270D01*
G03X572562I1114J1919D01*
G02X574002Y1006330I737J-1270D01*
G01X574035Y1006311D01*
G03X575614Y1005740I2361J4059D01*
G03X575914Y1005716I293J1780D01*
G01X579562D01*
X579900Y1006054D01*
X581315D01*
G01X567748Y1008230D02*
Y1008229D01*
X567334Y1007517D01*
G03X567742Y1006762I541J-195D01*
G03X568451Y1006941I7J1466D01*
G01X568455Y1006943D01*
X568484Y1006960D01*
G02X570712I1114J-1919D01*
G01X570745Y1006941D01*
G03X572185Y1006960I703J1289D01*
G02X574413I1114J-1919D01*
G03X575244Y1006736I831J1429D01*
G01X578562D01*
X579220Y1007394D01*
X581125D01*
G01X568929Y1030198D02*
X568502Y1030933D01*
G02X569099Y1031656I533J168D01*
G02X569632Y1031487I-169J-1458D01*
G01X569665Y1031468D01*
G03X571893I1114J1919D01*
G01X571894D01*
G02X573366I736J-1268D01*
G03X575594I1114J1919D01*
G02X575919Y1031634I1665J-2859D01*
G02X576214Y1031697I297J-667D01*
G01X579487Y1031702D01*
X580331Y1030858D01*
X582219D01*
G01X567078Y1033387D02*
G03X568874Y1032417I1746J1085D01*
G02X570043Y1032117I54J-2218D01*
G03X571515I736J1270D01*
G02X573743I1114J-1919D01*
G03X575183Y1032098I737J1270D01*
G01X575216Y1032117D01*
G02X576047Y1032482I2009J-3446D01*
G02X576345Y1032526I295J-965D01*
G01X580378D01*
X580706Y1032198D01*
X581929D01*
G01X572629Y1036576D02*
G03X574712Y1035594I2450J2497D01*
G02X574864Y1035573I-228J-2207D01*
G02X575594Y1035306I-385J-2185D01*
G03X576208Y1035112I739J1269D01*
G03X576330Y1035107I121J1464D01*
G01X580214D01*
X580443Y1034878D01*
X581640D01*
G01X568929Y1036576D02*
X568502Y1037311D01*
G02X569099Y1038034I533J168D01*
G02X569632Y1037865I-169J-1458D01*
G01X569665Y1037846D01*
G03X571893I1114J1919D01*
G01X571894D01*
G02X573366I736J-1268D01*
G03X575594I1114J1919D01*
G02X575919Y1038012I1665J-2859D01*
G02X576214Y1038075I297J-667D01*
G01X579552Y1038079D01*
X580193Y1037421D01*
X582453D01*
G01X567078Y1039765D02*
G03X568874Y1038795I1746J1085D01*
G02X570043Y1038495I54J-2218D01*
G03X571515I736J1270D01*
G02X573743I1114J-1919D01*
G03X575183Y1038476I737J1270D01*
G01X575216Y1038495D01*
G02X576047Y1038860I2009J-3446D01*
G02X576345Y1038904I295J-965D01*
G01X580075D01*
X580218Y1038761D01*
X582177D01*
G01X567078Y1046143D02*
G03X568874Y1045173I1746J1085D01*
G02X570043Y1044873I54J-2218D01*
G03X571515I736J1270D01*
G02X573743I1114J-1919D01*
G03X575183Y1044854I737J1270D01*
G01X575216Y1044873D01*
G02X576047Y1045238I2009J-3446D01*
G02X576345Y1045282I295J-965D01*
G01X580214D01*
X580357Y1045139D01*
X582137D01*
G01X568929Y1042954D02*
X568502Y1043689D01*
G02X569099Y1044412I533J168D01*
G02X569632Y1044243I-169J-1458D01*
G01X569665Y1044224D01*
G03X571893I1114J1919D01*
G01X571894D01*
G02X573366I736J-1268D01*
G03X575594I1114J1919D01*
G02X575919Y1044390I1665J-2859D01*
G02X576214Y1044453I297J-667D01*
G01X579649Y1044457D01*
X580307Y1043799D01*
X582354D01*
G01X568929Y1049332D02*
X568502Y1050067D01*
G02X569099Y1050790I533J168D01*
G02X569632Y1050621I-169J-1458D01*
G01X569665Y1050602D01*
G03X571893I1114J1919D01*
G01X571894D01*
G02X573366I736J-1268D01*
G03X575594I1114J1919D01*
G02X575919Y1050768I1665J-2859D01*
G02X576214Y1050831I297J-667D01*
G01X579533Y1050835D01*
X579636Y1050728D01*
X580189Y1050175D01*
X581476D01*
G01X572629Y1049332D02*
G03X574396Y1048361I1694J989D01*
G02X575594Y1048062I83J-2217D01*
G03X576475Y1047824I883J1520D01*
G01X579613Y1047819D01*
X581682D01*
G01X572629Y1074844D02*
G03X574712Y1073862I2450J2497D01*
G02X574864Y1073841I-228J-2207D01*
G02X575594Y1073574I-385J-2185D01*
G03X576208Y1073380I739J1269D01*
G03X576330Y1073375I121J1464D01*
G01X579901D01*
X580569Y1072707D01*
X581790D01*
G01X568929Y1062088D02*
X568502Y1062823D01*
G02X569099Y1063546I533J168D01*
G02X569632Y1063377I-169J-1458D01*
G01X569665Y1063358D01*
G03X571893I1114J1919D01*
G01X571894D01*
G02X573366I736J-1268D01*
G03X575594I1114J1919D01*
G02X575919Y1063524I1665J-2859D01*
G02X576214Y1063587I297J-667D01*
G01X579402Y1063592D01*
X580993Y1062001D01*
X581382D01*
G01X572629Y1062088D02*
G03X574712Y1061106I2450J2497D01*
G02X574864Y1061085I-228J-2207D01*
G02X575594Y1060818I-385J-2185D01*
G03X576208Y1060624I739J1269D01*
G03X576330Y1060619I121J1464D01*
G01X579716D01*
X579886Y1060449D01*
X582531D01*
G01X567078Y1065277D02*
G03X568874Y1064307I1746J1085D01*
G02X570043Y1064007I54J-2218D01*
G03X571515I736J1270D01*
G02X573743I1114J-1919D01*
G03X575183Y1063988I737J1270D01*
G01X575216Y1064007D01*
G02X576047Y1064372I2009J-3446D01*
G02X576345Y1064416I295J-965D01*
G01X579898D01*
X580395Y1063919D01*
X582085D01*
G01X568929Y1068466D02*
X568528Y1069156D01*
G02X569105Y1069923I511J216D01*
G02X569632Y1069755I-175J-1458D01*
G01X569665Y1069736D01*
G03X571893I1114J1919D01*
G01X571926Y1069755D01*
G02X573366Y1069736I703J-1289D01*
G03X575594I1114J1919D01*
G02X576330Y1069933I734J-1270D01*
G01X576332Y1069935D01*
X579582D01*
X580780Y1068737D01*
X582024D01*
X582284Y1068477D01*
X582359D01*
G01X572629Y1068466D02*
G03X574712Y1067484I2450J2497D01*
G02X574864Y1067463I-228J-2207D01*
G02X575594Y1067196I-385J-2185D01*
G03X576208Y1067002I739J1269D01*
G03X576330Y1066997I121J1464D01*
G01X578578D01*
X579018Y1066557D01*
X580643D01*
X580903Y1066817D01*
X580978D01*
G01X567078Y1071655D02*
G03X569103Y1070679I2272J2125D01*
G02X569196Y1070670I-167J-2213D01*
G02X570043Y1070385I-270J-2203D01*
G03X571515I736J1270D01*
G02X573743I1114J-1919D01*
G03X575183Y1070366I737J1270D01*
G01X575216Y1070385D01*
G02X576330Y1070685I1114J-1918D01*
G01X579893D01*
X581091Y1069487D01*
X582024D01*
X582284Y1069747D01*
X582359D01*
G01X568929Y1074844D02*
X568502Y1075579D01*
G02X569099Y1076302I533J168D01*
G02X569632Y1076133I-169J-1458D01*
G01X569665Y1076114D01*
G03X571893I1114J1919D01*
G01X571894D01*
G02X573366I736J-1268D01*
G03X575594I1114J1919D01*
G02X575919Y1076280I1665J-2859D01*
G02X576214Y1076343I297J-667D01*
G01X579399Y1076348D01*
X581700Y1074047D01*
X582172D01*
G01X567078Y1078033D02*
G03X568874Y1077063I1746J1085D01*
G02X570043Y1076763I54J-2218D01*
G03X571515I736J1270D01*
G02X573743I1114J-1919D01*
G03X575183Y1076744I737J1270D01*
G01X575216Y1076763D01*
G02X576047Y1077128I2009J-3446D01*
G02X576345Y1077172I295J-965D01*
G01X579769D01*
X581554Y1075387D01*
X582240D01*
G01X568929Y1081222D02*
X568502Y1081957D01*
G02X569099Y1082680I533J168D01*
G02X569632Y1082511I-169J-1458D01*
G01X569665Y1082492D01*
G03X571893I1114J1919D01*
G01X571894D01*
G02X573366I736J-1268D01*
G03X575594I1114J1919D01*
G02X575919Y1082658I1665J-2859D01*
G02X576214Y1082721I297J-667D01*
G01X580814Y1082727D01*
X581230Y1082311D01*
X581434D01*
G01X572629Y1081222D02*
G03X574712Y1080240I2450J2497D01*
G02X574864Y1080219I-228J-2207D01*
G02X575594Y1079952I-385J-2185D01*
G03X576208Y1079758I739J1269D01*
G03X576330Y1079753I121J1464D01*
G01X580062D01*
X580385Y1079430D01*
X582238D01*
G01X567078Y1084411D02*
G03X568874Y1083441I1746J1085D01*
G02X570043Y1083141I54J-2218D01*
G03X571515I736J1270D01*
G02X573743I1114J-1919D01*
G03X575183Y1083122I737J1270D01*
G01X575216Y1083141D01*
G02X576047Y1083506I2009J-3446D01*
G02X577018Y1083651I971J-3178D01*
G01X582441D01*
G01X572629Y1087600D02*
G03X574712Y1086618I2450J2497D01*
G02X574864Y1086597I-228J-2207D01*
G02X575594Y1086330I-385J-2185D01*
G03X576208Y1086136I739J1269D01*
G03X576330Y1086131I121J1464D01*
G01X579932D01*
X580090Y1086289D01*
X582024D01*
X582284Y1086549D01*
X582359D01*
G01X568929Y1087600D02*
X568528Y1088290D01*
G02X569105Y1089057I511J216D01*
G02X569632Y1088889I-175J-1458D01*
G01X569665Y1088870D01*
G03X571893I1114J1919D01*
G01X571926Y1088889D01*
G02X573366Y1088870I703J-1289D01*
G03X575594I1114J1919D01*
G02X576330Y1089067I734J-1270D01*
G01X576332Y1089069D01*
X579582D01*
X580147Y1088504D01*
X582024D01*
X582284Y1088244D01*
X582359D01*
G01X567078Y1090789D02*
G03X569103Y1089813I2272J2125D01*
G02X569196Y1089804I-167J-2213D01*
G02X570043Y1089519I-270J-2203D01*
G03X571515I736J1270D01*
G02X573743I1114J-1919D01*
G03X575183Y1089500I737J1270D01*
G01X575216Y1089519D01*
G02X576330Y1089819I1114J-1918D01*
G01X579893D01*
X580458Y1089254D01*
X582024D01*
X582284Y1089514D01*
X582359D01*
G01X572629Y1100356D02*
G03X574712Y1099374I2450J2497D01*
G02X574864Y1099353I-228J-2207D01*
G02X575594Y1099086I-385J-2185D01*
G03X576208Y1098892I739J1269D01*
G03X576330Y1098887I121J1464D01*
G01X579716D01*
X579760Y1098843D01*
X582475D01*
G01X567078Y1103545D02*
G03X568874Y1102575I1746J1085D01*
G02X570043Y1102275I54J-2218D01*
G03X571515I736J1270D01*
G02X573743I1114J-1919D01*
G03X575183Y1102256I737J1270D01*
G01X575216Y1102275D01*
G02X576047Y1102640I2009J-3446D01*
G02X576345Y1102684I295J-965D01*
G01X579719D01*
X580880Y1101523D01*
X582089D01*
G01X568929Y1093978D02*
X568502Y1094713D01*
G02X569099Y1095436I533J168D01*
G02X569632Y1095267I-169J-1458D01*
G01X569665Y1095248D01*
G03X571893I1114J1919D01*
G01X571894D01*
G02X573366I736J-1268D01*
G03X575594I1114J1919D01*
G02X575919Y1095414I1665J-2859D01*
G02X576214Y1095477I297J-667D01*
G01X578961Y1095481D01*
X582170Y1094149D01*
G01X572629Y1093978D02*
G03X574712Y1092996I2450J2497D01*
G02X574864Y1092975I-228J-2207D01*
G02X575594Y1092708I-385J-2185D01*
G03X576208Y1092514I739J1269D01*
G03X576330Y1092509I121J1464D01*
G01X581385D01*
X581445Y1092569D01*
G01X567078Y1097167D02*
G03X568874Y1096197I1746J1085D01*
G02X570043Y1095897I54J-2218D01*
G03X571515I736J1270D01*
G02X573743I1114J-1919D01*
G03X575183Y1095878I737J1270D01*
G01X575216Y1095897D01*
G02X576047Y1096262I2009J-3446D01*
G02X576345Y1096306I295J-965D01*
G01X580946D01*
X581688Y1095564D01*
X582667D01*
G01X568929Y1100356D02*
X568502Y1101091D01*
G02X569099Y1101814I533J168D01*
G02X569632Y1101645I-169J-1458D01*
G01X569665Y1101626D01*
G03X571893I1114J1919D01*
G01X571894D01*
G02X573366I736J-1268D01*
G03X575594I1114J1919D01*
G02X575919Y1101792I1665J-2859D01*
G02X576214Y1101855I297J-667D01*
G01X579397Y1101859D01*
X581073Y1100183D01*
X582340D01*
G01X568929Y1113112D02*
X568502Y1113847D01*
G02X569099Y1114570I533J168D01*
G02X569632Y1114401I-169J-1458D01*
G01X569665Y1114382D01*
G03X571893I1114J1919D01*
G01X571894D01*
G02X573366I736J-1268D01*
G03X575594I1114J1919D01*
G02X575919Y1114548I1665J-2859D01*
G02X576214Y1114611I297J-667D01*
G01X579317Y1114615D01*
X579405Y1114527D01*
X582666D01*
G01X572629Y1113112D02*
G03X574712Y1112130I2450J2497D01*
G02X574864Y1112109I-228J-2207D01*
G02X575594Y1111842I-385J-2185D01*
G03X576208Y1111648I739J1269D01*
G03X576330Y1111643I121J1464D01*
G01X579804D01*
X581218Y1113057D01*
G01X567078Y1116301D02*
G03X568874Y1115331I1746J1085D01*
G02X570043Y1115031I54J-2218D01*
G03X571515I736J1270D01*
G02X573743I1114J-1919D01*
G03X575183Y1115012I737J1270D01*
G01X575216Y1115031D01*
G02X576047Y1115396I2009J-3446D01*
G02X576345Y1115440I295J-965D01*
G01X580246D01*
X580673Y1115867D01*
X582632D01*
G01X568929Y1119490D02*
X568502Y1120225D01*
G02X569099Y1120948I533J168D01*
G02X569632Y1120779I-169J-1458D01*
G01X569665Y1120760D01*
G03X571893I1114J1919D01*
G01X571894D01*
G02X573366I736J-1268D01*
G03X575594I1114J1919D01*
G02X575919Y1120926I1665J-2859D01*
G02X576214Y1120989I297J-667D01*
G01X579719Y1120994D01*
X580052D01*
X580621Y1120425D01*
X581310D01*
G01X572629Y1119490D02*
G03X574712Y1118508I2450J2497D01*
G02X574864Y1118487I-228J-2207D01*
G02X575594Y1118220I-385J-2185D01*
G03X576208Y1118026I739J1269D01*
G03X576330Y1118021I121J1464D01*
G01X579801D01*
X580797Y1119017D01*
X581487D01*
G01X572629Y1106734D02*
G03X574712Y1105752I2450J2497D01*
G02X574864Y1105731I-228J-2207D01*
G02X575594Y1105464I-385J-2185D01*
G03X576208Y1105270I739J1269D01*
G03X576330Y1105265I121J1464D01*
G01X580042D01*
X581055Y1104252D01*
X582024D01*
X582284Y1104512D01*
X582359D01*
G01X568929Y1106734D02*
X568528Y1107424D01*
G02X569105Y1108191I511J216D01*
G02X569632Y1108023I-175J-1458D01*
G01X569665Y1108004D01*
G03X571893I1114J1919D01*
G01X571926Y1108023D01*
G02X573366Y1108004I703J-1289D01*
G03X575594I1114J1919D01*
G02X576330Y1108201I734J-1270D01*
G01X576332Y1108203D01*
X579610D01*
X580896Y1106917D01*
X582024D01*
X582284Y1106657D01*
X582359D01*
G01X567078Y1109923D02*
G03X569103Y1108947I2272J2125D01*
G02X569196Y1108938I-167J-2213D01*
G02X570043Y1108653I-270J-2203D01*
G03X571515I736J1270D01*
G02X573743I1114J-1919D01*
G03X575183Y1108634I737J1270D01*
G01X575216Y1108653D01*
G02X576330Y1108953I1114J-1918D01*
G01X579921D01*
X581207Y1107667D01*
X582024D01*
X582284Y1107927D01*
X582359D01*
G01X567078Y1122679D02*
G03X568874Y1121709I1746J1085D01*
G02X570043Y1121409I54J-2218D01*
G03X571515I736J1270D01*
G02X573743I1114J-1919D01*
G03X575183Y1121390I737J1270D01*
G01X575216Y1121409D01*
G02X576047Y1121774I2009J-3446D01*
G02X576345Y1121818I295J-965D01*
G01X581135D01*
G01X568929Y1132246D02*
X568502Y1132981D01*
G02X569099Y1133704I533J168D01*
G02X569632Y1133535I-169J-1458D01*
G01X569665Y1133516D01*
G03X571893I1114J1919D01*
G01X571894D01*
G02X573366I736J-1268D01*
G03X575594I1114J1919D01*
G02X575919Y1133682I1665J-2859D01*
G02X576214Y1133745I297J-667D01*
G01X579719Y1133750D01*
X580302D01*
X580444Y1133892D01*
X582337D01*
G01X572629Y1132246D02*
G03X574712Y1131264I2450J2497D01*
G02X574864Y1131243I-228J-2207D01*
G02X575594Y1130976I-385J-2185D01*
G03X576208Y1130782I739J1269D01*
G03X576330Y1130777I121J1464D01*
G01X579596D01*
X581371Y1132552D01*
X582265D01*
G01X567078Y1135434D02*
G03X568874Y1134465I2518J2518D01*
G02X570043Y1134165I54J-2218D01*
G03X571515I736J1270D01*
G02X573743I1114J-1919D01*
G03X575183Y1134146I737J1270D01*
G01X575216Y1134165D01*
G02X576047Y1134530I2009J-3446D01*
G02X576345Y1134574I295J-965D01*
G01X579708D01*
X580366Y1135232D01*
X582470D01*
G01X572629Y1125868D02*
G03X574712Y1124886I2450J2497D01*
G02X574864Y1124865I-228J-2207D01*
G02X575594Y1124598I-385J-2185D01*
G03X576208Y1124404I739J1269D01*
G03X576330Y1124399I121J1464D01*
G01X580344D01*
X580404Y1124459D01*
X582024D01*
X582284Y1124719D01*
X582359D01*
G01X568929Y1125868D02*
X568528Y1126558D01*
G02X569105Y1127325I511J216D01*
G02X569632Y1127157I-175J-1458D01*
G01X569665Y1127138D01*
G03X571893I1114J1919D01*
G01X571926Y1127157D01*
G02X573366Y1127138I703J-1289D01*
G03X575594I1114J1919D01*
G02X576330Y1127335I734J-1270D01*
G01X576332Y1127337D01*
X579811D01*
X580482Y1126666D01*
X582024D01*
X582284Y1126406D01*
X582359D01*
G01X567078Y1129057D02*
G03X569103Y1128081I2272J2125D01*
G02X569196Y1128072I-167J-2213D01*
G02X570043Y1127787I-270J-2203D01*
G03X571515I736J1270D01*
G02X573743I1114J-1919D01*
G03X575183Y1127768I737J1270D01*
G01X575216Y1127787D01*
G02X576330Y1128087I1114J-1918D01*
G01X580122D01*
X580793Y1127416D01*
X582024D01*
X582284Y1127676D01*
X582359D01*
G01X568929Y1138623D02*
X568502Y1139358D01*
G02X569099Y1140081I533J168D01*
G02X569632Y1139912I-169J-1458D01*
G01X569665Y1139893D01*
G03X571893I1114J1919D01*
G01X571894D01*
G02X573366I736J-1268D01*
G03X575594I1114J1919D01*
G02X575919Y1140059I1665J-2859D01*
G02X576214Y1140122I297J-667D01*
G01X579719Y1140127D01*
X580164D01*
X580579Y1139712D01*
X581545D01*
G01X572629Y1138623D02*
G03X574712Y1137641I2450J2497D01*
G02X574864Y1137620I-228J-2207D01*
G02X575594Y1137353I-385J-2185D01*
G03X576208Y1137159I739J1269D01*
G03X576330Y1137154I121J1464D01*
G01X579590D01*
X580808Y1138372D01*
X581648D01*
G01X567078Y1141812D02*
G03X568874Y1140842I1746J1085D01*
G02X570043Y1140542I54J-2218D01*
G03X571515I736J1270D01*
G02X573743I1114J-1919D01*
G03X575183Y1140523I737J1270D01*
G01X575216Y1140542D01*
G02X576047Y1140907I2009J-3446D01*
G02X577018Y1141052I971J-3178D01*
G01X581443D01*
G01X572629Y1145001D02*
G03X574712Y1144019I2450J2497D01*
G02X574864Y1143998I-228J-2207D01*
G02X575594Y1143731I-385J-2185D01*
G03X576208Y1143537I739J1269D01*
G03X576330Y1143532I121J1464D01*
G01X579769D01*
X580496Y1144259D01*
X581536D01*
X581796Y1144519D01*
X581871D01*
G01X568929Y1145001D02*
X568528Y1145691D01*
G02X569105Y1146458I511J216D01*
G02X569632Y1146290I-175J-1458D01*
G01X569665Y1146271D01*
G03X571893I1114J1919D01*
G01X571926Y1146290D01*
G02X573366Y1146271I703J-1289D01*
G03X575594I1114J1919D01*
G02X576330Y1146468I734J-1270D01*
G01X576332Y1146470D01*
X581335D01*
X581595Y1146210D01*
X581670D01*
G01X567078Y1148190D02*
G03X569103Y1147214I2272J2125D01*
G02X569196Y1147205I-167J-2213D01*
G02X570043Y1146920I-270J-2203D01*
G03X571515I736J1270D01*
G02X573743I1114J-1919D01*
G03X575183Y1146901I737J1270D01*
G01X575216Y1146920D01*
G02X576330Y1147220I1114J-1918D01*
G01X581335D01*
X581595Y1147480D01*
X581670D01*
G01X568929Y1151379D02*
X568502Y1152114D01*
G02X569099Y1152837I533J168D01*
G02X569632Y1152668I-169J-1458D01*
G01X569665Y1152649D01*
G03X571893I1114J1919D01*
G01X571894D01*
G02X573366I736J-1268D01*
G03X575594I1114J1919D01*
G02X575919Y1152815I1665J-2859D01*
G02X576214Y1152878I297J-667D01*
G01X579719Y1152883D01*
X579875D01*
X581480Y1154488D01*
Y1155615D01*
G01X572629Y1151379D02*
G03X574712Y1150397I2450J2497D01*
G02X574864Y1150376I-228J-2207D01*
G02X575594Y1150109I-385J-2185D01*
G03X576208Y1149915I739J1269D01*
G03X576330Y1149910I121J1464D01*
G01X579509D01*
X580940Y1151341D01*
G01X574480Y1033387D02*
X574077Y1034081D01*
G02X574734Y1034833I556J177D01*
G02X575183Y1034676I-253J-1443D01*
G01X575216Y1034657D01*
G03X576144Y1034364I1116J1918D01*
G03X576329Y1034357I176J2212D01*
G01X579411D01*
X580230Y1033538D01*
X581585D01*
G01X574480Y1039765D02*
X574077Y1040459D01*
G02X574734Y1041211I556J177D01*
G02X575183Y1041054I-253J-1443D01*
G01X575216Y1041035D01*
G03X576144Y1040742I1116J1918D01*
G03X576329Y1040735I176J2212D01*
G01X579866D01*
X580500Y1040101D01*
X582332D01*
G01X574480Y1058899D02*
X574077Y1059593D01*
G02X574734Y1060345I556J177D01*
G02X575183Y1060188I-253J-1443D01*
G01X575216Y1060169D01*
G03X576144Y1059876I1116J1918D01*
G03X576329Y1059869I176J2212D01*
G01X578180D01*
X579526Y1058523D01*
X581831D01*
G01X574480Y1052521D02*
X574077Y1053215D01*
G02X574734Y1053967I556J177D01*
G02X575183Y1053810I-253J-1443D01*
G01X575216Y1053791D01*
G03X576144Y1053498I1116J1918D01*
G03X576329Y1053491I176J2212D01*
G01X580139D01*
X580775Y1052855D01*
X581724D01*
G01X574480Y1071655D02*
X574077Y1072349D01*
G02X574734Y1073101I556J177D01*
G02X575183Y1072944I-253J-1443D01*
G01X575216Y1072925D01*
G03X576144Y1072632I1116J1918D01*
G03X576329Y1072625I176J2212D01*
G01X579514D01*
X580772Y1071367D01*
X582013D01*
G01X574480Y1065277D02*
X574077Y1065971D01*
G02X574734Y1066723I556J177D01*
G02X575183Y1066566I-253J-1443D01*
G01X575216Y1066547D01*
G03X576144Y1066254I1116J1918D01*
G03X576329Y1066247I176J2212D01*
G01X578267D01*
X578707Y1065807D01*
X580643D01*
X580903Y1065547D01*
X580978D01*
G01X574480Y1078033D02*
X574077Y1078727D01*
G02X574734Y1079479I556J177D01*
G02X575183Y1079322I-253J-1443D01*
G01X575216Y1079303D01*
G03X576144Y1079010I1116J1918D01*
G03X576329Y1079003I176J2212D01*
G01X579331D01*
X580244Y1078090D01*
X582373D01*
G01X574480Y1084411D02*
X574077Y1085105D01*
G02X574734Y1085857I556J177D01*
G02X575183Y1085700I-253J-1443D01*
G01X575216Y1085681D01*
G03X576144Y1085388I1116J1918D01*
G03X576329Y1085381I176J2212D01*
G01X580243D01*
X580401Y1085539D01*
X582024D01*
X582284Y1085279D01*
X582359D01*
G01X574480Y1090789D02*
X574077Y1091483D01*
G02X574734Y1092235I556J177D01*
G02X575183Y1092078I-253J-1443D01*
G01X575216Y1092059D01*
G03X576144Y1091766I1116J1918D01*
G03X576329Y1091759I176J2212D01*
G01X579611D01*
X580235Y1091135D01*
X582576D01*
G01X574480Y1097167D02*
X574077Y1097861D01*
G02X574734Y1098613I556J177D01*
G02X575183Y1098456I-253J-1443D01*
G01X575216Y1098437D01*
G03X576144Y1098144I1116J1918D01*
G03X576329Y1098137I176J2212D01*
G01X579236D01*
X579884Y1097489D01*
X582272D01*
G01X574480Y1103545D02*
X574077Y1104239D01*
G02X574734Y1104991I556J177D01*
G02X575183Y1104834I-253J-1443D01*
G01X575216Y1104815D01*
G03X576144Y1104522I1116J1918D01*
G03X576329Y1104515I176J2212D01*
G01X579731D01*
X580744Y1103502D01*
X582024D01*
X582284Y1103242D01*
X582359D01*
G01X574480Y1109923D02*
X574077Y1110617D01*
G02X574734Y1111369I556J177D01*
G02X575183Y1111212I-253J-1443D01*
G01X575216Y1111193D01*
G03X576144Y1110900I1116J1918D01*
G03X576329Y1110893I176J2212D01*
G01X580116D01*
X580940Y1111717D01*
X582171D01*
G01X574480Y1116301D02*
X574077Y1116995D01*
G02X574734Y1117747I556J177D01*
G02X575183Y1117590I-253J-1443D01*
G01X575216Y1117571D01*
G03X576144Y1117278I1116J1918D01*
G03X576329Y1117271I176J2212D01*
G01X580563D01*
X580959Y1117667D01*
X581971D01*
G01X574480Y1129057D02*
X574077Y1129751D01*
G02X574734Y1130503I556J177D01*
G02X575183Y1130346I-253J-1443D01*
G01X575216Y1130327D01*
G03X576144Y1130034I1116J1918D01*
G03X576329Y1130027I176J2212D01*
G01X579907D01*
X581092Y1131212D01*
X582249D01*
G01X574480Y1122679D02*
X574077Y1123373D01*
G02X574734Y1124125I556J177D01*
G02X575183Y1123968I-253J-1443D01*
G01X575216Y1123949D01*
G03X576144Y1123656I1116J1918D01*
G03X576329Y1123649I176J2212D01*
G01X580655D01*
X580715Y1123709D01*
X582024D01*
X582284Y1123449D01*
X582359D01*
G01X574480Y1135434D02*
X574077Y1136128D01*
G02X574734Y1136880I556J177D01*
G02X575183Y1136723I-253J-1443D01*
G01X575216Y1136704D01*
G03X576144Y1136411I1116J1918D01*
G03X576329Y1136404I176J2212D01*
G01X579901D01*
X580529Y1137032D01*
X581506D01*
G01X574480Y1148190D02*
X574077Y1148884D01*
G02X574734Y1149636I556J177D01*
G02X575183Y1149479I-253J-1443D01*
G01X575216Y1149460D01*
G03X576144Y1149167I1116J1918D01*
G03X576329Y1149160I176J2212D01*
G01X577215D01*
X577470Y1148905D01*
X580516D01*
X582228Y1150617D01*
G01X574480Y1141812D02*
X574077Y1142506D01*
G02X574734Y1143258I556J177D01*
G02X575183Y1143101I-253J-1443D01*
G01X575216Y1143082D01*
G03X576144Y1142789I1116J1918D01*
G03X576329Y1142782I176J2212D01*
G01X580080D01*
X580807Y1143509D01*
X581536D01*
X581796Y1143249D01*
X581871D01*
G01X1282984Y890237D02*
G02X1281392Y888645I-1592J0D01*
G01X1279923D01*
X1276437Y885159D01*
G01X1288535Y893426D02*
X1288910Y892780D01*
Y892414D01*
G02X1288460Y891960I-454J0D01*
G02X1287832Y892137I74J1466D01*
G01X1287799Y892156D01*
G03X1285571I-1114J-1919D01*
G01X1285538Y892137D01*
G02X1284098Y892156I-703J1289D01*
G03X1281415Y891806I-1114J-1919D01*
G01X1280535Y890925D01*
X1278124D01*
X1276787Y889588D01*
G01X1282984Y902993D02*
X1283361Y902344D01*
G02X1282786Y901538I-500J-252D01*
G02X1282281Y901704I198J1455D01*
G01X1282248Y901723D01*
G03X1280561Y902215I-1687J-2646D01*
G01X1277403D01*
X1276593Y901405D01*
G01X1290386Y896615D02*
G03X1288339Y897593I-2337J-2261D01*
G02X1287421Y897885I198J2210D01*
G03X1285949I-736J-1270D01*
G02X1283721I-1114J1919D01*
G03X1282247I-737J-1270D01*
G03X1281946Y897653I738J-1269D01*
G01X1280880Y896588D01*
X1276738D01*
X1276133Y895983D01*
X1276134Y895615D01*
X1276081Y895562D01*
G01X1288535Y899804D02*
X1288932Y899121D01*
G02X1288357Y898347I-508J-223D01*
G02X1287832Y898515I177J1458D01*
G01X1287799Y898534D01*
G03X1285571I-1114J-1919D01*
G01X1285538Y898515D01*
G02X1284098Y898534I-703J1289D01*
G03X1281415Y898184I-1114J-1919D01*
G01X1280569Y897338D01*
X1276427D01*
X1275602Y896513D01*
X1275234D01*
X1275181Y896460D01*
G01X1282984Y909370D02*
X1283350Y908740D01*
G02X1282831Y907910I-463J-288D01*
G02X1282281Y908081I152J1460D01*
G01X1282248Y908100D01*
G03X1279148Y908935I-3100J-5337D01*
G01X1276531D01*
G01X1288535Y906181D02*
X1288932Y905499D01*
G02X1288357Y904725I-508J-223D01*
G02X1287832Y904893I177J1458D01*
G01X1287799Y904912D01*
G03X1285571I-1114J-1919D01*
G01X1285538Y904893D01*
G02X1284098Y904912I-703J1289D01*
G03X1281870I-1114J-1919D01*
G02X1281256Y904718I-739J1269D01*
G02X1281134Y904713I-121J1464D01*
G01X1275585D01*
X1275577Y904705D01*
G01X1288535Y912559D02*
X1288949Y911847D01*
G02X1288541Y911092I-541J-195D01*
G02X1287832Y911271I-7J1466D01*
G01X1287828Y911273D01*
X1287799Y911290D01*
G03X1285571I-1114J-1919D01*
G01X1285538Y911271D01*
G02X1284098Y911290I-703J1288D01*
G03X1281870I-1114J-1919D01*
G02X1281134Y911090I-740J1268D01*
G01X1277726D01*
X1277011Y911805D01*
G01X1290386Y915748D02*
G03X1288339Y916726I-2337J-2261D01*
G02X1287421Y917018I198J2210D01*
G03X1285949I-736J-1270D01*
G02X1283721I-1114J1919D01*
G03X1282281Y917037I-737J-1270D01*
G01X1282248Y917018D01*
G02X1281320Y916725I-1116J1918D01*
G02X1281135Y916718I-176J2212D01*
G01X1277186D01*
X1276766Y917138D01*
X1275516D01*
X1275256Y916878D01*
X1275181D01*
G01X1288535Y918937D02*
X1288932Y918254D01*
G02X1288357Y917480I-508J-223D01*
G02X1287832Y917648I177J1458D01*
G01X1287799Y917667D01*
G03X1285571I-1114J-1919D01*
G01X1285538Y917648D01*
G02X1284098Y917667I-703J1289D01*
G03X1281870I-1114J-1919D01*
G02X1281256Y917473I-739J1269D01*
G02X1281134Y917468I-121J1464D01*
G01X1277497D01*
X1277077Y917888D01*
X1275516D01*
X1275256Y918148D01*
X1275181D01*
G01X1282984Y922126D02*
X1283350Y921496D01*
G02X1282831Y920666I-463J-288D01*
G02X1282281Y920837I152J1460D01*
G01X1282248Y920856D01*
G03X1279022Y921725I-3226J-5555D01*
G01X1275811D01*
X1275471Y922065D01*
G01X1288535Y925315D02*
Y925314D01*
X1288949Y924602D01*
G02X1288541Y923847I-541J-195D01*
G02X1287832Y924026I-7J1466D01*
G01X1287828Y924028D01*
X1287799Y924045D01*
G03X1285571I-1114J-1919D01*
G01X1285538Y924026D01*
G02X1284098Y924045I-703J1289D01*
G03X1281870I-1114J-1919D01*
G02X1281134Y923846I-738J1269D01*
G01X1277520D01*
X1275841Y925525D01*
X1275601D01*
G01X1282984Y928504D02*
X1283350Y927874D01*
G02X1282831Y927044I-463J-288D01*
G02X1282281Y927215I152J1460D01*
G01X1282248Y927234D01*
G03X1280239Y927775I-2009J-3458D01*
G01X1277181D01*
X1275941Y929015D01*
X1275141D01*
G01X1288535Y931693D02*
Y931692D01*
X1288949Y930980D01*
G02X1288541Y930225I-541J-195D01*
G02X1287832Y930404I-7J1466D01*
G01X1287828Y930406D01*
X1287799Y930423D01*
G03X1285571I-1114J-1919D01*
G01X1285538Y930404D01*
G02X1284098Y930423I-703J1289D01*
G03X1281870I-1114J-1919D01*
G02X1281061Y930205I-809J1391D01*
G01X1277781D01*
X1276151Y931835D01*
X1275101D01*
G01X1282984Y941260D02*
X1283350Y940630D01*
G02X1282831Y939800I-463J-288D01*
G02X1282281Y939971I152J1460D01*
G03X1279679Y940695I-2602J-4313D01*
G01X1277211D01*
X1275681Y942225D01*
X1275231D01*
G01X1290386Y934882D02*
G03X1288339Y935860I-2337J-2261D01*
G02X1287421Y936152I198J2210D01*
G03X1285949I-736J-1270D01*
G02X1283721I-1114J1919D01*
G03X1282281Y936171I-737J-1270D01*
G01X1282248Y936152D01*
G02X1281320Y935859I-1116J1918D01*
G02X1281135Y935852I-176J2212D01*
G01X1277506D01*
X1276757Y936601D01*
X1276607Y936785D01*
X1275638D01*
X1275378Y936525D01*
X1275303D01*
G01X1288535Y938071D02*
X1288932Y937388D01*
G02X1288357Y936614I-508J-223D01*
G02X1287832Y936782I177J1458D01*
G01X1287799Y936801D01*
G03X1285571I-1114J-1919D01*
G01X1285538Y936782D01*
G02X1284098Y936801I-703J1289D01*
G03X1281870I-1114J-1919D01*
G02X1281256Y936607I-739J1269D01*
G02X1281134Y936602I-121J1464D01*
G01X1277817D01*
X1277314Y937105D01*
X1276963Y937535D01*
X1275638D01*
X1275378Y937795D01*
X1275303D01*
G01X1288535Y944449D02*
Y944448D01*
X1288949Y943736D01*
G02X1288541Y942981I-541J-195D01*
G02X1287832Y943160I-7J1466D01*
G01X1287828Y943162D01*
X1287799Y943179D01*
G03X1285571I-1114J-1919D01*
G01X1285538Y943160D01*
G02X1284098Y943179I-703J1289D01*
G03X1281870I-1114J-1919D01*
G02X1281039Y942955I-831J1429D01*
G01X1278068D01*
X1276108Y944915D01*
X1275221D01*
G01X1282984Y947638D02*
X1283350Y947008D01*
G02X1282831Y946178I-463J-288D01*
G02X1282281Y946349I152J1460D01*
G03X1278594Y947375I-3687J-6112D01*
G01X1277061D01*
X1276371Y948065D01*
X1275241D01*
G01X1288535Y950827D02*
Y950826D01*
X1288949Y950114D01*
G02X1288541Y949359I-541J-195D01*
G02X1287832Y949538I-7J1466D01*
G01X1287828Y949540D01*
X1287799Y949557D01*
G03X1285571I-1114J-1919D01*
G01X1285538Y949538D01*
G02X1284098Y949557I-703J1289D01*
G03X1281870I-1114J-1919D01*
G02X1281047Y949335I-823J1416D01*
G01X1277891D01*
X1276438Y950788D01*
G01X1290386Y954016D02*
G03X1288339Y954994I-2337J-2261D01*
G02X1287421Y955286I198J2210D01*
G03X1285949I-736J-1270D01*
G02X1283721I-1114J1919D01*
G03X1282281Y955305I-737J-1270D01*
G01X1282248Y955286D01*
G02X1281320Y954993I-1116J1918D01*
G02X1281135Y954986I-176J2212D01*
G01X1277607D01*
X1276980Y955613D01*
X1276815Y955785D01*
X1275510D01*
X1275250Y955525D01*
X1275175D01*
G01X1288535Y957205D02*
X1288932Y956522D01*
G02X1288357Y955748I-508J-223D01*
G02X1287832Y955916I177J1458D01*
G01X1287799Y955935D01*
G03X1285571I-1114J-1919D01*
G01X1285538Y955916D01*
G02X1284098Y955935I-703J1289D01*
G03X1281870I-1114J-1919D01*
G02X1281256Y955741I-739J1269D01*
G02X1281134Y955736I-121J1464D01*
G01X1277918D01*
X1277516Y956138D01*
X1277136Y956535D01*
X1275510D01*
X1275250Y956795D01*
X1275175D01*
G01X1282984Y960394D02*
X1283350Y959764D01*
G02X1282831Y958934I-463J-288D01*
G02X1282281Y959105I152J1460D01*
G01X1282248Y959124D01*
G03X1281922Y959279I-1113J-1920D01*
G03X1280019Y959791I-3447J-9020D01*
G03X1279719Y959815I-299J-1848D01*
G01X1275301D01*
X1275291Y959805D01*
G01X1288535Y963583D02*
Y963582D01*
X1288949Y962870D01*
G02X1288541Y962115I-541J-195D01*
G02X1287832Y962294I-7J1466D01*
G01X1287828Y962296D01*
X1287799Y962313D01*
G03X1285571I-1114J-1919D01*
G01X1285538Y962294D01*
G02X1284098Y962313I-703J1289D01*
G03X1281870I-1114J-1919D01*
G02X1281061Y962095I-809J1391D01*
G01X1277341D01*
X1276941Y962495D01*
G01X1282984Y966772D02*
X1283350Y966142D01*
G02X1282831Y965312I-463J-288D01*
G02X1282281Y965483I152J1460D01*
G01X1282248Y965502D01*
G03X1281864Y965679I-1117J-1918D01*
G03X1279704Y966045I-2160J-6188D01*
G01X1276491D01*
X1276151Y965705D01*
G01X1288535Y969961D02*
Y969960D01*
X1288949Y969248D01*
G02X1288541Y968493I-541J-195D01*
G02X1287832Y968672I-7J1466D01*
G01X1287828Y968674D01*
X1287799Y968691D01*
G03X1285571I-1114J-1919D01*
G01X1285538Y968672D01*
G02X1284098Y968691I-703J1289D01*
G03X1281870I-1114J-1919D01*
G02X1281069Y968475I-801J1378D01*
G01X1277491D01*
X1277111Y968855D01*
G01X1282984Y979528D02*
X1283371Y978862D01*
G02X1282829Y978068I-484J-251D01*
G02X1282281Y978239I155J1460D01*
G01X1282248Y978258D01*
G03X1281134Y978558I-1114J-1918D01*
G01X1276928D01*
X1275741Y979745D01*
X1275281D01*
G01X1290386Y973150D02*
G03X1288339Y974128I-2337J-2261D01*
G02X1287421Y974420I198J2210D01*
G03X1285949I-736J-1270D01*
G02X1283721I-1114J1919D01*
G03X1282281Y974439I-737J-1270D01*
G01X1282248Y974420D01*
G02X1281320Y974127I-1116J1918D01*
G02X1281135Y974120I-176J2212D01*
G01X1277384D01*
X1276766Y974738D01*
X1275516D01*
X1275256Y974478D01*
X1275181D01*
G01X1288535Y976339D02*
X1288932Y975656D01*
G02X1288357Y974882I-508J-223D01*
G02X1287832Y975050I177J1458D01*
G01X1287799Y975069D01*
G03X1285571I-1114J-1919D01*
G01X1285538Y975050D01*
G02X1284098Y975069I-703J1289D01*
G03X1281870I-1114J-1919D01*
G02X1281256Y974875I-739J1269D01*
G02X1281134Y974870I-121J1464D01*
G01X1277695D01*
X1277077Y975488D01*
X1275516D01*
X1275256Y975748D01*
X1275181D01*
G01X1288535Y982717D02*
Y982716D01*
X1288949Y982004D01*
G02X1288541Y981249I-541J-195D01*
G02X1287832Y981428I-7J1466D01*
G01X1287828Y981430D01*
X1287799Y981447D01*
G03X1285571I-1114J-1919D01*
G01X1285538Y981428D01*
G02X1284098Y981447I-703J1289D01*
G03X1281870I-1114J-1919D01*
G02X1281047Y981225I-823J1416D01*
G01X1277861D01*
X1276571Y982515D01*
G01X1282984Y998662D02*
X1283350Y998032D01*
G02X1282831Y997202I-463J-288D01*
G02X1282281Y997373I152J1460D01*
G01X1282248Y997392D01*
G03X1279493Y998135I-2755J-4736D01*
G01X1275681D01*
X1275316Y998500D01*
G01X1288535Y1001851D02*
Y1001850D01*
X1288949Y1001138D01*
G02X1288541Y1000383I-541J-195D01*
G02X1287832Y1000562I-7J1466D01*
G01X1287828Y1000564D01*
X1287799Y1000581D01*
G03X1285571I-1114J-1919D01*
G01X1285538Y1000562D01*
G02X1284098Y1000581I-703J1289D01*
G03X1281870I-1114J-1919D01*
G02X1281069Y1000365I-801J1378D01*
G01X1277251D01*
X1276366Y1001250D01*
G01X1288535Y995473D02*
Y995472D01*
X1288949Y994760D01*
G02X1288541Y994005I-541J-195D01*
G02X1287832Y994184I-7J1466D01*
G01X1287828Y994186D01*
X1287799Y994203D01*
G03X1285571I-1114J-1919D01*
G01X1285538Y994184D01*
G02X1284098Y994203I-703J1289D01*
G03X1281870I-1114J-1919D01*
G02X1281024Y993975I-846J1454D01*
G01X1278061D01*
G01X1282984Y1011418D02*
X1283350Y1010788D01*
G02X1282831Y1009958I-463J-288D01*
G02X1282281Y1010129I152J1460D01*
G01X1282248Y1010148D01*
G03X1281320Y1010441I-1116J-1918D01*
G01X1281317Y1010445D01*
G03X1280764Y1010467I-553J-6934D01*
G01X1280380D01*
X1280376Y1010463D01*
X1278663Y1012176D01*
Y1012593D01*
X1278610Y1012646D01*
G01X1284835Y1008229D02*
G03X1282797Y1009206I-2310J-2204D01*
G02X1281870Y1009499I189J2211D01*
G03X1281256Y1009693I-739J-1269D01*
G03X1280772Y1009713I-484J-5854D01*
G01X1280065D01*
X1278133Y1011645D01*
X1277715D01*
X1277662Y1011698D01*
G01X1282984Y1005040D02*
X1283371Y1004374D01*
G02X1282829Y1003580I-484J-251D01*
G02X1282281Y1003751I155J1460D01*
G01X1282248Y1003770D01*
G03X1281134Y1004070I-1114J-1918D01*
G01X1277436D01*
X1273795Y1007711D01*
G01X1291567Y1033386D02*
G02X1289771Y1032416I-1746J1085D01*
G03X1288602Y1032116I-54J-2218D01*
G02X1287130I-736J1270D01*
G03X1284902I-1114J-1919D01*
G02X1283462Y1032097I-737J1270D01*
G01X1283429Y1032116D01*
G03X1282501Y1032409I-1116J-1918D01*
G03X1282325Y1032416I-176J-2207D01*
G01X1277510D01*
X1276920Y1033006D01*
X1275741D01*
G01X1286016Y1036575D02*
G02X1283940Y1035594I-2427J2450D01*
G03X1283051Y1035305I226J-2207D01*
G02X1282315Y1035106I-738J1269D01*
G01X1278440D01*
X1277783Y1035763D01*
X1275741D01*
G01X1291567Y1039764D02*
G02X1289771Y1038794I-1746J1085D01*
G03X1288602Y1038494I-54J-2218D01*
G02X1287130I-736J1270D01*
G03X1284902I-1114J-1919D01*
G02X1283462Y1038475I-737J1270D01*
G01X1283429Y1038494D01*
G03X1282501Y1038787I-1116J-1918D01*
G03X1282316Y1038794I-176J-2212D01*
G01X1281942D01*
X1281651Y1039085D01*
X1278341D01*
X1277699Y1038443D01*
X1275741D01*
G01X1286016Y1049331D02*
G02X1284249Y1048360I-1694J989D01*
G03X1283051Y1048061I-83J-2217D01*
G02X1282315Y1047862I-738J1269D01*
G01X1278914D01*
X1278111Y1048665D01*
G01X1286016Y1042953D02*
G02X1283940Y1041972I-2427J2450D01*
G03X1283051Y1041683I226J-2207D01*
G02X1282315Y1041484I-738J1269D01*
G01X1277212D01*
X1277211Y1041485D01*
G01X1286016Y1062087D02*
G02X1283940Y1061106I-2427J2450D01*
G03X1283051Y1060817I226J-2207D01*
G02X1282315Y1060618I-738J1269D01*
G01X1276509D01*
X1275692Y1061435D01*
G01X1291567Y1065276D02*
G02X1289520Y1064298I-2337J2261D01*
G03X1288602Y1064006I198J-2210D01*
G02X1287130I-736J1270D01*
G03X1284902I-1114J-1919D01*
G02X1283462Y1063987I-737J1270D01*
G01X1283429Y1064006D01*
G03X1282501Y1064299I-1116J-1918D01*
G03X1282316Y1064306I-176J-2212D01*
G01X1277542D01*
X1277351Y1064115D01*
X1274910D01*
G01X1289716Y1068465D02*
X1290113Y1069148D01*
G03X1289538Y1069922I-508J223D01*
G03X1289013Y1069754I177J-1458D01*
G01X1288980Y1069735D01*
G02X1286752I-1114J1919D01*
G01X1286719Y1069754D01*
G03X1285279Y1069735I-703J-1289D01*
G02X1283051I-1114J1919D01*
G03X1282437Y1069929I-739J-1269D01*
G03X1282315Y1069934I-121J-1464D01*
G01X1278670D01*
X1277942Y1069206D01*
X1276325D01*
X1276065Y1068946D01*
X1275990D01*
G01X1286016Y1074843D02*
G02X1283940Y1073862I-2427J2450D01*
G03X1283051Y1073573I226J-2207D01*
G02X1282315Y1073374I-738J1269D01*
G01X1278873D01*
X1278684Y1073185D01*
X1275180D01*
G01X1291567Y1071654D02*
G02X1289520Y1070676I-2337J2261D01*
G03X1288602Y1070384I198J-2210D01*
G02X1287130I-736J1270D01*
G03X1284902I-1114J-1919D01*
G02X1283462Y1070365I-737J1270D01*
G01X1283429Y1070384D01*
G03X1282501Y1070677I-1116J-1918D01*
G03X1282316Y1070684I-176J-2212D01*
G01X1278359D01*
X1277631Y1069956D01*
X1276325D01*
X1276065Y1070216D01*
X1275990D01*
G01X1291567Y1078032D02*
G02X1289520Y1077054I-2337J2261D01*
G03X1288602Y1076762I198J-2210D01*
G02X1287130I-736J1270D01*
G03X1284902I-1114J-1919D01*
G02X1283462Y1076743I-737J1270D01*
G01X1283429Y1076762D01*
G03X1282501Y1077055I-1116J-1918D01*
G03X1282316Y1077062I-176J-2212D01*
G01X1278237D01*
X1277410Y1076235D01*
X1275231D01*
G01X1286016Y1081221D02*
G02X1283940Y1080240I-2427J2450D01*
G03X1283051Y1079951I226J-2207D01*
G02X1282315Y1079752I-738J1269D01*
G01X1276461D01*
X1276274Y1079565D01*
X1275201D01*
G01X1291567Y1084410D02*
G02X1289520Y1083432I-2337J2261D01*
G03X1288602Y1083140I198J-2210D01*
G02X1287130I-736J1270D01*
G03X1284902I-1114J-1919D01*
G02X1283462Y1083121I-737J1270D01*
G01X1283429Y1083140D01*
G03X1282501Y1083433I-1116J-1918D01*
G03X1282316Y1083440I-176J-2212D01*
G01X1278064D01*
X1276869Y1082245D01*
G01X1289716Y1087599D02*
X1290113Y1088282D01*
G03X1289538Y1089056I-508J223D01*
G03X1289013Y1088888I177J-1458D01*
G01X1288980Y1088869D01*
G02X1286752I-1114J1919D01*
G01X1286719Y1088888D01*
G03X1285279Y1088869I-703J-1289D01*
G02X1283051I-1114J1919D01*
G03X1282437Y1089063I-739J-1269D01*
G03X1282315Y1089068I-121J-1464D01*
G01X1278901D01*
X1277959Y1088126D01*
X1275516D01*
X1275256Y1087866D01*
X1275181D01*
G01X1291567Y1090788D02*
G02X1289520Y1089810I-2337J2261D01*
G03X1288602Y1089518I198J-2210D01*
G02X1287130I-736J1270D01*
G03X1284902I-1114J-1919D01*
G02X1283462Y1089499I-737J1270D01*
G01X1283429Y1089518D01*
G03X1282501Y1089811I-1116J-1918D01*
G03X1282316Y1089818I-176J-2212D01*
G01X1278590D01*
X1277648Y1088876D01*
X1275441D01*
X1275181Y1089136D01*
G01X1286016Y1100355D02*
G02X1283940Y1099374I-2427J2450D01*
G03X1283051Y1099085I226J-2207D01*
G02X1282315Y1098886I-738J1269D01*
G01X1277586D01*
X1277162Y1099310D01*
X1275221D01*
G01X1286016Y1093977D02*
G02X1283940Y1092996I-2427J2450D01*
G03X1283051Y1092707I226J-2207D01*
G02X1282315Y1092508I-738J1269D01*
G01X1276864D01*
X1276479Y1092123D01*
X1276002D01*
G01X1291567Y1097166D02*
G02X1289520Y1096188I-2337J2261D01*
G03X1288602Y1095896I198J-2210D01*
G02X1287130I-736J1270D01*
G03X1284902I-1114J-1919D01*
G02X1283462Y1095877I-737J1270D01*
G01X1283429Y1095896D01*
G03X1282501Y1096189I-1116J-1918D01*
G03X1282316Y1096196I-176J-2212D01*
G01X1278003D01*
X1277888Y1096081D01*
X1275201D01*
G01X1291567Y1103544D02*
G02X1289520Y1102566I-2337J2261D01*
G03X1288602Y1102274I198J-2210D01*
G02X1287130I-736J1270D01*
G03X1284902I-1114J-1919D01*
G02X1283462Y1102255I-737J1270D01*
G01X1283429Y1102274D01*
G03X1282501Y1102567I-1116J-1918D01*
G03X1282316Y1102574I-176J-2212D01*
G01X1276926D01*
X1276342Y1101990D01*
G01X1289716Y1106733D02*
X1290113Y1107416D01*
G03X1289538Y1108190I-508J223D01*
G03X1289013Y1108022I177J-1458D01*
G01X1288980Y1108003D01*
G02X1286752I-1114J1919D01*
G01X1286719Y1108022D01*
G03X1285279Y1108003I-703J-1289D01*
G02X1283051I-1114J1919D01*
G03X1282437Y1108197I-739J-1269D01*
G03X1282315Y1108202I-121J-1464D01*
G01X1278838D01*
X1277601Y1106965D01*
X1275479D01*
X1275219Y1106705D01*
X1275181D01*
G01X1291567Y1109922D02*
G02X1289520Y1108944I-2337J2261D01*
G03X1288602Y1108652I198J-2210D01*
G02X1287130I-736J1270D01*
G03X1284902I-1114J-1919D01*
G02X1283462Y1108633I-737J1270D01*
G01X1283429Y1108652D01*
G03X1282501Y1108945I-1116J-1918D01*
G03X1282316Y1108952I-176J-2212D01*
G01X1278527D01*
X1277290Y1107715D01*
X1275441D01*
X1275181Y1107975D01*
G01X1286016Y1113111D02*
G02X1283940Y1112130I-2427J2450D01*
G03X1283051Y1111841I226J-2207D01*
G02X1282315Y1111642I-738J1269D01*
G01X1276817D01*
X1276138Y1110963D01*
X1275406D01*
G01X1291567Y1116300D02*
G02X1289520Y1115322I-2337J2261D01*
G03X1288602Y1115030I198J-2210D01*
G02X1287130I-736J1270D01*
G03X1284902I-1114J-1919D01*
G02X1283462Y1115011I-737J1270D01*
G01X1283429Y1115030D01*
G03X1282501Y1115323I-1116J-1918D01*
G03X1282316Y1115330I-176J-2212D01*
G01X1277214D01*
X1277009Y1115535D01*
X1275001D01*
G01X1286016Y1119489D02*
G02X1283940Y1118508I-2427J2450D01*
G03X1283051Y1118219I226J-2207D01*
G02X1282315Y1118020I-738J1269D01*
G01X1277534D01*
X1276844Y1118710D01*
X1275201D01*
G01X1291567Y1122678D02*
G02X1289520Y1121700I-2337J2261D01*
G03X1288602Y1121408I198J-2210D01*
G02X1287130I-736J1270D01*
G03X1284902I-1114J-1919D01*
G02X1283462Y1121389I-737J1270D01*
G01X1283429Y1121408D01*
G03X1282501Y1121701I-1116J-1918D01*
G03X1282316Y1121708I-176J-2212D01*
G01X1275744D01*
X1275426Y1121390D01*
G01X1286016Y1132245D02*
G02X1283940Y1131264I-2427J2450D01*
G03X1283051Y1130975I226J-2207D01*
G02X1282315Y1130776I-738J1269D01*
G01X1275412D01*
X1275201Y1130565D01*
G01X1289716Y1125867D02*
X1290113Y1126550D01*
G03X1289538Y1127324I-508J223D01*
G03X1289013Y1127156I177J-1458D01*
G01X1288980Y1127137D01*
G02X1286752I-1114J1919D01*
G01X1286719Y1127156D01*
G03X1285279Y1127137I-703J-1289D01*
G02X1283051I-1114J1919D01*
G03X1282437Y1127331I-739J-1269D01*
G03X1282315Y1127336I-121J-1464D01*
G01X1278572D01*
X1277440Y1126204D01*
X1275516D01*
X1275256Y1125944D01*
X1275181D01*
G01X1291567Y1129056D02*
G02X1289520Y1128078I-2337J2261D01*
G03X1288602Y1127786I198J-2210D01*
G02X1287130I-736J1270D01*
G03X1284902I-1114J-1919D01*
G02X1283462Y1127767I-737J1270D01*
G01X1283429Y1127786D01*
G03X1282501Y1128079I-1116J-1918D01*
G03X1282316Y1128086I-176J-2212D01*
G01X1278261D01*
X1277129Y1126954D01*
X1275516D01*
X1275256Y1127214D01*
X1275181D01*
G01X1291567Y1135433D02*
G02X1289520Y1134456I-2337J2264D01*
G03X1288602Y1134164I198J-2210D01*
G02X1287130I-736J1270D01*
G03X1284902I-1114J-1919D01*
G02X1283462Y1134145I-737J1270D01*
G01X1283429Y1134164D01*
G03X1282501Y1134457I-1116J-1918D01*
G03X1282316Y1134464I-176J-2212D01*
G01X1278100D01*
X1277401Y1133765D01*
X1275301D01*
G01X1286016Y1138622D02*
G02X1283940Y1137641I-2427J2450D01*
G03X1283051Y1137352I226J-2207D01*
G02X1282315Y1137153I-738J1269D01*
G01X1275489D01*
X1275301Y1136965D01*
G01X1291567Y1141811D02*
G02X1289520Y1140833I-2337J2261D01*
G03X1288602Y1140541I198J-2210D01*
G02X1287130I-736J1270D01*
G03X1284902I-1114J-1919D01*
G02X1283462Y1140522I-737J1270D01*
G01X1283429Y1140541D01*
G03X1282501Y1140834I-1116J-1918D01*
G03X1282316Y1140841I-176J-2212D01*
G01X1276677D01*
X1276001Y1140165D01*
X1275301D01*
G01X1289716Y1145000D02*
X1290113Y1145683D01*
G03X1289538Y1146457I-508J223D01*
G03X1289013Y1146289I177J-1458D01*
G01X1288980Y1146270D01*
G02X1286752I-1114J1919D01*
G01X1286719Y1146289D01*
G03X1285279Y1146270I-703J-1289D01*
G02X1283051I-1114J1919D01*
G03X1282437Y1146464I-739J-1269D01*
G03X1282315Y1146469I-121J-1464D01*
G01X1275923D01*
X1275462Y1146930D01*
X1275094D01*
X1275041Y1146983D01*
G01X1291567Y1148189D02*
G02X1289520Y1147211I-2337J2261D01*
G03X1288602Y1146919I198J-2210D01*
G02X1287130I-736J1270D01*
G03X1284902I-1114J-1919D01*
G02X1283462Y1146900I-737J1270D01*
G01X1283429Y1146919D01*
G03X1282501Y1147212I-1116J-1918D01*
G03X1282316Y1147219I-176J-2212D01*
G01X1276234D01*
X1275994Y1147459D01*
Y1147829D01*
X1275941Y1147882D01*
G01X1286016Y1151378D02*
G02X1283940Y1150397I-2427J2450D01*
G03X1283051Y1150108I226J-2207D01*
G02X1282315Y1149909I-738J1269D01*
G01X1278077D01*
X1275211Y1152775D01*
G01X1284165Y1154567D02*
X1278861D01*
X1278001Y1155427D01*
G01X1284835Y887048D02*
G02X1283040Y885882I-3585J3554D01*
G01X1282328D01*
X1281221Y884775D01*
X1280831D01*
X1279511Y883455D01*
X1278751D01*
X1277777Y882481D01*
G01X1290386Y890237D02*
G03X1288500Y891207I-1886J-1349D01*
G02X1287421Y891507I36J2219D01*
G03X1285949I-736J-1270D01*
G02X1283721I-1114J1919D01*
G03X1281946Y891275I-737J-1270D01*
G01X1280566Y889895D01*
X1279071D01*
X1277844Y888668D01*
G01X1284835Y893426D02*
G03X1282759Y894407I-2427J-2450D01*
G02X1281870Y894696I226J2207D01*
G03X1281134Y894895I-738J-1269D01*
G01X1279361D01*
X1277301Y892835D01*
Y892466D01*
X1277248Y892413D01*
G01X1284835Y899804D02*
G03X1282795Y900782I-2312J-2206D01*
G02X1281870Y901074I189J2211D01*
G03X1280761Y901365I-1109J-1968D01*
G01X1278311D01*
X1277451Y900505D01*
G01X1282984Y896615D02*
X1283371Y895949D01*
G02X1282829Y895155I-484J-251D01*
G02X1282281Y895326I155J1460D01*
G01X1282248Y895345D01*
G03X1281134Y895645I-1114J-1918D01*
G01X1279050D01*
X1276771Y893366D01*
X1276403D01*
X1276350Y893313D01*
G01X1290386Y902993D02*
G03X1288339Y903971I-2337J-2261D01*
G02X1287421Y904263I198J2210D01*
G03X1285949I-736J-1270D01*
G02X1283721I-1114J1919D01*
G03X1282281Y904282I-737J-1270D01*
G01X1282248Y904263D01*
G02X1281320Y903970I-1116J1918D01*
G02X1281135Y903963I-176J2212D01*
G01X1277152D01*
X1276175Y902986D01*
G01X1284835Y906181D02*
G03X1282797Y907158I-2310J-2204D01*
G02X1281870Y907451I189J2211D01*
G03X1281040Y907675I-830J-1426D01*
G01X1277271D01*
X1276751Y907155D01*
G01X1290386Y909370D02*
G03X1288541Y910339I-1845J-1272D01*
G02X1287421Y910640I-4J2219D01*
G03X1285949I-736J-1269D01*
G02X1283721I-1114J1919D01*
G03X1282281Y910659I-737J-1269D01*
G01X1282248Y910640D01*
G02X1281134Y910340I-1114J1918D01*
G01X1276166D01*
G01X1282984Y915748D02*
X1283371Y915082D01*
G02X1282829Y914288I-484J-251D01*
G02X1282281Y914459I155J1460D01*
G01X1282248Y914478D01*
G03X1281134Y914778I-1114J-1918D01*
G01X1276391D01*
X1276131Y915038D01*
X1276056D01*
G01X1284835Y912559D02*
G03X1282759Y913540I-2427J-2450D01*
G02X1281870Y913829I226J2207D01*
G03X1281134Y914028I-738J-1269D01*
G01X1276391D01*
X1276131Y913768D01*
X1276056D01*
G01X1284835Y918937D02*
G03X1282797Y919914I-2310J-2204D01*
G02X1281870Y920207I189J2211D01*
G03X1281025Y920435I-845J-1452D01*
G01X1275211D01*
G01X1290386Y922126D02*
G03X1288541Y923094I-1845J-1274D01*
G02X1287421Y923395I-4J2219D01*
G01Y923396D01*
G03X1285949I-736J-1270D01*
G02X1283721I-1114J1919D01*
G03X1282281Y923415I-737J-1270D01*
G01X1282248Y923396D01*
G02X1281134Y923096I-1114J1918D01*
G01X1276600D01*
X1275861Y923835D01*
X1275171D01*
G01X1284835Y925315D02*
G03X1282797Y926292I-2310J-2204D01*
G02X1281870Y926585I189J2211D01*
G03X1281055Y926805I-815J-1401D01*
G01X1276891D01*
X1276201Y927495D01*
X1275261D01*
G01X1290386Y928504D02*
G03X1288541Y929472I-1845J-1274D01*
G02X1287421Y929773I-4J2219D01*
G01Y929774D01*
G03X1285949I-736J-1270D01*
G02X1283721I-1114J1919D01*
G03X1282281Y929793I-737J-1270D01*
G01X1282248Y929774D01*
G02X1279578Y929055I-2670J4598D01*
G01X1277511D01*
X1276081Y930485D01*
X1275111D01*
G01X1284835Y931693D02*
G03X1282759Y932674I-2427J-2450D01*
G02X1281870Y932963I226J2207D01*
G03X1281134Y933162I-738J-1269D01*
G01X1277322D01*
X1276749Y933735D01*
X1276276D01*
X1276016Y933475D01*
X1275941D01*
G01X1284835Y938071D02*
G03X1282797Y939048I-2310J-2204D01*
G02X1281870Y939341I189J2211D01*
G03X1281000Y939575I-870J-1500D01*
G01X1276311D01*
X1275081Y940805D01*
G01X1290386Y941260D02*
G03X1288541Y942228I-1845J-1274D01*
G02X1287421Y942529I-4J2219D01*
G01Y942530D01*
G03X1285949I-736J-1270D01*
G02X1283721I-1114J1919D01*
G03X1282281Y942549I-737J-1270D01*
G01X1282248Y942530D01*
G02X1279704Y941845I-2544J4380D01*
G01X1277781D01*
X1276061Y943565D01*
X1275261D01*
G01X1282984Y934882D02*
X1283371Y934216D01*
G02X1282829Y933422I-484J-251D01*
G02X1282281Y933593I155J1460D01*
G01X1282248Y933612D01*
G03X1281134Y933912I-1114J-1918D01*
G01X1277633D01*
X1277060Y934485D01*
X1276276D01*
X1276016Y934745D01*
X1275941D01*
G01X1284835Y944449D02*
G03X1282797Y945426I-2310J-2204D01*
G02X1281870Y945719I189J2211D01*
G03X1280324Y946135I-1546J-2666D01*
G01X1276921D01*
X1276341Y946715D01*
X1275241D01*
G01X1290386Y947638D02*
G03X1288541Y948606I-1845J-1274D01*
G02X1287421Y948907I-4J2219D01*
G01Y948908D01*
G03X1285949I-736J-1270D01*
G02X1283721I-1114J1919D01*
G03X1282281Y948927I-737J-1270D01*
G01X1282248Y948908D01*
G02X1281011Y948575I-1237J2129D01*
G01X1277241D01*
X1276371Y949445D01*
X1275221D01*
G01X1284835Y957205D02*
G03X1282797Y958182I-2310J-2204D01*
G02X1281870Y958475I189J2211D01*
G03X1281256Y958669I-739J-1269D01*
G03X1280869Y958685I-387J-4683D01*
G01X1276201D01*
X1275981Y958465D01*
G01X1282984Y954016D02*
X1283371Y953350D01*
G02X1282829Y952556I-484J-251D01*
G02X1282281Y952727I155J1460D01*
G01X1282248Y952746D01*
G03X1281134Y953046I-1114J-1918D01*
G01X1278141D01*
X1277641Y953546D01*
X1275516D01*
X1275256Y953806D01*
X1275181D01*
G01X1284835Y950827D02*
G03X1282759Y951808I-2427J-2450D01*
G02X1281870Y952097I226J2207D01*
G03X1281134Y952296I-738J-1269D01*
G01X1277830D01*
X1277330Y952796D01*
X1275516D01*
X1275256Y952536D01*
X1275181D01*
G01X1284835Y963583D02*
G03X1282797Y964560I-2310J-2204D01*
G02X1281870Y964853I189J2211D01*
G03X1281256Y965047I-739J-1269D01*
G03X1280820Y965065I-436J-5268D01*
G01X1277621D01*
X1276921Y964365D01*
G01X1290386Y960394D02*
G03X1288541Y961362I-1845J-1274D01*
G02X1287421Y961663I-4J2219D01*
G01Y961664D01*
G03X1285949I-736J-1270D01*
G02X1283721I-1114J1919D01*
G03X1282281Y961683I-737J-1270D01*
G01X1282248Y961664D01*
G02X1279875Y961025I-2373J4086D01*
G01X1277021D01*
X1276901Y961145D01*
X1275241D01*
G01X1290386Y966772D02*
G03X1288541Y967740I-1845J-1274D01*
G02X1287421Y968041I-4J2219D01*
G01Y968042D01*
G03X1285949I-736J-1270D01*
G02X1283721I-1114J1919D01*
G03X1282281Y968061I-737J-1270D01*
G01X1282248Y968042D01*
G02X1279957Y967425I-2291J3945D01*
G01X1275461D01*
X1275341Y967305D01*
G01X1282984Y973150D02*
X1283371Y972484D01*
G02X1282829Y971690I-484J-251D01*
G02X1282281Y971861I155J1460D01*
G01X1282248Y971880D01*
G03X1281134Y972180I-1114J-1918D01*
G01X1277381D01*
X1277121Y972440D01*
X1277046D01*
G01X1284835Y969961D02*
G03X1282759Y970942I-2427J-2450D01*
G02X1281870Y971231I226J2207D01*
G03X1281134Y971430I-738J-1269D01*
G01X1277381D01*
X1277121Y971170D01*
X1277046D01*
G01X1284835Y976339D02*
G03X1282759Y977320I-2427J-2450D01*
G02X1281870Y977609I226J2207D01*
G03X1281134Y977808I-738J-1269D01*
G01X1276616D01*
X1276243Y977435D01*
G01X1290386Y979528D02*
G03X1288541Y980496I-1845J-1274D01*
G02X1287421Y980797I-4J2219D01*
G01Y980798D01*
G03X1285949I-736J-1270D01*
G02X1283721I-1114J1919D01*
G03X1282281Y980817I-737J-1270D01*
G01X1282248Y980798D01*
G02X1279489Y980055I-2759J4751D01*
G01X1277121D01*
X1276061Y981115D01*
G01X1284835Y982717D02*
G03X1282797Y983694I-2310J-2204D01*
G02X1282351Y983778I186J2211D01*
G02X1282075Y983898I368J1224D01*
G01X1281097Y984465D01*
G03X1278491Y985165I-2605J-4498D01*
G01X1282984Y992284D02*
X1283350Y991654D01*
G02X1282831Y990824I-463J-288D01*
G02X1282281Y990995I152J1460D01*
G01X1282248Y991014D01*
G03X1280057Y991605I-2191J-3767D01*
G01X1276571D01*
G01X1284835Y995473D02*
G03X1282797Y996450I-2310J-2204D01*
G02X1281870Y996743I189J2211D01*
G03X1281047Y996965I-823J-1414D01*
G01X1274811D01*
G01X1290386Y998662D02*
G03X1288541Y999630I-1845J-1274D01*
G02X1287421Y999931I-4J2219D01*
G01Y999932D01*
G03X1285949I-736J-1270D01*
G02X1283721I-1114J1919D01*
G03X1282281Y999951I-737J-1270D01*
G01X1282248Y999932D01*
G02X1279957Y999315I-2291J3945D01*
G01X1276401D01*
X1275446Y1000270D01*
G01X1284835Y1001851D02*
G03X1282759Y1002832I-2427J-2450D01*
G02X1281870Y1003121I226J2207D01*
G03X1281134Y1003320I-738J-1269D01*
G01X1276206D01*
X1276153Y1003373D01*
G01X1290386Y1005040D02*
G03X1288541Y1006008I-1845J-1274D01*
G02X1287421Y1006309I-4J2219D01*
G01Y1006310D01*
G03X1285949I-736J-1270D01*
G02X1283721I-1114J1919D01*
G03X1282281Y1006329I-737J-1270D01*
G01X1282248Y1006310D01*
G02X1280669Y1005739I-2361J4059D01*
G02X1280369Y1005715I-293J1780D01*
G01X1277761D01*
X1275671Y1007805D01*
G01X1288535Y1008229D02*
Y1008228D01*
X1288949Y1007516D01*
G02X1288541Y1006761I-541J-195D01*
G02X1287832Y1006940I-7J1466D01*
G01X1287828Y1006942D01*
X1287799Y1006959D01*
G03X1285571I-1114J-1919D01*
G01X1285538Y1006940D01*
G02X1284098Y1006959I-703J1289D01*
G03X1281870I-1114J-1919D01*
G02X1281039Y1006735I-831J1429D01*
G01X1278051D01*
X1277155Y1007631D01*
Y1008771D01*
G01X1289716Y1030197D02*
X1290143Y1030932D01*
G03X1289546Y1031655I-533J168D01*
G03X1289013Y1031486I169J-1458D01*
G01X1288980Y1031467D01*
G02X1286752I-1114J1919D01*
G01X1286719Y1031486D01*
G03X1285279Y1031467I-703J-1289D01*
G02X1283051I-1114J1919D01*
G03X1282315Y1031666I-738J-1269D01*
G01X1275741D01*
G01X1284165Y1033386D02*
X1284552Y1034052D01*
G03X1284010Y1034846I-484J251D01*
G03X1283462Y1034675I155J-1460D01*
G01X1283429Y1034656D01*
G02X1282315Y1034356I-1114J1918D01*
G01X1280718D01*
X1280708Y1034346D01*
X1275741D01*
G01X1289716Y1036575D02*
X1290143Y1037310D01*
G03X1289546Y1038033I-533J168D01*
G03X1289013Y1037864I169J-1458D01*
G01X1288980Y1037845D01*
G02X1286752I-1114J1919D01*
G01X1286719Y1037864D01*
G03X1285279Y1037845I-703J-1289D01*
G02X1283051I-1114J1919D01*
G03X1282315Y1038044I-738J-1269D01*
G01X1278960D01*
X1278019Y1037103D01*
X1275741D01*
G01X1284165Y1039764D02*
X1284552Y1040430D01*
G03X1284010Y1041224I-484J251D01*
G03X1283462Y1041053I155J-1460D01*
G01X1283429Y1041034D01*
G02X1282315Y1040734I-1114J1918D01*
G01X1278290D01*
X1277339Y1039783D01*
X1275971D01*
G01X1291567Y1046142D02*
G02X1289771Y1045172I-1746J1085D01*
G03X1288602Y1044872I-54J-2218D01*
G02X1287130I-736J1270D01*
G03X1284902I-1114J-1919D01*
G02X1283462Y1044853I-737J1270D01*
G01X1283429Y1044872D01*
G03X1282501Y1045165I-1116J-1918D01*
G03X1279812Y1045272I-2689J-33731D01*
G01X1277644D01*
G01X1289716Y1049331D02*
X1290143Y1050066D01*
G03X1289546Y1050789I-533J168D01*
G03X1289013Y1050620I169J-1458D01*
G01X1288980Y1050601D01*
G02X1286752I-1114J1919D01*
G01X1286719Y1050620D01*
G03X1285279Y1050601I-703J-1289D01*
G02X1283051I-1114J1919D01*
G03X1282315Y1050800I-738J-1269D01*
G01X1279031D01*
X1278236Y1050005D01*
G01X1284165Y1058898D02*
X1284552Y1059564D01*
G03X1284010Y1060358I-484J251D01*
G03X1283462Y1060187I155J-1460D01*
G01X1283429Y1060168D01*
G02X1282315Y1059868I-1114J1918D01*
G01X1275298D01*
X1275071Y1060095D01*
G01X1284165Y1052520D02*
X1284552Y1053186D01*
G03X1284010Y1053980I-484J251D01*
G03X1283462Y1053809I155J-1460D01*
G01X1283429Y1053790D01*
G02X1282315Y1053490I-1114J1918D01*
G01X1277526D01*
X1277271Y1053235D01*
G01X1289716Y1062087D02*
X1290113Y1062770D01*
G03X1289538Y1063544I-508J223D01*
G03X1289013Y1063376I177J-1458D01*
G01X1288980Y1063357D01*
G02X1286752I-1114J1919D01*
G01X1286719Y1063376D01*
G03X1285279Y1063357I-703J-1289D01*
G02X1283051I-1114J1919D01*
G03X1282437Y1063551I-739J-1269D01*
G03X1282315Y1063556I-121J-1464D01*
G01X1277892D01*
X1277111Y1062775D01*
X1275111D01*
G01X1286016Y1068465D02*
G02X1283940Y1067484I-2427J2450D01*
G03X1283051Y1067195I226J-2207D01*
G02X1282315Y1066996I-738J1269D01*
G01X1277184D01*
X1276924Y1067256D01*
X1276849D01*
G01X1284165Y1065276D02*
X1284552Y1065942D01*
G03X1284010Y1066736I-484J251D01*
G03X1283462Y1066565I155J-1460D01*
G01X1283429Y1066546D01*
G02X1282315Y1066246I-1114J1918D01*
G01X1277184D01*
X1276924Y1065986D01*
X1276849D01*
G01X1284165Y1071654D02*
X1284552Y1072320D01*
G03X1284010Y1073114I-484J251D01*
G03X1283462Y1072943I155J-1460D01*
G01X1283429Y1072924D01*
G02X1282315Y1072624I-1114J1918D01*
G01X1280253D01*
X1279474Y1071845D01*
X1275280D01*
G01X1289716Y1074843D02*
X1290113Y1075526D01*
G03X1289538Y1076300I-508J223D01*
G03X1289013Y1076132I177J-1458D01*
G01X1288980Y1076113D01*
G02X1286752I-1114J1919D01*
G01X1286719Y1076132D01*
G03X1285279Y1076113I-703J-1289D01*
G02X1283051I-1114J1919D01*
G03X1282437Y1076307I-739J-1269D01*
G03X1282315Y1076312I-121J-1464D01*
G01X1278548D01*
X1276761Y1074525D01*
X1275201D01*
G01X1284165Y1078032D02*
X1284552Y1078698D01*
G03X1284010Y1079492I-484J251D01*
G03X1283462Y1079321I155J-1460D01*
G01X1283429Y1079302D01*
G02X1282315Y1079002I-1114J1918D01*
G01X1276868D01*
X1275931Y1078065D01*
G01X1289716Y1081221D02*
X1290113Y1081904D01*
G03X1289538Y1082678I-508J223D01*
G03X1289013Y1082510I177J-1458D01*
G01X1288980Y1082491D01*
G02X1286752I-1114J1919D01*
G01X1286719Y1082510D01*
G03X1285279Y1082491I-703J-1289D01*
G02X1283051I-1114J1919D01*
G03X1282437Y1082685I-739J-1269D01*
G03X1282315Y1082690I-121J-1464D01*
G01X1279150D01*
X1277365Y1080905D01*
X1275201D01*
G01X1284165Y1090788D02*
X1284552Y1091454D01*
G03X1284010Y1092248I-484J251D01*
G03X1283462Y1092077I155J-1460D01*
G01X1283429Y1092058D01*
G02X1282315Y1091758I-1114J1918D01*
G01X1278756D01*
X1277752Y1090754D01*
X1277333D01*
G01X1286016Y1087599D02*
G02X1283940Y1086618I-2427J2450D01*
G03X1283051Y1086329I226J-2207D01*
G02X1282315Y1086130I-738J1269D01*
G01X1278208D01*
X1276951Y1084873D01*
X1276042D01*
X1275782Y1085133D01*
X1275707D01*
G01X1284165Y1084410D02*
X1284552Y1085076D01*
G03X1284010Y1085870I-484J251D01*
G03X1283462Y1085699I155J-1460D01*
G01X1283429Y1085680D01*
G02X1282315Y1085380I-1114J1918D01*
G01X1278519D01*
X1277262Y1084123D01*
X1276042D01*
X1275782Y1083863D01*
X1275707D01*
G01X1289716Y1093977D02*
X1290113Y1094660D01*
G03X1289538Y1095434I-508J223D01*
G03X1289013Y1095266I177J-1458D01*
G01X1288980Y1095247D01*
G02X1286752I-1114J1919D01*
G01X1286719Y1095266D01*
G03X1285279Y1095247I-703J-1289D01*
G02X1283051I-1114J1919D01*
G03X1282437Y1095441I-739J-1269D01*
G03X1282315Y1095446I-121J-1464D01*
G01X1278872D01*
X1276949Y1093523D01*
X1275359D01*
G01X1284165Y1097166D02*
X1284552Y1097832D01*
G03X1284010Y1098626I-484J251D01*
G03X1283462Y1098455I155J-1460D01*
G01X1283429Y1098436D01*
G02X1282315Y1098136I-1114J1918D01*
G01X1280718D01*
X1280463Y1097881D01*
X1275112D01*
G01X1289716Y1100355D02*
X1290113Y1101038D01*
G03X1289538Y1101812I-508J223D01*
G03X1289013Y1101644I177J-1458D01*
G01X1288980Y1101625D01*
G02X1286752I-1114J1919D01*
G01X1286719Y1101644D01*
G03X1285279Y1101625I-703J-1289D01*
G02X1283051I-1114J1919D01*
G03X1282437Y1101819I-739J-1269D01*
G03X1282315Y1101824I-121J-1464D01*
G01X1278217D01*
X1277043Y1100650D01*
X1275201D01*
G01X1286016Y1106733D02*
G02X1283940Y1105752I-2427J2450D01*
G03X1283051Y1105463I226J-2207D01*
G02X1282315Y1105264I-738J1269D01*
G01X1280407D01*
X1279833Y1104690D01*
X1276197D01*
X1275441Y1104615D01*
X1275181Y1104875D01*
G01X1284165Y1103544D02*
X1284552Y1104210D01*
G03X1284010Y1105004I-484J251D01*
G03X1283462Y1104833I155J-1460D01*
G01X1283429Y1104814D01*
G02X1282315Y1104514I-1114J1918D01*
G01X1280718D01*
X1280144Y1103940D01*
X1276236D01*
X1275516Y1103865D01*
X1275256Y1103605D01*
X1275181D01*
G01X1284165Y1109922D02*
X1284552Y1110588D01*
G03X1284010Y1111382I-484J251D01*
G03X1283462Y1111211I155J-1460D01*
G01X1283429Y1111192D01*
G02X1282315Y1110892I-1114J1918D01*
G01X1277731D01*
X1276433Y1109594D01*
X1275234D01*
G01X1289716Y1113111D02*
X1290113Y1113794D01*
G03X1289538Y1114568I-508J223D01*
G03X1289013Y1114400I177J-1458D01*
G01X1288980Y1114381D01*
G02X1286752I-1114J1919D01*
G01X1286719Y1114400D01*
G03X1285279Y1114381I-703J-1289D01*
G02X1283051I-1114J1919D01*
G03X1282437Y1114575I-739J-1269D01*
G03X1282315Y1114580I-121J-1464D01*
G01X1278416D01*
X1278031Y1114195D01*
X1275201D01*
G01X1284165Y1116300D02*
X1284552Y1116966D01*
G03X1284010Y1117760I-484J251D01*
G03X1283462Y1117589I155J-1460D01*
G01X1283429Y1117570D01*
G02X1282315Y1117270I-1114J1918D01*
G01X1276396D01*
X1276296Y1117370D01*
G01X1289716Y1119489D02*
X1290113Y1120172D01*
G03X1289538Y1120946I-508J223D01*
G03X1289013Y1120778I177J-1458D01*
G01X1288980Y1120759D01*
G02X1286752I-1114J1919D01*
G01X1286719Y1120778D01*
G03X1285279Y1120759I-703J-1289D01*
G02X1283051I-1114J1919D01*
G03X1282437Y1120953I-739J-1269D01*
G03X1282315Y1120958I-121J-1464D01*
G01X1278594D01*
X1277686Y1120050D01*
X1275201D01*
G01X1284165Y1129056D02*
X1284552Y1129722D01*
G03X1284010Y1130516I-484J251D01*
G03X1283462Y1130345I155J-1460D01*
G01X1283429Y1130326D01*
G02X1282315Y1130026I-1114J1918D01*
G01X1276702D01*
X1275741Y1129065D01*
G01X1286016Y1125867D02*
G02X1283940Y1124886I-2427J2450D01*
G03X1283051Y1124597I226J-2207D01*
G02X1282315Y1124398I-738J1269D01*
G01X1280407D01*
X1280024Y1124015D01*
X1275516D01*
X1275256Y1124275D01*
X1275181D01*
G01X1284165Y1122678D02*
X1284552Y1123344D01*
G03X1284010Y1124138I-484J251D01*
G03X1283462Y1123967I155J-1460D01*
G01X1283429Y1123948D01*
G02X1282315Y1123648I-1114J1918D01*
G01X1280718D01*
X1280335Y1123265D01*
X1275516D01*
X1275256Y1123005D01*
X1275181D01*
G01X1289716Y1132245D02*
X1290113Y1132928D01*
G03X1289538Y1133702I-508J223D01*
G03X1289013Y1133534I177J-1458D01*
G01X1288980Y1133515D01*
G02X1286752I-1114J1919D01*
G01X1286719Y1133534D01*
G03X1285279Y1133515I-703J-1289D01*
G02X1283051I-1114J1919D01*
G03X1282437Y1133709I-739J-1269D01*
G03X1282315Y1133714I-121J-1464D01*
G01X1278649D01*
X1277201Y1132266D01*
X1275201D01*
G01X1284165Y1135433D02*
X1284552Y1136099D01*
G03X1284010Y1136893I-484J251D01*
G03X1283462Y1136722I155J-1460D01*
G01X1283429Y1136703D01*
G02X1282315Y1136403I-1114J1918D01*
G01X1276139D01*
X1275301Y1135565D01*
G01X1289716Y1138622D02*
X1290113Y1139305D01*
G03X1289538Y1140079I-508J223D01*
G03X1289013Y1139911I177J-1458D01*
G01X1288980Y1139892D01*
G02X1286752I-1114J1919D01*
G01X1286719Y1139911D01*
G03X1285279Y1139892I-703J-1289D01*
G02X1283051I-1114J1919D01*
G03X1282437Y1140086I-739J-1269D01*
G03X1282315Y1140091I-121J-1464D01*
G01X1279027D01*
X1277701Y1138765D01*
X1275201D01*
G01X1286016Y1145000D02*
G02X1283940Y1144019I-2427J2450D01*
G03X1283051Y1143730I226J-2207D01*
G02X1282315Y1143531I-738J1269D01*
G01X1280407D01*
X1280255Y1143379D01*
X1275516D01*
X1275256Y1143639D01*
X1275181D01*
G01X1284165Y1141811D02*
X1284552Y1142477D01*
G03X1284010Y1143271I-484J251D01*
G03X1283462Y1143100I155J-1460D01*
G01X1283429Y1143081D01*
G02X1282315Y1142781I-1114J1918D01*
G01X1280718D01*
X1280566Y1142629D01*
X1275516D01*
X1275256Y1142369D01*
X1275181D01*
G01X1284165Y1148189D02*
X1284552Y1148855D01*
G03X1284010Y1149649I-484J251D01*
G03X1283462Y1149478I155J-1460D01*
G01X1283429Y1149459D01*
G02X1282315Y1149159I-1114J1918D01*
G01X1277325D01*
X1275454Y1151030D01*
G01X1289716Y1151378D02*
X1289706Y1151382D01*
X1287815Y1152655D01*
G03X1286800Y1152965I-1015J-1508D01*
G01X1277461D01*
X1276551Y1153875D01*
G01X1542039Y890237D02*
G02X1543925Y891207I1886J-1349D01*
G03X1545004Y891507I-36J2219D01*
G02X1546476I736J-1270D01*
G03X1548704I1114J1919D01*
G02X1550144Y891526I737J-1270D01*
G02X1550479Y891275I-704J-1288D01*
G01X1551739Y890015D01*
X1552469D01*
X1556017Y886467D01*
Y885367D01*
G01X1542039Y902993D02*
G02X1544064Y903969I2272J-2125D01*
G03X1544157Y903978I-167J2213D01*
G03X1545004Y904263I-270J2203D01*
G02X1546476I736J-1270D01*
G03X1548704I1114J1919D01*
G02X1550144Y904282I737J-1270D01*
G01X1550177Y904263D01*
G03X1551291Y903963I1114J1918D01*
G01X1555161D01*
X1557267Y901857D01*
Y901255D01*
X1558567Y899955D01*
G01X1542039Y909370D02*
G02X1543884Y910339I1845J-1272D01*
G03X1545004Y910640I4J2219D01*
G02X1546476I736J-1269D01*
G03X1548704I1114J1919D01*
G02X1550144Y910659I737J-1269D01*
G01X1550177Y910640D01*
G03X1552932Y909898I2755J4745D01*
G01X1555231D01*
X1555544Y909585D01*
X1557248D01*
G01X1542039Y896615D02*
G02X1544064Y897591I2272J-2125D01*
G03X1544157Y897600I-167J2213D01*
G03X1545004Y897885I-270J2203D01*
G02X1546476I736J-1270D01*
G03X1548704I1114J1919D01*
G02X1550178I737J-1270D01*
G02X1550479Y897653I-738J-1269D01*
G01X1551655Y896478D01*
X1554383D01*
Y896476D01*
X1556053Y894806D01*
X1556052Y894440D01*
X1556105Y894387D01*
G01X1542039Y922126D02*
G02X1543884Y923094I1845J-1274D01*
G03X1545004Y923395I4J2219D01*
G01Y923396D01*
G02X1546476I736J-1270D01*
G03X1548704I1114J1919D01*
G02X1550144Y923415I737J-1270D01*
G01X1550177Y923396D01*
G03X1551291Y923096I1114J1918D01*
G01X1555724D01*
X1556506Y923878D01*
X1557867D01*
G01X1542039Y915748D02*
G02X1544064Y916724I2272J-2125D01*
G03X1544157Y916733I-167J2213D01*
G03X1545004Y917018I-270J2203D01*
G02X1546476I736J-1270D01*
G03X1548704I1114J1919D01*
G02X1550144Y917037I737J-1270D01*
G01X1550177Y917018D01*
G03X1551291Y916718I1114J1918D01*
G01X1555814D01*
X1556074Y916458D01*
X1556149D01*
G01X1542039Y928504D02*
G02X1543884Y929472I1845J-1274D01*
G03X1545004Y929773I4J2219D01*
G01Y929774D01*
G02X1546476I736J-1270D01*
G03X1548704I1114J1919D01*
G02X1550144Y929793I737J-1270D01*
G01X1550177Y929774D01*
G03X1552847Y929055I2670J4598D01*
G01X1554744D01*
X1555694Y930005D01*
X1557934D01*
G01X1542039Y934882D02*
G02X1544064Y935858I2272J-2125D01*
G03X1544157Y935867I-167J2213D01*
G03X1545004Y936152I-270J2203D01*
G02X1546476I736J-1270D01*
G03X1548704I1114J1919D01*
G02X1550144Y936171I737J-1270D01*
G01X1550177Y936152D01*
G03X1551291Y935852I1114J1918D01*
G01X1554778D01*
X1555531Y936605D01*
X1556717D01*
X1556977Y936345D01*
X1557052D01*
G01X1542039Y941260D02*
G02X1543884Y942228I1845J-1274D01*
G03X1545004Y942529I4J2219D01*
G01Y942530D01*
G02X1546476I736J-1270D01*
G03X1548704I1114J1919D01*
G02X1550144Y942549I737J-1270D01*
G01X1550177Y942530D01*
G03X1552721Y941845I2544J4380D01*
G01X1554331D01*
X1556061Y943575D01*
X1557067D01*
G01X1542039Y947638D02*
G02X1543884Y948606I1845J-1274D01*
G03X1545004Y948907I4J2219D01*
G01Y948908D01*
G02X1546476I736J-1270D01*
G03X1548704I1114J1919D01*
G02X1550144Y948927I737J-1270D01*
G01X1550177Y948908D01*
G03X1551414Y948575I1237J2129D01*
G01X1555184D01*
X1555196Y948587D01*
X1557276Y949448D01*
X1558087D01*
G01X1542039Y954016D02*
G02X1544064Y954992I2272J-2125D01*
G03X1544157Y955001I-167J2213D01*
G03X1545004Y955286I-270J2203D01*
G02X1546476I736J-1270D01*
G03X1548704I1114J1919D01*
G02X1550144Y955305I737J-1270D01*
G01X1550177Y955286D01*
G03X1551291Y954986I1114J1918D01*
G01X1554744D01*
X1556143Y956385D01*
X1557205D01*
X1557465Y956125D01*
X1557540D01*
G01X1542039Y966772D02*
G02X1543884Y967740I1845J-1274D01*
G03X1545004Y968041I4J2219D01*
G01Y968042D01*
G02X1546476I736J-1270D01*
G03X1548704I1114J1919D01*
G02X1550144Y968061I737J-1270D01*
G01X1550177Y968042D01*
G03X1552468Y967425I2291J3945D01*
G01X1555924D01*
X1556167Y967668D01*
X1557880D01*
G01X1542039Y960394D02*
G02X1543884Y961362I1845J-1274D01*
G03X1545004Y961663I4J2219D01*
G01Y961664D01*
G02X1546476I736J-1270D01*
G03X1548704I1114J1919D01*
G02X1550144Y961683I737J-1270D01*
G01X1550177Y961664D01*
G03X1552550Y961025I2373J4086D01*
G01X1555434D01*
X1556167Y961758D01*
X1557857D01*
G01X1542039Y979528D02*
G02X1543884Y980496I1845J-1274D01*
G03X1545004Y980797I4J2219D01*
G01Y980798D01*
G02X1546476I736J-1270D01*
G03X1548704I1114J1919D01*
G02X1550144Y980817I737J-1270D01*
G01X1550177Y980798D01*
G03X1552936Y980055I2759J4751D01*
G01X1555304D01*
X1556811Y981562D01*
G01X1542039Y973150D02*
G02X1544064Y974126I2272J-2125D01*
G03X1544157Y974135I-167J2213D01*
G03X1545004Y974420I-270J2203D01*
G02X1546476I736J-1270D01*
G03X1548704I1114J1919D01*
G02X1550144Y974439I737J-1270D01*
G01X1550177Y974420D01*
G03X1551291Y974120I1114J1918D01*
G01X1553107D01*
X1553267Y973960D01*
X1556184D01*
X1556444Y973700D01*
X1556519D01*
G01X1542039Y998662D02*
G02X1543884Y999630I1845J-1274D01*
G03X1545004Y999931I4J2219D01*
G01Y999932D01*
G02X1546476I736J-1270D01*
G03X1548704I1114J1919D01*
G02X1550144Y999951I737J-1270D01*
G01X1550177Y999932D01*
G03X1552468Y999315I2291J3945D01*
G01X1557407D01*
X1557567Y999475D01*
G01X1542039Y992284D02*
G02X1543884Y993252I1845J-1274D01*
G03X1545004Y993553I4J2219D01*
G01Y993554D01*
G02X1546476I736J-1270D01*
G03X1548704I1114J1919D01*
G02X1550144Y993573I737J-1270D01*
G01X1550177Y993554D01*
G03X1552958Y992805I2781J4789D01*
G01X1554734D01*
G01X1542039Y1005040D02*
G02X1543884Y1006008I1845J-1274D01*
G03X1545004Y1006309I4J2219D01*
G01Y1006310D01*
G02X1546476I736J-1270D01*
G03X1548704I1114J1919D01*
G02X1550144Y1006329I737J-1270D01*
G01X1550177Y1006310D01*
G03X1551756Y1005739I2361J4059D01*
G03X1552056Y1005715I293J1780D01*
G01X1555704D01*
X1556042Y1006053D01*
X1557457D01*
G01X1547590Y887048D02*
G03X1551174Y885555I3584J3555D01*
G01X1553241Y883488D01*
G01X1549441Y890237D02*
G03X1551144Y888534I1703J0D01*
G01X1552612D01*
X1554711Y886435D01*
Y884689D01*
X1555033Y884367D01*
G01X1543890Y893426D02*
X1543515Y892780D01*
Y892414D01*
G03X1543965Y891960I454J0D01*
G03X1544593Y892137I-74J1466D01*
G01X1544626Y892156D01*
G02X1546854I1114J-1919D01*
G01X1546887Y892137D01*
G03X1548327Y892156I703J1289D01*
G02X1551010Y891806I1114J-1919D01*
G01X1551981Y890835D01*
X1552841D01*
X1557267Y886409D01*
G01X1549441Y896615D02*
X1549038Y895921D01*
G03X1549695Y895169I556J-177D01*
G03X1550144Y895326I-253J1443D01*
G01X1550177Y895345D01*
G02X1551105Y895638I1116J-1918D01*
G02X1551290Y895645I176J-2212D01*
G01X1552165D01*
X1553429Y895121D01*
X1555477Y893073D01*
Y891928D01*
X1557148Y890257D01*
X1557516D01*
X1557569Y890204D01*
G01X1547590Y893426D02*
G02X1549673Y894408I2450J-2497D01*
G03X1549825Y894429I-228J2207D01*
G03X1550555Y894696I-385J2185D01*
G02X1551169Y894890I739J-1269D01*
G02X1551291Y894895I121J-1464D01*
G01X1552015D01*
X1553004Y894485D01*
X1554727Y892762D01*
Y891617D01*
X1556618Y889726D01*
X1556617Y889358D01*
X1556670Y889305D01*
G01X1543890Y899804D02*
X1543489Y899114D01*
G03X1544066Y898347I511J-216D01*
G03X1544593Y898515I-175J1458D01*
G01X1544626Y898534D01*
G02X1546854I1114J-1919D01*
G01X1546887Y898515D01*
G03X1548327Y898534I703J1289D01*
G02X1550555I1114J-1919D01*
G02X1551010Y898184I-1114J-1919D01*
G01X1551966Y897228D01*
X1554694D01*
X1556637Y895285D01*
X1557004D01*
G01X1549441Y909370D02*
X1549075Y908740D01*
G03X1549594Y907910I463J-288D01*
G03X1550144Y908081I-152J1460D01*
G01X1550177Y908100D01*
G02X1553277Y908935I3100J-5337D01*
G01X1554880D01*
X1555660Y908155D01*
X1556782D01*
G01X1547590Y899804D02*
G02X1549630Y900782I2312J-2206D01*
G03X1550555Y901074I-189J2211D01*
G02X1551022Y901272I1110J-1967D01*
G02X1551320Y901315I297J-1002D01*
G01X1554373D01*
X1555367Y900321D01*
Y899361D01*
X1558134Y896594D01*
G01X1549441Y902993D02*
X1549064Y902344D01*
G03X1549639Y901538I500J-252D01*
G03X1550144Y901704I-198J1455D01*
G01X1550177Y901723D01*
G02X1551864Y902215I1687J-2646D01*
G01X1555371D01*
X1556247Y901339D01*
Y900379D01*
X1558327Y898299D01*
G01X1543890Y906181D02*
X1543489Y905492D01*
G03X1544066Y904725I511J-216D01*
G03X1544593Y904893I-175J1458D01*
G01X1544626Y904912D01*
G02X1546854I1114J-1919D01*
G01X1546887Y904893D01*
G03X1548327Y904912I703J1289D01*
G02X1550555I1114J-1919D01*
G03X1551291Y904715I734J1270D01*
G01X1551293Y904713D01*
X1555761D01*
X1558527Y901947D01*
G01X1547590Y906181D02*
G02X1549628Y907158I2310J-2204D01*
G03X1550555Y907451I-189J2211D01*
G02X1551385Y907675I830J-1426D01*
G01X1554422D01*
X1555362Y906735D01*
X1556306D01*
G01X1543890Y912559D02*
X1543476Y911847D01*
G03X1543884Y911092I541J-195D01*
G03X1544593Y911271I7J1466D01*
G01X1544597Y911273D01*
X1544626Y911290D01*
G02X1546854I1114J-1919D01*
G01X1546887Y911271D01*
G03X1548327Y911290I703J1288D01*
G02X1550555I1114J-1919D01*
G03X1551291Y911090I740J1268D01*
G01X1556819D01*
G01X1547590Y918937D02*
G02X1549628Y919914I2310J-2204D01*
G03X1550555Y920207I-189J2211D01*
G02X1551400Y920435I845J-1452D01*
G01X1554347D01*
G01X1549441Y922126D02*
X1549075Y921496D01*
G03X1549594Y920666I463J-288D01*
G03X1550144Y920837I-152J1460D01*
G01X1550177Y920856D01*
G02X1553403Y921725I3226J-5555D01*
G01X1555960D01*
X1556300Y922065D01*
X1557824D01*
G01X1543890Y925315D02*
Y925314D01*
X1543476Y924602D01*
G03X1543884Y923847I541J-195D01*
G03X1544593Y924026I7J1466D01*
G01X1544597Y924028D01*
X1544626Y924045D01*
G02X1546854I1114J-1919D01*
G01X1546887Y924026D01*
G03X1548327Y924045I703J1289D01*
G02X1550555I1114J-1919D01*
G03X1551291Y923846I738J1269D01*
G01X1554905D01*
X1556584Y925525D01*
X1557884D01*
G01X1547590Y925315D02*
G02X1549628Y926292I2310J-2204D01*
G03X1550555Y926585I-189J2211D01*
G02X1551370Y926805I815J-1401D01*
G01X1555952D01*
X1556472Y927325D01*
X1557984D01*
G01X1549441Y915748D02*
X1549038Y915054D01*
G03X1549695Y914302I556J-177D01*
G03X1550144Y914459I-253J1443D01*
G01X1550177Y914478D01*
G02X1551105Y914771I1116J-1918D01*
G02X1551290Y914778I176J-2212D01*
G01X1554928D01*
X1555978Y913728D01*
X1557417D01*
X1557677Y913988D01*
X1557752D01*
G01X1547590Y912559D02*
G02X1549673Y913541I2450J-2497D01*
G03X1549825Y913562I-228J2207D01*
G03X1550555Y913829I-385J2185D01*
G02X1551169Y914023I739J-1269D01*
G02X1551291Y914028I121J-1464D01*
G01X1554617D01*
X1555667Y912978D01*
X1557417D01*
X1557677Y912718D01*
X1557752D01*
G01X1543890Y918937D02*
X1543489Y918247D01*
G03X1544066Y917480I511J-216D01*
G03X1544593Y917648I-175J1458D01*
G01X1544626Y917667D01*
G02X1546854I1114J-1919D01*
G01X1546887Y917648D01*
G03X1548327Y917667I703J1289D01*
G02X1550555I1114J-1919D01*
G03X1551291Y917470I734J1270D01*
G01X1551293Y917468D01*
X1555814D01*
X1556074Y917728D01*
X1556149D01*
G01X1549441Y928504D02*
X1549075Y927874D01*
G03X1549594Y927044I463J-288D01*
G03X1550144Y927215I-152J1460D01*
G01X1550177Y927234D01*
G02X1552186Y927775I2009J-3458D01*
G01X1555324D01*
X1556214Y928665D01*
X1558024D01*
G01X1543890Y931693D02*
Y931692D01*
X1543476Y930980D01*
G03X1543884Y930225I541J-195D01*
G03X1544593Y930404I7J1466D01*
G01X1544597Y930406D01*
X1544626Y930423D01*
G02X1546854I1114J-1919D01*
G01X1546887Y930404D01*
G03X1548327Y930423I703J1289D01*
G02X1550555I1114J-1919D01*
G03X1551364Y930205I809J1391D01*
G01X1554384D01*
X1555524Y931345D01*
X1557804D01*
G01X1547590Y938071D02*
G02X1549628Y939048I2310J-2204D01*
G03X1550555Y939341I-189J2211D01*
G02X1551425Y939575I870J-1500D01*
G01X1554834D01*
X1555144Y939265D01*
X1557397D01*
G01X1549441Y941260D02*
X1549075Y940630D01*
G03X1549594Y939800I463J-288D01*
G03X1550144Y939971I-152J1460D01*
G02X1552746Y940695I2602J-4313D01*
G01X1554684D01*
X1556224Y942235D01*
G01X1549441Y934882D02*
X1549038Y934188D01*
G03X1549695Y933436I556J-177D01*
G03X1550144Y933593I-253J1443D01*
G01X1550177Y933612D01*
G02X1551105Y933905I1116J-1918D01*
G02X1551290Y933912I176J-2212D01*
G01X1554710D01*
X1555163Y934365D01*
X1556509D01*
X1556769Y934625D01*
X1556844D01*
G01X1547590Y931693D02*
G02X1549673Y932675I2450J-2497D01*
G03X1549825Y932696I-228J2207D01*
G03X1550555Y932963I-385J2185D01*
G02X1551169Y933157I739J-1269D01*
G02X1551291Y933162I121J-1464D01*
G01X1555021D01*
X1555474Y933615D01*
X1556509D01*
X1556769Y933355D01*
X1556844D01*
G01X1543890Y938071D02*
X1543489Y937381D01*
G03X1544066Y936614I511J-216D01*
G03X1544593Y936782I-175J1458D01*
G01X1544626Y936801D01*
G02X1546854I1114J-1919D01*
G01X1546887Y936782D01*
G03X1548327Y936801I703J1289D01*
G02X1550555I1114J-1919D01*
G03X1551291Y936604I734J1270D01*
G01X1551293Y936602D01*
X1554467D01*
X1555220Y937355D01*
X1556717D01*
X1556977Y937615D01*
X1557052D01*
G01X1543890Y944449D02*
Y944448D01*
X1543476Y943736D01*
G03X1543884Y942981I541J-195D01*
G03X1544593Y943160I7J1466D01*
G01X1544597Y943162D01*
X1544626Y943179D01*
G02X1546854I1114J-1919D01*
G01X1546887Y943160D01*
G03X1548327Y943179I703J1289D01*
G02X1550555I1114J-1919D01*
G03X1551386Y942955I831J1429D01*
G01X1554379D01*
X1556339Y944915D01*
X1557367D01*
G01X1547590Y944449D02*
G02X1549628Y945426I2310J-2204D01*
G03X1550555Y945719I-189J2211D01*
G02X1552101Y946135I1546J-2666D01*
G01X1555504D01*
X1556084Y946715D01*
X1557627D01*
G01X1549441Y947638D02*
X1549075Y947008D01*
G03X1549594Y946178I463J-288D01*
G03X1550144Y946349I-152J1460D01*
G02X1553831Y947375I3687J-6112D01*
G01X1555364D01*
X1556054Y948065D01*
X1557717D01*
G01X1543890Y950827D02*
Y950826D01*
X1543476Y950114D01*
G03X1543884Y949359I541J-195D01*
G03X1544593Y949538I7J1466D01*
G01X1544597Y949540D01*
X1544626Y949557D01*
G02X1546854I1114J-1919D01*
G01X1546887Y949538D01*
G03X1548327Y949557I703J1289D01*
G02X1550555I1114J-1919D01*
G03X1551378Y949335I823J1416D01*
G01X1554534D01*
X1556037Y950838D01*
X1558027D01*
G01X1549441Y954016D02*
X1549038Y953322D01*
G03X1549695Y952570I556J-177D01*
G03X1550144Y952727I-253J1443D01*
G01X1550177Y952746D01*
G02X1551105Y953039I1116J-1918D01*
G02X1551290Y953046I176J-2212D01*
G01X1554896D01*
X1555696Y953846D01*
X1557007D01*
X1557267Y954106D01*
X1557342D01*
G01X1547590Y950827D02*
G02X1549673Y951809I2450J-2497D01*
G03X1549825Y951830I-228J2207D01*
G03X1550555Y952097I-385J2185D01*
G02X1551169Y952291I739J-1269D01*
G02X1551291Y952296I121J-1464D01*
G01X1555207D01*
X1556007Y953096D01*
X1557007D01*
X1557267Y952836D01*
X1557342D01*
G01X1547590Y963583D02*
G02X1549628Y964560I2310J-2204D01*
G03X1550555Y964853I-189J2211D01*
G02X1551169Y965047I739J-1269D01*
G02X1551605Y965065I436J-5268D01*
G01X1555320D01*
X1555420Y964965D01*
X1556904D01*
G01X1549441Y966772D02*
X1549075Y966142D01*
G03X1549594Y965312I463J-288D01*
G03X1550144Y965483I-152J1460D01*
G01X1550177Y965502D01*
G02X1550561Y965679I1117J-1918D01*
G02X1554331Y966318I3770J-10804D01*
G01X1556897D01*
G01X1543890Y969961D02*
Y969960D01*
X1543476Y969248D01*
G03X1543884Y968493I541J-195D01*
G03X1544593Y968672I7J1466D01*
G01X1544597Y968674D01*
X1544626Y968691D01*
G02X1546854I1114J-1919D01*
G01X1546887Y968672D01*
G03X1548327Y968691I703J1289D01*
G02X1550555I1114J-1919D01*
G03X1551356Y968475I801J1378D01*
G01X1555124D01*
X1555677Y969028D01*
X1557267D01*
G01X1547590Y957205D02*
G02X1549628Y958182I2310J-2204D01*
G03X1550555Y958475I-189J2211D01*
G02X1551169Y958669I739J-1269D01*
G02X1551556Y958685I387J-4683D01*
G01X1556804D01*
X1557144Y959025D01*
X1558327D01*
G01X1549441Y960394D02*
X1549075Y959764D01*
G03X1549594Y958934I463J-288D01*
G03X1550144Y959105I-152J1460D01*
G01X1550177Y959124D01*
G02X1550503Y959279I1113J-1920D01*
G02X1553949Y959915I3446J-9020D01*
G01X1556354D01*
X1556827Y960388D01*
X1558137D01*
G01X1543890Y963583D02*
Y963582D01*
X1543476Y962870D01*
G03X1543884Y962115I541J-195D01*
G03X1544593Y962294I7J1466D01*
G01X1544597Y962296D01*
X1544626Y962313D01*
G02X1546854I1114J-1919D01*
G01X1546887Y962294D01*
G03X1548327Y962313I703J1289D01*
G02X1550555I1114J-1919D01*
G03X1551364Y962095I809J1391D01*
G01X1554544D01*
X1555554Y963105D01*
X1557700D01*
G01X1547590Y969961D02*
G02X1549673Y970943I2450J-2497D01*
G03X1549825Y970964I-228J2207D01*
G03X1550555Y971231I-385J2185D01*
G02X1551169Y971425I739J-1269D01*
G02X1551291Y971430I121J-1464D01*
G01X1554835D01*
X1555337Y970928D01*
X1556197D01*
X1556457Y970668D01*
X1556532D01*
G01X1543890Y957205D02*
X1543489Y956515D01*
G03X1544066Y955748I511J-216D01*
G03X1544593Y955916I-175J1458D01*
G01X1544626Y955935D01*
G02X1546854I1114J-1919D01*
G01X1546887Y955916D01*
G03X1548327Y955935I703J1289D01*
G02X1550555I1114J-1919D01*
G03X1551291Y955738I734J1270D01*
G01X1551293Y955736D01*
X1554433D01*
X1555832Y957135D01*
X1557205D01*
X1557465Y957395D01*
X1557540D01*
G01X1547590Y982717D02*
G02X1549628Y983694I2310J-2204D01*
G03X1550074Y983778I-186J2211D01*
G03X1550350Y983898I-368J1224D01*
G01X1551328Y984465D01*
G02X1553934Y985165I2605J-4498D01*
G01X1547590Y976339D02*
G02X1549673Y977321I2450J-2497D01*
G03X1549825Y977342I-228J2207D01*
G03X1550555Y977609I-385J2185D01*
G02X1551169Y977803I739J-1269D01*
G02X1551291Y977808I121J-1464D01*
G01X1554471D01*
X1555679Y976600D01*
X1556585D01*
G01X1549441Y979528D02*
X1549038Y978834D01*
G03X1549695Y978082I556J-177D01*
G03X1550144Y978239I-253J1443D01*
G01X1550177Y978258D01*
G02X1551105Y978551I1116J-1918D01*
G02X1551290Y978558I176J-2212D01*
G01X1555497D01*
X1557161Y980222D01*
G01X1543890Y982717D02*
Y982716D01*
X1543476Y982004D01*
G03X1543884Y981249I541J-195D01*
G03X1544593Y981428I7J1466D01*
G01X1544597Y981430D01*
X1544626Y981447D01*
G02X1546854I1114J-1919D01*
G01X1546887Y981428D01*
G03X1548327Y981447I703J1289D01*
G02X1550555I1114J-1919D01*
G03X1551378Y981225I823J1416D01*
G01X1554524D01*
X1556201Y982902D01*
X1556907D01*
G01X1549441Y973150D02*
X1549038Y972456D01*
G03X1549695Y971704I556J-177D01*
G03X1550144Y971861I-253J1443D01*
G01X1550177Y971880D01*
G02X1551105Y972173I1116J-1918D01*
G02X1551290Y972180I176J-2212D01*
G01X1555146D01*
X1555648Y971678D01*
X1556197D01*
X1556457Y971938D01*
X1556532D01*
G01X1543890Y976339D02*
X1543489Y975649D01*
G03X1544066Y974882I511J-216D01*
G03X1544593Y975050I-175J1458D01*
G01X1544626Y975069D01*
G02X1546854I1114J-1919D01*
G01X1546887Y975050D01*
G03X1548327Y975069I703J1289D01*
G02X1550555I1114J-1919D01*
G03X1551291Y974872I734J1270D01*
G01X1551293Y974870D01*
X1553418D01*
X1553578Y974710D01*
X1556184D01*
X1556444Y974970D01*
X1556519D01*
G01X1547590Y995473D02*
G02X1549628Y996450I2310J-2204D01*
G03X1550555Y996743I-189J2211D01*
G02X1551378Y996965I823J-1414D01*
G01X1554874D01*
X1555044Y996795D01*
X1557497D01*
G01X1549441Y998662D02*
X1549075Y998032D01*
G03X1549594Y997202I463J-288D01*
G03X1550144Y997373I-152J1460D01*
G01X1550177Y997392D01*
G02X1552932Y998135I2755J-4736D01*
G01X1557584D01*
G01X1547590Y989095D02*
G02X1549628Y990072I2310J-2204D01*
G03X1550555Y990365I-189J2211D01*
G02X1551370Y990585I815J-1401D01*
G01X1556314D01*
G01X1549441Y1011418D02*
X1549075Y1010788D01*
G03X1549594Y1009958I463J-288D01*
G03X1550144Y1010129I-152J1460D01*
G01X1550177Y1010148D01*
G02X1551105Y1010441I1116J-1918D01*
G01X1551108Y1010445D01*
G02X1551661Y1010467I553J-6934D01*
G01X1551755D01*
X1551759Y1010463D01*
X1552466D01*
X1553353Y1011350D01*
X1554637D01*
X1554932Y1011645D01*
X1555007D01*
G01X1547590Y1008229D02*
G02X1549628Y1009206I2310J-2204D01*
G03X1550555Y1009499I-189J2211D01*
G02X1551169Y1009693I739J-1269D01*
G02X1551653Y1009713I484J-5854D01*
G01X1552777D01*
X1553664Y1010600D01*
X1554637D01*
X1554932Y1010305D01*
X1555007D01*
G01X1543890Y1001851D02*
Y1001850D01*
X1543476Y1001138D01*
G03X1543884Y1000383I541J-195D01*
G03X1544593Y1000562I7J1466D01*
G01X1544597Y1000564D01*
X1544626Y1000581D01*
G02X1546854I1114J-1919D01*
G01X1546887Y1000562D01*
G03X1548327Y1000581I703J1289D01*
G02X1550555I1114J-1919D01*
G03X1551356Y1000365I801J1378D01*
G01X1554974D01*
X1555424Y1000815D01*
X1557497D01*
G01X1547590Y1001851D02*
G02X1549628Y1002828I2310J-2204D01*
G03X1550555Y1003121I-189J2211D01*
G02X1551378Y1003343I823J-1414D01*
G01X1555842D01*
X1555872Y1003373D01*
X1557527D01*
G01X1549441Y1005040D02*
X1549075Y1004410D01*
G03X1549594Y1003580I463J-288D01*
G03X1550144Y1003751I-152J1460D01*
G01X1550177Y1003770D01*
G02X1552932Y1004513I2755J-4736D01*
G01X1556162D01*
X1556362Y1004713D01*
X1557527D01*
G01X1543890Y1008229D02*
Y1008228D01*
X1543476Y1007516D01*
G03X1543884Y1006761I541J-195D01*
G03X1544593Y1006940I7J1466D01*
G01X1544597Y1006942D01*
X1544626Y1006959D01*
G02X1546854I1114J-1919D01*
G01X1546887Y1006940D01*
G03X1548327Y1006959I703J1289D01*
G02X1550555I1114J-1919D01*
G03X1551386Y1006735I831J1429D01*
G01X1554704D01*
X1555362Y1007393D01*
X1557267D01*
G01X1545071Y1030197D02*
X1544644Y1030932D01*
G02X1545241Y1031655I533J168D01*
G02X1545774Y1031486I-169J-1458D01*
G01X1545807Y1031467D01*
G03X1548035I1114J1919D01*
G01X1548036D01*
G02X1549508I736J-1268D01*
G03X1551736I1114J1919D01*
G02X1552061Y1031633I1665J-2859D01*
G02X1552356Y1031696I297J-667D01*
G01X1555629Y1031701D01*
X1556473Y1030857D01*
X1558361D01*
G01X1543220Y1033386D02*
G03X1545016Y1032416I1746J1085D01*
G02X1546185Y1032116I54J-2218D01*
G03X1547657I736J1270D01*
G02X1549885I1114J-1919D01*
G03X1551325Y1032097I737J1270D01*
G01X1551358Y1032116D01*
G02X1552189Y1032481I2009J-3446D01*
G02X1552487Y1032525I295J-965D01*
G01X1556520D01*
X1556848Y1032197D01*
X1558071D01*
G01X1550622Y1033386D02*
X1550219Y1034080D01*
G02X1550876Y1034832I556J177D01*
G02X1551325Y1034675I-253J-1443D01*
G01X1551358Y1034656D01*
G03X1552286Y1034363I1116J1918D01*
G03X1552471Y1034356I176J2212D01*
G01X1555553D01*
X1556372Y1033537D01*
X1557727D01*
G01X1548771Y1036575D02*
G03X1550854Y1035593I2450J2497D01*
G02X1551006Y1035572I-228J-2207D01*
G02X1551736Y1035305I-385J-2185D01*
G03X1552350Y1035111I739J1269D01*
G03X1552472Y1035106I121J1464D01*
G01X1556356D01*
X1556585Y1034877D01*
X1557782D01*
G01X1545071Y1036575D02*
X1544644Y1037310D01*
G02X1545241Y1038033I533J168D01*
G02X1545774Y1037864I-169J-1458D01*
G01X1545807Y1037845D01*
G03X1548035I1114J1919D01*
G01X1548036D01*
G02X1549508I736J-1268D01*
G03X1551736I1114J1919D01*
G02X1552061Y1038011I1665J-2859D01*
G02X1552356Y1038074I297J-667D01*
G01X1555694Y1038078D01*
X1556335Y1037420D01*
X1558595D01*
G01X1543220Y1039764D02*
G03X1545016Y1038794I1746J1085D01*
G02X1546185Y1038494I54J-2218D01*
G03X1547657I736J1270D01*
G02X1549885I1114J-1919D01*
G03X1551325Y1038475I737J1270D01*
G01X1551358Y1038494D01*
G02X1552189Y1038859I2009J-3446D01*
G02X1552487Y1038903I295J-965D01*
G01X1556217D01*
X1556360Y1038760D01*
X1558319D01*
G01X1550622Y1039764D02*
X1550219Y1040458D01*
G02X1550876Y1041210I556J177D01*
G02X1551325Y1041053I-253J-1443D01*
G01X1551358Y1041034D01*
G03X1552286Y1040741I1116J1918D01*
G03X1552471Y1040734I176J2212D01*
G01X1556008D01*
X1556642Y1040100D01*
X1558474D01*
G01X1543220Y1046142D02*
G03X1545016Y1045172I1746J1085D01*
G02X1546185Y1044872I54J-2218D01*
G03X1547657I736J1270D01*
G02X1549885I1114J-1919D01*
G03X1551325Y1044853I737J1270D01*
G01X1551358Y1044872D01*
G02X1552189Y1045237I2009J-3446D01*
G02X1552487Y1045281I295J-965D01*
G01X1556356D01*
X1556499Y1045138D01*
X1558279D01*
G01X1545071Y1042953D02*
X1544644Y1043688D01*
G02X1545241Y1044411I533J168D01*
G02X1545774Y1044242I-169J-1458D01*
G01X1545807Y1044223D01*
G03X1548035I1114J1919D01*
G01X1548036D01*
G02X1549508I736J-1268D01*
G03X1551736I1114J1919D01*
G02X1552061Y1044389I1665J-2859D01*
G02X1552356Y1044452I297J-667D01*
G01X1555791Y1044456D01*
X1556449Y1043798D01*
X1558496D01*
G01X1545071Y1049331D02*
X1544644Y1050066D01*
G02X1545241Y1050789I533J168D01*
G02X1545774Y1050620I-169J-1458D01*
G01X1545807Y1050601D01*
G03X1548035I1114J1919D01*
G01X1548036D01*
G02X1549508I736J-1268D01*
G03X1551736I1114J1919D01*
G02X1552061Y1050767I1665J-2859D01*
G02X1552356Y1050830I297J-667D01*
G01X1555675Y1050834D01*
X1555778Y1050727D01*
X1556331Y1050174D01*
X1557618D01*
G01X1550622Y1058898D02*
X1550219Y1059592D01*
G02X1550876Y1060344I556J177D01*
G02X1551325Y1060187I-253J-1443D01*
G01X1551358Y1060168D01*
G03X1552286Y1059875I1116J1918D01*
G03X1552471Y1059868I176J2212D01*
G01X1554322D01*
X1555668Y1058522D01*
X1557973D01*
G01X1548771Y1049331D02*
G03X1550538Y1048360I1694J989D01*
G02X1551736Y1048061I83J-2217D01*
G03X1552617Y1047823I883J1520D01*
G01X1555755Y1047818D01*
X1557824D01*
G01X1550622Y1052520D02*
X1550219Y1053214D01*
G02X1550876Y1053966I556J177D01*
G02X1551325Y1053809I-253J-1443D01*
G01X1551358Y1053790D01*
G03X1552286Y1053497I1116J1918D01*
G03X1552471Y1053490I176J2212D01*
G01X1556281D01*
X1556917Y1052854D01*
X1557866D01*
G01X1550622Y1071654D02*
X1550219Y1072348D01*
G02X1550876Y1073100I556J177D01*
G02X1551325Y1072943I-253J-1443D01*
G01X1551358Y1072924D01*
G03X1552286Y1072631I1116J1918D01*
G03X1552471Y1072624I176J2212D01*
G01X1555656D01*
X1556914Y1071366D01*
X1558155D01*
G01X1545071Y1074843D02*
X1544644Y1075578D01*
G02X1545241Y1076301I533J168D01*
G02X1545774Y1076132I-169J-1458D01*
G01X1545807Y1076113D01*
G03X1548035I1114J1919D01*
G01X1548036D01*
G02X1549508I736J-1268D01*
G03X1551736I1114J1919D01*
G02X1552061Y1076279I1665J-2859D01*
G02X1552356Y1076342I297J-667D01*
G01X1555541Y1076347D01*
X1557842Y1074046D01*
X1558314D01*
G01X1548771Y1074843D02*
G03X1550854Y1073861I2450J2497D01*
G02X1551006Y1073840I-228J-2207D01*
G02X1551736Y1073573I-385J-2185D01*
G03X1552350Y1073379I739J1269D01*
G03X1552472Y1073374I121J1464D01*
G01X1556043D01*
X1556711Y1072706D01*
X1557932D01*
G01X1545071Y1062087D02*
X1544644Y1062822D01*
G02X1545241Y1063545I533J168D01*
G02X1545774Y1063376I-169J-1458D01*
G01X1545807Y1063357D01*
G03X1548035I1114J1919D01*
G01X1548036D01*
G02X1549508I736J-1268D01*
G03X1551736I1114J1919D01*
G02X1552061Y1063523I1665J-2859D01*
G02X1552356Y1063586I297J-667D01*
G01X1555544Y1063591D01*
X1557135Y1062000D01*
X1557524D01*
G01X1548771Y1062087D02*
G03X1550854Y1061105I2450J2497D01*
G02X1551006Y1061084I-228J-2207D01*
G02X1551736Y1060817I-385J-2185D01*
G03X1552350Y1060623I739J1269D01*
G03X1552472Y1060618I121J1464D01*
G01X1555858D01*
X1556028Y1060448D01*
X1558673D01*
G01X1543220Y1065276D02*
G03X1545016Y1064306I1746J1085D01*
G02X1546185Y1064006I54J-2218D01*
G03X1547657I736J1270D01*
G02X1549885I1114J-1919D01*
G03X1551325Y1063987I737J1270D01*
G01X1551358Y1064006D01*
G02X1552189Y1064371I2009J-3446D01*
G02X1552487Y1064415I295J-965D01*
G01X1556040D01*
X1556537Y1063918D01*
X1558227D01*
G01X1545071Y1068465D02*
X1544670Y1069155D01*
G02X1545247Y1069922I511J216D01*
G02X1545774Y1069754I-175J-1458D01*
G01X1545807Y1069735D01*
G03X1548035I1114J1919D01*
G01X1548068Y1069754D01*
G02X1549508Y1069735I703J-1289D01*
G03X1551736I1114J1919D01*
G02X1552472Y1069932I734J-1270D01*
G01X1552474Y1069934D01*
X1555724D01*
X1556922Y1068736D01*
X1558166D01*
X1558426Y1068476D01*
X1558501D01*
G01X1548771Y1068465D02*
G03X1550854Y1067483I2450J2497D01*
G02X1551006Y1067462I-228J-2207D01*
G02X1551736Y1067195I-385J-2185D01*
G03X1552350Y1067001I739J1269D01*
G03X1552472Y1066996I121J1464D01*
G01X1554720D01*
X1555160Y1066556D01*
X1556785D01*
X1557045Y1066816D01*
X1557120D01*
G01X1543220Y1071654D02*
G03X1545245Y1070678I2272J2125D01*
G02X1545338Y1070669I-167J-2213D01*
G02X1546185Y1070384I-270J-2203D01*
G03X1547657I736J1270D01*
G02X1549885I1114J-1919D01*
G03X1551325Y1070365I737J1270D01*
G01X1551358Y1070384D01*
G02X1552472Y1070684I1114J-1918D01*
G01X1556035D01*
X1557233Y1069486D01*
X1558166D01*
X1558426Y1069746D01*
X1558501D01*
G01X1550622Y1065276D02*
X1550219Y1065970D01*
G02X1550876Y1066722I556J177D01*
G02X1551325Y1066565I-253J-1443D01*
G01X1551358Y1066546D01*
G03X1552286Y1066253I1116J1918D01*
G03X1552471Y1066246I176J2212D01*
G01X1554409D01*
X1554849Y1065806D01*
X1556785D01*
X1557045Y1065546D01*
X1557120D01*
G01X1543220Y1078032D02*
G03X1545016Y1077062I1746J1085D01*
G02X1546185Y1076762I54J-2218D01*
G03X1547657I736J1270D01*
G02X1549885I1114J-1919D01*
G03X1551325Y1076743I737J1270D01*
G01X1551358Y1076762D01*
G02X1552189Y1077127I2009J-3446D01*
G02X1552487Y1077171I295J-965D01*
G01X1555911D01*
X1557696Y1075386D01*
X1558382D01*
G01X1550622Y1078032D02*
X1550219Y1078726D01*
G02X1550876Y1079478I556J177D01*
G02X1551325Y1079321I-253J-1443D01*
G01X1551358Y1079302D01*
G03X1552286Y1079009I1116J1918D01*
G03X1552471Y1079002I176J2212D01*
G01X1555473D01*
X1556386Y1078089D01*
X1558515D01*
G01X1545071Y1081221D02*
X1544644Y1081956D01*
G02X1545241Y1082679I533J168D01*
G02X1545774Y1082510I-169J-1458D01*
G01X1545807Y1082491D01*
G03X1548035I1114J1919D01*
G01X1548036D01*
G02X1549508I736J-1268D01*
G03X1551736I1114J1919D01*
G02X1552061Y1082657I1665J-2859D01*
G02X1552356Y1082720I297J-667D01*
G01X1556956Y1082726D01*
X1557372Y1082310D01*
X1557576D01*
G01X1548771Y1081221D02*
G03X1550854Y1080239I2450J2497D01*
G02X1551006Y1080218I-228J-2207D01*
G02X1551736Y1079951I-385J-2185D01*
G03X1552350Y1079757I739J1269D01*
G03X1552472Y1079752I121J1464D01*
G01X1556204D01*
X1556527Y1079429D01*
X1558380D01*
G01X1543220Y1084410D02*
G03X1545016Y1083440I1746J1085D01*
G02X1546185Y1083140I54J-2218D01*
G03X1547657I736J1270D01*
G02X1549885I1114J-1919D01*
G03X1551325Y1083121I737J1270D01*
G01X1551358Y1083140D01*
G02X1552189Y1083505I2009J-3446D01*
G02X1553160Y1083650I971J-3178D01*
G01X1558583D01*
G01X1548771Y1087599D02*
G03X1550854Y1086617I2450J2497D01*
G02X1551006Y1086596I-228J-2207D01*
G02X1551736Y1086329I-385J-2185D01*
G03X1552350Y1086135I739J1269D01*
G03X1552472Y1086130I121J1464D01*
G01X1556074D01*
X1556232Y1086288D01*
X1558166D01*
X1558426Y1086548D01*
X1558501D01*
G01X1545071Y1087599D02*
X1544670Y1088289D01*
G02X1545247Y1089056I511J216D01*
G02X1545774Y1088888I-175J-1458D01*
G01X1545807Y1088869D01*
G03X1548035I1114J1919D01*
G01X1548068Y1088888D01*
G02X1549508Y1088869I703J-1289D01*
G03X1551736I1114J1919D01*
G02X1552472Y1089066I734J-1270D01*
G01X1552474Y1089068D01*
X1555724D01*
X1556289Y1088503D01*
X1558166D01*
X1558426Y1088243D01*
X1558501D01*
G01X1550622Y1084410D02*
X1550219Y1085104D01*
G02X1550876Y1085856I556J177D01*
G02X1551325Y1085699I-253J-1443D01*
G01X1551358Y1085680D01*
G03X1552286Y1085387I1116J1918D01*
G03X1552471Y1085380I176J2212D01*
G01X1556385D01*
X1556543Y1085538D01*
X1558166D01*
X1558426Y1085278D01*
X1558501D01*
G01X1543220Y1090788D02*
G03X1545245Y1089812I2272J2125D01*
G02X1545338Y1089803I-167J-2213D01*
G02X1546185Y1089518I-270J-2203D01*
G03X1547657I736J1270D01*
G02X1549885I1114J-1919D01*
G03X1551325Y1089499I737J1270D01*
G01X1551358Y1089518D01*
G02X1552472Y1089818I1114J-1918D01*
G01X1556035D01*
X1556600Y1089253D01*
X1558166D01*
X1558426Y1089513D01*
X1558501D01*
G01X1548771Y1100355D02*
G03X1550854Y1099373I2450J2497D01*
G02X1551006Y1099352I-228J-2207D01*
G02X1551736Y1099085I-385J-2185D01*
G03X1552350Y1098891I739J1269D01*
G03X1552472Y1098886I121J1464D01*
G01X1555858D01*
X1555902Y1098842D01*
X1558617D01*
G01X1543220Y1103544D02*
G03X1545016Y1102574I1746J1085D01*
G02X1546185Y1102274I54J-2218D01*
G03X1547657I736J1270D01*
G02X1549885I1114J-1919D01*
G03X1551325Y1102255I737J1270D01*
G01X1551358Y1102274D01*
G02X1552189Y1102639I2009J-3446D01*
G02X1552487Y1102683I295J-965D01*
G01X1555861D01*
X1557022Y1101522D01*
X1558231D01*
G01X1550622Y1090788D02*
X1550219Y1091482D01*
G02X1550876Y1092234I556J177D01*
G02X1551325Y1092077I-253J-1443D01*
G01X1551358Y1092058D01*
G03X1552286Y1091765I1116J1918D01*
G03X1552471Y1091758I176J2212D01*
G01X1555753D01*
X1556377Y1091134D01*
X1558718D01*
G01X1545071Y1093977D02*
X1544644Y1094712D01*
G02X1545241Y1095435I533J168D01*
G02X1545774Y1095266I-169J-1458D01*
G01X1545807Y1095247D01*
G03X1548035I1114J1919D01*
G01X1548036D01*
G02X1549508I736J-1268D01*
G03X1551736I1114J1919D01*
G02X1552061Y1095413I1665J-2859D01*
G02X1552356Y1095476I297J-667D01*
G01X1555103Y1095480D01*
X1558312Y1094148D01*
G01X1548771Y1093977D02*
G03X1550854Y1092995I2450J2497D01*
G02X1551006Y1092974I-228J-2207D01*
G02X1551736Y1092707I-385J-2185D01*
G03X1552350Y1092513I739J1269D01*
G03X1552472Y1092508I121J1464D01*
G01X1557527D01*
X1557587Y1092568D01*
G01X1543220Y1097166D02*
G03X1545016Y1096196I1746J1085D01*
G02X1546185Y1095896I54J-2218D01*
G03X1547657I736J1270D01*
G02X1549885I1114J-1919D01*
G03X1551325Y1095877I737J1270D01*
G01X1551358Y1095896D01*
G02X1552189Y1096261I2009J-3446D01*
G02X1552487Y1096305I295J-965D01*
G01X1557088D01*
X1557830Y1095563D01*
X1558809D01*
G01X1550622Y1097166D02*
X1550219Y1097860D01*
G02X1550876Y1098612I556J177D01*
G02X1551325Y1098455I-253J-1443D01*
G01X1551358Y1098436D01*
G03X1552286Y1098143I1116J1918D01*
G03X1552471Y1098136I176J2212D01*
G01X1555378D01*
X1556026Y1097488D01*
X1558414D01*
G01X1545071Y1100355D02*
X1544644Y1101090D01*
G02X1545241Y1101813I533J168D01*
G02X1545774Y1101644I-169J-1458D01*
G01X1545807Y1101625D01*
G03X1548035I1114J1919D01*
G01X1548036D01*
G02X1549508I736J-1268D01*
G03X1551736I1114J1919D01*
G02X1552061Y1101791I1665J-2859D01*
G02X1552356Y1101854I297J-667D01*
G01X1555539Y1101858D01*
X1557215Y1100182D01*
X1558482D01*
G01X1548771Y1106733D02*
G03X1550854Y1105751I2450J2497D01*
G02X1551006Y1105730I-228J-2207D01*
G02X1551736Y1105463I-385J-2185D01*
G03X1552350Y1105269I739J1269D01*
G03X1552472Y1105264I121J1464D01*
G01X1556184D01*
X1557197Y1104251D01*
X1558166D01*
X1558426Y1104511D01*
X1558501D01*
G01X1550622Y1103544D02*
X1550219Y1104238D01*
G02X1550876Y1104990I556J177D01*
G02X1551325Y1104833I-253J-1443D01*
G01X1551358Y1104814D01*
G03X1552286Y1104521I1116J1918D01*
G03X1552471Y1104514I176J2212D01*
G01X1555873D01*
X1556886Y1103501D01*
X1558166D01*
X1558426Y1103241D01*
X1558501D01*
G01X1550622Y1109922D02*
X1550219Y1110616D01*
G02X1550876Y1111368I556J177D01*
G02X1551325Y1111211I-253J-1443D01*
G01X1551358Y1111192D01*
G03X1552286Y1110899I1116J1918D01*
G03X1552471Y1110892I176J2212D01*
G01X1556258D01*
X1557082Y1111716D01*
X1558313D01*
G01X1545071Y1113111D02*
X1544644Y1113846D01*
G02X1545241Y1114569I533J168D01*
G02X1545774Y1114400I-169J-1458D01*
G01X1545807Y1114381D01*
G03X1548035I1114J1919D01*
G01X1548036D01*
G02X1549508I736J-1268D01*
G03X1551736I1114J1919D01*
G02X1552061Y1114547I1665J-2859D01*
G02X1552356Y1114610I297J-667D01*
G01X1555459Y1114614D01*
X1555547Y1114526D01*
X1558808D01*
G01X1548771Y1113111D02*
G03X1550854Y1112129I2450J2497D01*
G02X1551006Y1112108I-228J-2207D01*
G02X1551736Y1111841I-385J-2185D01*
G03X1552350Y1111647I739J1269D01*
G03X1552472Y1111642I121J1464D01*
G01X1555946D01*
X1557360Y1113056D01*
G01X1543220Y1116300D02*
G03X1545016Y1115330I1746J1085D01*
G02X1546185Y1115030I54J-2218D01*
G03X1547657I736J1270D01*
G02X1549885I1114J-1919D01*
G03X1551325Y1115011I737J1270D01*
G01X1551358Y1115030D01*
G02X1552189Y1115395I2009J-3446D01*
G02X1552487Y1115439I295J-965D01*
G01X1556388D01*
X1556815Y1115866D01*
X1558774D01*
G01X1550622Y1116300D02*
X1550219Y1116994D01*
G02X1550876Y1117746I556J177D01*
G02X1551325Y1117589I-253J-1443D01*
G01X1551358Y1117570D01*
G03X1552286Y1117277I1116J1918D01*
G03X1552471Y1117270I176J2212D01*
G01X1556705D01*
X1557101Y1117666D01*
X1558113D01*
G01X1545071Y1119489D02*
X1544644Y1120224D01*
G02X1545241Y1120947I533J168D01*
G02X1545774Y1120778I-169J-1458D01*
G01X1545807Y1120759D01*
G03X1548035I1114J1919D01*
G01X1548036D01*
G02X1549508I736J-1268D01*
G03X1551736I1114J1919D01*
G02X1552061Y1120925I1665J-2859D01*
G02X1552356Y1120988I297J-667D01*
G01X1555861Y1120993D01*
X1556194D01*
X1556763Y1120424D01*
X1557452D01*
G01X1548771Y1119489D02*
G03X1550854Y1118507I2450J2497D01*
G02X1551006Y1118486I-228J-2207D01*
G02X1551736Y1118219I-385J-2185D01*
G03X1552350Y1118025I739J1269D01*
G03X1552472Y1118020I121J1464D01*
G01X1555943D01*
X1556939Y1119016D01*
X1557629D01*
G01X1545071Y1106733D02*
X1544670Y1107423D01*
G02X1545247Y1108190I511J216D01*
G02X1545774Y1108022I-175J-1458D01*
G01X1545807Y1108003D01*
G03X1548035I1114J1919D01*
G01X1548068Y1108022D01*
G02X1549508Y1108003I703J-1289D01*
G03X1551736I1114J1919D01*
G02X1552472Y1108200I734J-1270D01*
G01X1552474Y1108202D01*
X1555752D01*
X1557038Y1106916D01*
X1558166D01*
X1558426Y1106656D01*
X1558501D01*
G01X1543220Y1109922D02*
G03X1545245Y1108946I2272J2125D01*
G02X1545338Y1108937I-167J-2213D01*
G02X1546185Y1108652I-270J-2203D01*
G03X1547657I736J1270D01*
G02X1549885I1114J-1919D01*
G03X1551325Y1108633I737J1270D01*
G01X1551358Y1108652D01*
G02X1552472Y1108952I1114J-1918D01*
G01X1556063D01*
X1557349Y1107666D01*
X1558166D01*
X1558426Y1107926D01*
X1558501D01*
G01X1543220Y1122678D02*
G03X1545016Y1121708I1746J1085D01*
G02X1546185Y1121408I54J-2218D01*
G03X1547657I736J1270D01*
G02X1549885I1114J-1919D01*
G03X1551325Y1121389I737J1270D01*
G01X1551358Y1121408D01*
G02X1552189Y1121773I2009J-3446D01*
G02X1552487Y1121817I295J-965D01*
G01X1557277D01*
G01X1550622Y1129056D02*
X1550219Y1129750D01*
G02X1550876Y1130502I556J177D01*
G02X1551325Y1130345I-253J-1443D01*
G01X1551358Y1130326D01*
G03X1552286Y1130033I1116J1918D01*
G03X1552471Y1130026I176J2212D01*
G01X1556049D01*
X1557234Y1131211D01*
X1558391D01*
G01X1545071Y1132245D02*
X1544644Y1132980D01*
G02X1545241Y1133703I533J168D01*
G02X1545774Y1133534I-169J-1458D01*
G01X1545807Y1133515D01*
G03X1548035I1114J1919D01*
G01X1548036D01*
G02X1549508I736J-1268D01*
G03X1551736I1114J1919D01*
G02X1552061Y1133681I1665J-2859D01*
G02X1552356Y1133744I297J-667D01*
G01X1555861Y1133749D01*
X1556444D01*
X1556586Y1133891D01*
X1558479D01*
G01X1548771Y1132245D02*
G03X1550854Y1131263I2450J2497D01*
G02X1551006Y1131242I-228J-2207D01*
G02X1551736Y1130975I-385J-2185D01*
G03X1552350Y1130781I739J1269D01*
G03X1552472Y1130776I121J1464D01*
G01X1555738D01*
X1557513Y1132551D01*
X1558407D01*
G01X1543220Y1135433D02*
G03X1545016Y1134464I2518J2518D01*
G02X1546185Y1134164I54J-2218D01*
G03X1547657I736J1270D01*
G02X1549885I1114J-1919D01*
G03X1551325Y1134145I737J1270D01*
G01X1551358Y1134164D01*
G02X1552189Y1134529I2009J-3446D01*
G02X1552487Y1134573I295J-965D01*
G01X1555850D01*
X1556508Y1135231D01*
X1558612D01*
G01X1548771Y1125867D02*
G03X1550854Y1124885I2450J2497D01*
G02X1551006Y1124864I-228J-2207D01*
G02X1551736Y1124597I-385J-2185D01*
G03X1552350Y1124403I739J1269D01*
G03X1552472Y1124398I121J1464D01*
G01X1556486D01*
X1556546Y1124458D01*
X1558166D01*
X1558426Y1124718D01*
X1558501D01*
G01X1545071Y1125867D02*
X1544670Y1126557D01*
G02X1545247Y1127324I511J216D01*
G02X1545774Y1127156I-175J-1458D01*
G01X1545807Y1127137D01*
G03X1548035I1114J1919D01*
G01X1548068Y1127156D01*
G02X1549508Y1127137I703J-1289D01*
G03X1551736I1114J1919D01*
G02X1552472Y1127334I734J-1270D01*
G01X1552474Y1127336D01*
X1555953D01*
X1556624Y1126665D01*
X1558166D01*
X1558426Y1126405D01*
X1558501D01*
G01X1550622Y1122678D02*
X1550219Y1123372D01*
G02X1550876Y1124124I556J177D01*
G02X1551325Y1123967I-253J-1443D01*
G01X1551358Y1123948D01*
G03X1552286Y1123655I1116J1918D01*
G03X1552471Y1123648I176J2212D01*
G01X1556797D01*
X1556857Y1123708D01*
X1558166D01*
X1558426Y1123448D01*
X1558501D01*
G01X1543220Y1129056D02*
G03X1545245Y1128080I2272J2125D01*
G02X1545338Y1128071I-167J-2213D01*
G02X1546185Y1127786I-270J-2203D01*
G03X1547657I736J1270D01*
G02X1549885I1114J-1919D01*
G03X1551325Y1127767I737J1270D01*
G01X1551358Y1127786D01*
G02X1552472Y1128086I1114J-1918D01*
G01X1556264D01*
X1556935Y1127415D01*
X1558166D01*
X1558426Y1127675D01*
X1558501D01*
G01X1550622Y1135433D02*
X1550219Y1136127D01*
G02X1550876Y1136879I556J177D01*
G02X1551325Y1136722I-253J-1443D01*
G01X1551358Y1136703D01*
G03X1552286Y1136410I1116J1918D01*
G03X1552471Y1136403I176J2212D01*
G01X1556043D01*
X1556671Y1137031D01*
X1557648D01*
G01X1545071Y1138622D02*
X1544644Y1139357D01*
G02X1545241Y1140080I533J168D01*
G02X1545774Y1139911I-169J-1458D01*
G01X1545807Y1139892D01*
G03X1548035I1114J1919D01*
G01X1548036D01*
G02X1549508I736J-1268D01*
G03X1551736I1114J1919D01*
G02X1552061Y1140058I1665J-2859D01*
G02X1552356Y1140121I297J-667D01*
G01X1555861Y1140126D01*
X1556306D01*
X1556721Y1139711D01*
X1557687D01*
G01X1548771Y1138622D02*
G03X1550854Y1137640I2450J2497D01*
G02X1551006Y1137619I-228J-2207D01*
G02X1551736Y1137352I-385J-2185D01*
G03X1552350Y1137158I739J1269D01*
G03X1552472Y1137153I121J1464D01*
G01X1555732D01*
X1556950Y1138371D01*
X1557790D01*
G01X1543220Y1141811D02*
G03X1545016Y1140841I1746J1085D01*
G02X1546185Y1140541I54J-2218D01*
G03X1547657I736J1270D01*
G02X1549885I1114J-1919D01*
G03X1551325Y1140522I737J1270D01*
G01X1551358Y1140541D01*
G02X1552189Y1140906I2009J-3446D01*
G02X1553160Y1141051I971J-3178D01*
G01X1557585D01*
G01X1550622Y1148189D02*
X1550219Y1148883D01*
G02X1550876Y1149635I556J177D01*
G02X1551325Y1149478I-253J-1443D01*
G01X1551358Y1149459D01*
G03X1552286Y1149166I1116J1918D01*
G03X1552471Y1149159I176J2212D01*
G01X1553357D01*
X1553612Y1148904D01*
X1556658D01*
X1558370Y1150616D01*
G01X1548771Y1145000D02*
G03X1550854Y1144018I2450J2497D01*
G02X1551006Y1143997I-228J-2207D01*
G02X1551736Y1143730I-385J-2185D01*
G03X1552350Y1143536I739J1269D01*
G03X1552472Y1143531I121J1464D01*
G01X1555911D01*
X1556638Y1144258D01*
X1557678D01*
X1557938Y1144518D01*
X1558013D01*
G01X1545071Y1145000D02*
X1544670Y1145690D01*
G02X1545247Y1146457I511J216D01*
G02X1545774Y1146289I-175J-1458D01*
G01X1545807Y1146270D01*
G03X1548035I1114J1919D01*
G01X1548068Y1146289D01*
G02X1549508Y1146270I703J-1289D01*
G03X1551736I1114J1919D01*
G02X1552472Y1146467I734J-1270D01*
G01X1552474Y1146469D01*
X1557477D01*
X1557737Y1146209D01*
X1557812D01*
G01X1550622Y1141811D02*
X1550219Y1142505D01*
G02X1550876Y1143257I556J177D01*
G02X1551325Y1143100I-253J-1443D01*
G01X1551358Y1143081D01*
G03X1552286Y1142788I1116J1918D01*
G03X1552471Y1142781I176J2212D01*
G01X1556222D01*
X1556949Y1143508D01*
X1557678D01*
X1557938Y1143248D01*
X1558013D01*
G01X1543220Y1148189D02*
G03X1545245Y1147213I2272J2125D01*
G02X1545338Y1147204I-167J-2213D01*
G02X1546185Y1146919I-270J-2203D01*
G03X1547657I736J1270D01*
G02X1549885I1114J-1919D01*
G03X1551325Y1146900I737J1270D01*
G01X1551358Y1146919D01*
G02X1552472Y1147219I1114J-1918D01*
G01X1557477D01*
X1557737Y1147479D01*
X1557812D01*
G01X1545071Y1151378D02*
X1544644Y1152113D01*
G02X1545241Y1152836I533J168D01*
G02X1545774Y1152667I-169J-1458D01*
G01X1545807Y1152648D01*
G03X1548035I1114J1919D01*
G01X1548036D01*
G02X1549508I736J-1268D01*
G03X1551736I1114J1919D01*
G02X1552061Y1152814I1665J-2859D01*
G02X1552356Y1152877I297J-667D01*
G01X1555861Y1152882D01*
X1556017D01*
X1557622Y1154487D01*
Y1155614D01*
G01X1548771Y1151378D02*
G03X1550854Y1150396I2450J2497D01*
G02X1551006Y1150375I-228J-2207D01*
G02X1551736Y1150108I-385J-2185D01*
G03X1552350Y1149914I739J1269D01*
G03X1552472Y1149909I121J1464D01*
G01X1555651D01*
X1557082Y1151340D01*
G54D128*
X258455Y669601D03*
X291185Y703842D03*
X323955Y723992D03*
X357015Y723724D03*
X390055Y723792D03*
X423055Y705992D03*
X455455Y681392D03*
X488055Y654892D03*
X521355Y620792D03*
X1369007Y638935D03*
X1401707Y671835D03*
X1434307Y704415D03*
X1467225Y723992D03*
X1500307Y724160D03*
X1533107Y723992D03*
X1566237Y702052D03*
X1599007Y668283D03*
X1632007Y649283D03*
G54D53*
X61760Y1535942D03*
X97503D03*
X109156Y1370064D03*
X141756D03*
X174456D03*
X207356D03*
X240156D03*
X261900Y660053D03*
X273756Y1323918D03*
X294630Y694294D03*
X306652Y1323890D03*
X327400Y714444D03*
X339556Y1323833D03*
X360460Y714176D03*
X372356Y1324033D03*
X393500Y714244D03*
X404938Y1343364D03*
X426500Y696444D03*
X458900Y671844D03*
X491500Y645344D03*
X524800Y611244D03*
X716712Y1388073D03*
X749494Y1388173D03*
X1080894Y1370045D03*
X1113494D03*
X1146194D03*
X1179094D03*
X1211894D03*
X1249885Y1323899D03*
X1282781Y1323871D03*
X1315685Y1323814D03*
X1348485Y1324014D03*
X1372452Y629387D03*
X1381067Y1343345D03*
X1405152Y662287D03*
X1437752Y694867D03*
X1470670Y714444D03*
X1503752Y714612D03*
X1536552Y714444D03*
X1569682Y692504D03*
X1602452Y658735D03*
X1635452Y639735D03*
X1664445Y1387362D03*
X1697227Y1387462D03*
X1749043Y1568978D03*
X1784786D03*
G54D263*
X849385Y1541015D03*
X949271Y1479729D03*
G54D308*
X1576680Y574022D03*
Y579022D03*
Y584022D03*
Y589022D03*
G54D44*
X65933Y32756D03*
Y44370D03*
X68295Y32756D03*
X70657D03*
X73020D03*
X75382D03*
X77744D03*
X80106D03*
X68295Y44370D03*
X70657D03*
X73020D03*
X75382D03*
X77744D03*
X80106D03*
X82468Y32756D03*
X84831D03*
X87193D03*
X89555D03*
X91917D03*
X94279D03*
X96642D03*
X82468Y44370D03*
X84831D03*
X87193D03*
X89555D03*
X91917D03*
X94279D03*
X96642D03*
X99004Y32756D03*
X101366D03*
X103728D03*
X106090D03*
X108453D03*
X110815D03*
X99004Y44370D03*
X101366D03*
X103728D03*
X106090D03*
X108453D03*
X110815D03*
X113177Y32756D03*
X115539D03*
X117902D03*
X120264D03*
X122626D03*
X124988D03*
X113177Y44370D03*
X115539D03*
X117902D03*
X120264D03*
X122626D03*
X124988D03*
X127350Y32756D03*
X129713D03*
X127350Y44370D03*
X129713D03*
X149043Y32756D03*
X151405D03*
X153768D03*
X156130D03*
X149043Y44370D03*
X151405D03*
X153768D03*
X156130D03*
X158492Y32756D03*
X160854D03*
X163216D03*
X165579D03*
X167941D03*
X170303D03*
X158492Y44370D03*
X160854D03*
X163216D03*
X165579D03*
X167941D03*
X170303D03*
X172665Y32756D03*
X175028D03*
X177390D03*
X179752D03*
X172665Y44370D03*
X175028D03*
X177390D03*
X179752D03*
X195539Y32756D03*
X197902D03*
X200264D03*
X195539Y44370D03*
X197902D03*
X200264D03*
X202626Y32756D03*
X204988D03*
X207350D03*
X209713D03*
X212075D03*
X214437D03*
X202626Y44370D03*
X204988D03*
X207350D03*
X209713D03*
X212075D03*
X214437D03*
X216799Y32756D03*
X219161D03*
X221524D03*
X223886D03*
X226248D03*
X228610D03*
X230972D03*
X216799Y44370D03*
X219161D03*
X221524D03*
X223886D03*
X226248D03*
X228610D03*
X230972D03*
X233335Y32756D03*
X235697D03*
X238059D03*
X240421D03*
X242783D03*
X245146D03*
X233335Y44370D03*
X235697D03*
X238059D03*
X240421D03*
X242783D03*
X245146D03*
X247508Y32756D03*
X249870D03*
X252232D03*
X254594D03*
X256957D03*
X259319D03*
X247508Y44370D03*
X249870D03*
X252232D03*
X254594D03*
X256957D03*
X259319D03*
X276622Y32756D03*
X278984D03*
X281346D03*
X283709D03*
X286071D03*
X288433D03*
X290795D03*
X276622Y44370D03*
X278984D03*
X281346D03*
X283709D03*
X286071D03*
X288433D03*
X290795D03*
X293157Y32756D03*
X295520D03*
X297882D03*
X300244D03*
X302606D03*
X304968D03*
X293157Y44370D03*
X295520D03*
X297882D03*
X300244D03*
X302606D03*
X304968D03*
X307331Y32756D03*
Y44370D03*
X510815Y53543D03*
X513177D03*
X510815Y65157D03*
X513177D03*
X515539Y53543D03*
X517902D03*
X520264D03*
X522626D03*
X524988D03*
X527350D03*
X515539Y65157D03*
X517902D03*
X520264D03*
X522626D03*
X524988D03*
X527350D03*
X529713Y53543D03*
X532075D03*
X534437D03*
X536799D03*
X539161D03*
X541524D03*
X543886D03*
X529713Y65157D03*
X532075D03*
X534437D03*
X536799D03*
X539161D03*
X541524D03*
X543886D03*
X546248Y53543D03*
X548610D03*
X550972D03*
X553335D03*
X555697D03*
X558059D03*
X546248Y65157D03*
X548610D03*
X550972D03*
X553335D03*
X555697D03*
X558059D03*
X560421Y53543D03*
X562784D03*
X565146D03*
X567508D03*
X569870D03*
X572232D03*
X560421Y65157D03*
X562784D03*
X565146D03*
X567508D03*
X569870D03*
X572232D03*
X574595Y53543D03*
Y65157D03*
X593925Y53543D03*
X596287D03*
X598650D03*
X601012D03*
X603374D03*
X593925Y65157D03*
X596287D03*
X598650D03*
X601012D03*
X603374D03*
X605736Y53543D03*
X608098D03*
X610461D03*
X612823D03*
X615185D03*
X617547D03*
X605736Y65157D03*
X608098D03*
X610461D03*
X612823D03*
X615185D03*
X617547D03*
X619910Y53543D03*
X622272D03*
X624634D03*
X619910Y65157D03*
X622272D03*
X624634D03*
X640421Y53543D03*
X642784D03*
X645146D03*
X647508D03*
X640421Y65157D03*
X642784D03*
X645146D03*
X647508D03*
X649870Y53543D03*
X652232D03*
X654595D03*
X656957D03*
X659319D03*
X661681D03*
X649870Y65157D03*
X652232D03*
X654595D03*
X656957D03*
X659319D03*
X661681D03*
X664043Y53543D03*
X666406D03*
X668768D03*
X671130D03*
X673492D03*
X675854D03*
X678217D03*
X664043Y65157D03*
X666406D03*
X668768D03*
X671130D03*
X673492D03*
X675854D03*
X678217D03*
X680579Y53543D03*
X682941D03*
X685303D03*
X687665D03*
X690028D03*
X692390D03*
X680579Y65157D03*
X682941D03*
X685303D03*
X687665D03*
X690028D03*
X692390D03*
X694752Y53543D03*
X697114D03*
X699476D03*
X701839D03*
X704201D03*
X694752Y65157D03*
X697114D03*
X699476D03*
X701839D03*
X704201D03*
X721504Y53543D03*
Y65157D03*
X723866Y53543D03*
X726228D03*
X728591D03*
X730953D03*
X733315D03*
X735677D03*
X738039D03*
X723866Y65157D03*
X726228D03*
X728591D03*
X730953D03*
X733315D03*
X735677D03*
X738039D03*
X740402Y53543D03*
X742764D03*
X745126D03*
X747488D03*
X749850D03*
X752213D03*
X740402Y65157D03*
X742764D03*
X745126D03*
X747488D03*
X749850D03*
X752213D03*
X1540342Y32756D03*
X1542704D03*
X1540342Y44370D03*
X1542704D03*
X1545066Y32756D03*
X1547429D03*
X1549791D03*
X1552153D03*
X1554515D03*
X1556877D03*
X1545066Y44370D03*
X1547429D03*
X1549791D03*
X1552153D03*
X1554515D03*
X1556877D03*
X1559240Y32756D03*
X1561602D03*
X1563964D03*
X1566326D03*
X1568688D03*
X1571051D03*
X1559240Y44370D03*
X1561602D03*
X1563964D03*
X1566326D03*
X1568688D03*
X1571051D03*
X1573413Y32756D03*
X1575775D03*
X1578137D03*
X1580499D03*
X1582862D03*
X1585224D03*
X1587586D03*
X1573413Y44370D03*
X1575775D03*
X1578137D03*
X1580499D03*
X1582862D03*
X1585224D03*
X1587586D03*
X1589948Y32756D03*
X1592311D03*
X1594673D03*
X1597035D03*
X1599397D03*
X1601759D03*
X1589948Y44370D03*
X1592311D03*
X1594673D03*
X1597035D03*
X1599397D03*
X1601759D03*
X1604122Y32756D03*
Y44370D03*
X1623452Y32756D03*
X1625814D03*
X1628177D03*
X1630539D03*
X1623452Y44370D03*
X1625814D03*
X1628177D03*
X1630539D03*
X1632901Y32756D03*
X1635263D03*
X1637625D03*
X1639988D03*
X1642350D03*
X1644712D03*
X1647074D03*
X1632901Y44370D03*
X1635263D03*
X1637625D03*
X1639988D03*
X1642350D03*
X1644712D03*
X1647074D03*
X1649437Y32756D03*
X1651799D03*
X1654161D03*
X1649437Y44370D03*
X1651799D03*
X1654161D03*
X1669948Y32756D03*
X1672311D03*
X1674673D03*
X1677035D03*
X1669948Y44370D03*
X1672311D03*
X1674673D03*
X1677035D03*
X1679397Y32756D03*
X1681759D03*
X1684122D03*
X1686484D03*
X1688846D03*
X1691208D03*
X1679397Y44370D03*
X1681759D03*
X1684122D03*
X1686484D03*
X1688846D03*
X1691208D03*
X1693570Y32756D03*
X1695933D03*
X1698295D03*
X1700657D03*
X1703019D03*
X1705381D03*
X1693570Y44370D03*
X1695933D03*
X1698295D03*
X1700657D03*
X1703019D03*
X1705381D03*
X1707744Y32756D03*
X1710106D03*
X1712468D03*
X1714830D03*
X1717192D03*
X1719555D03*
X1721917D03*
X1707744Y44370D03*
X1710106D03*
X1712468D03*
X1714830D03*
X1717192D03*
X1719555D03*
X1721917D03*
X1724279Y32756D03*
X1726641D03*
X1729003D03*
X1731366D03*
X1733728D03*
X1724279Y44370D03*
X1726641D03*
X1729003D03*
X1731366D03*
X1733728D03*
X1751031Y32756D03*
Y44370D03*
X1753393Y32756D03*
X1755755D03*
X1758118D03*
X1760480D03*
X1762842D03*
X1765204D03*
X1753393Y44370D03*
X1755755D03*
X1758118D03*
X1760480D03*
X1762842D03*
X1765204D03*
X1767566Y32756D03*
X1769929D03*
X1772291D03*
X1774653D03*
X1777015D03*
X1779377D03*
X1781740D03*
X1767566Y44370D03*
X1769929D03*
X1772291D03*
X1774653D03*
X1777015D03*
X1779377D03*
X1781740D03*
G54D227*
X702806Y588934D03*
X700246D03*
Y606060D03*
X702806D03*
G54D209*
X572297Y152080D03*
Y154640D03*
X589423D03*
Y152080D03*
X842562Y170918D03*
Y173478D03*
X859688D03*
Y170918D03*
X1594537Y298182D03*
Y300742D03*
X1611663Y298182D03*
Y300742D03*
G54D17*
X23031Y197224D03*
Y202224D03*
Y207224D03*
Y212224D03*
X39173Y197224D03*
Y202224D03*
Y207224D03*
Y212224D03*
X105975Y197241D03*
Y202241D03*
Y207241D03*
Y212241D03*
X122117Y197241D03*
Y202241D03*
Y207241D03*
Y212241D03*
X1255315Y236594D03*
Y241594D03*
Y246594D03*
Y251594D03*
X1271457Y236594D03*
Y241594D03*
Y246594D03*
Y251594D03*
X1341535Y236594D03*
Y251594D03*
Y246594D03*
Y241594D03*
X1357677Y236594D03*
Y251594D03*
Y246594D03*
Y241594D03*
G54D164*
X389743Y482395D03*
X387184D03*
X384625D03*
Y491057D03*
X387184D03*
X389743D03*
G54D236*
X711269Y1643326D03*
Y1666358D03*
X740205Y1643326D03*
Y1666358D03*
G54D317*
X1766929Y1714960D03*
G54D80*
X110770Y1662719D03*
X107620D03*
X110770D03*
X110775Y1657752D03*
D03*
X107625D03*
X113920Y1662719D03*
X113925Y1657752D03*
X134902Y671290D03*
X131752D03*
X138052D03*
X134902D03*
Y683290D03*
X131752D03*
X138052D03*
X134902D03*
X155710Y1679384D03*
X152560D03*
X155710D03*
Y1674239D03*
X152560D03*
X155710D03*
X169575Y670500D03*
D03*
X166425D03*
X169575Y676500D03*
D03*
X166425D03*
X158860Y1679384D03*
Y1674239D03*
X172725Y670500D03*
Y676500D03*
X235147Y127118D03*
X238297D03*
X273474Y1512220D03*
Y1516120D03*
X276624D03*
X279774D03*
X276624Y1512220D03*
Y1516120D03*
Y1512220D03*
X279774D03*
X404686Y1516120D03*
X407836D03*
X404686Y1512220D03*
X407836D03*
X401536D03*
X404686D03*
X401536Y1516120D03*
X404686D03*
X484080Y144392D03*
Y139492D03*
D03*
X480930D03*
X484080Y144392D03*
X480930D03*
X492080Y128942D03*
X495230D03*
X492080Y133942D03*
X495230D03*
X492080Y128942D03*
X488930D03*
X492080Y133942D03*
X488930D03*
X487230Y144392D03*
Y139492D03*
X540797Y1516120D03*
X543947D03*
X537647Y1512220D03*
X540797D03*
D03*
X543947D03*
X537647Y1516120D03*
X540797D03*
X573360Y122785D03*
X565210D03*
X568360D03*
X576510D03*
X672715Y1530526D03*
X675865D03*
X672715Y1526626D03*
X675865D03*
X669565Y1530526D03*
X672715D03*
X669565Y1526626D03*
X672715D03*
X1013620Y230423D03*
X1016770D03*
X1168957Y575602D03*
X1165807D03*
X1168957D03*
X1169000Y592673D03*
X1165850D03*
X1169000D03*
X1172107Y575602D03*
X1172150Y592673D03*
X1228118Y132739D03*
D03*
X1224968D03*
X1228118Y128239D03*
D03*
X1224968D03*
X1231268Y132739D03*
Y128239D03*
X1269437Y166051D03*
X1272587D03*
D03*
X1269437Y162051D03*
X1272587D03*
D03*
Y158051D03*
X1269437D03*
X1272587D03*
Y180565D03*
X1269437D03*
X1272587D03*
Y176051D03*
X1269437D03*
X1272587D03*
X1269437Y171551D03*
X1272587D03*
D03*
X1269437Y184987D03*
X1272587D03*
D03*
X1275737Y166051D03*
Y162051D03*
Y158051D03*
Y180565D03*
Y176051D03*
Y171551D03*
Y184987D03*
X1284497Y1549120D03*
X1287647D03*
X1281347D03*
X1284497D03*
X1281347Y1545220D03*
X1284497D03*
D03*
X1287647D03*
X1412559Y1549120D03*
X1415709D03*
X1409409D03*
X1412559D03*
X1409409Y1545220D03*
X1412559D03*
D03*
X1415709D03*
X1548671Y1549120D03*
X1551821D03*
X1548671Y1545220D03*
X1551821D03*
X1545521D03*
X1548671D03*
X1545521Y1549120D03*
X1548671D03*
X1677439Y1559626D03*
Y1563526D03*
X1680589D03*
X1683739D03*
X1680589Y1559626D03*
Y1563526D03*
Y1559626D03*
X1683739D03*
G54D35*
X44967Y416860D03*
D03*
Y413710D03*
X50339Y416945D03*
Y413795D03*
Y416945D03*
X44967Y420010D03*
X50339Y420095D03*
X60189Y417070D03*
Y413920D03*
X65533Y414040D03*
Y410890D03*
Y417190D03*
Y414040D03*
X60189Y413920D03*
Y410770D03*
X238297Y123968D03*
Y127118D03*
X556280Y119790D03*
X551280D03*
X556280Y126090D03*
Y122940D03*
X551280Y126090D03*
Y122940D03*
X556280D03*
X551280D03*
X568360Y119635D03*
X573360D03*
X568360Y122785D03*
X573360D03*
X568360Y125935D03*
Y122785D03*
X573360Y125935D03*
Y122785D03*
X714129Y664242D03*
Y667392D03*
Y661092D03*
Y664242D03*
X726201Y664244D03*
Y667394D03*
Y661094D03*
Y664244D03*
X1016770Y233573D03*
Y230423D03*
X1256785Y754715D03*
Y757865D03*
D03*
Y761015D03*
X1263706Y754715D03*
Y757865D03*
D03*
Y761015D03*
X1713000Y654925D03*
Y651775D03*
Y658075D03*
Y654925D03*
Y670425D03*
Y673575D03*
Y676725D03*
Y673575D03*
G54D326*
X1787234Y709079D03*
G54D62*
X64462Y1658400D03*
X66430D03*
X62493D03*
X60525D03*
X64462Y1673360D03*
X62493D03*
X60525D03*
X66430D03*
X68399Y1658400D03*
X70367D03*
X68399Y1673360D03*
X70367D03*
G54D137*
X276088Y605247D03*
G54D191*
X475251Y299219D03*
X562251Y308219D03*
G54D245*
X778687Y1573504D03*
Y1591222D03*
X792467Y1573504D03*
Y1591222D03*
X820687Y1573504D03*
Y1591222D03*
X834467Y1573504D03*
Y1591222D03*
X862687Y1573504D03*
Y1591222D03*
X876467Y1573504D03*
Y1591222D03*
X904687Y1573504D03*
Y1591222D03*
X918467Y1573504D03*
Y1591222D03*
G54D173*
X426767Y109243D03*
Y111212D03*
Y113180D03*
Y115149D03*
Y117117D03*
Y119086D03*
Y121054D03*
Y123023D03*
Y124991D03*
Y126960D03*
Y128928D03*
Y130897D03*
Y132865D03*
Y134834D03*
Y136802D03*
Y138771D03*
X461413Y121054D03*
Y119086D03*
Y117117D03*
Y115149D03*
Y113180D03*
Y111212D03*
Y109243D03*
Y134834D03*
Y132865D03*
Y130897D03*
Y128928D03*
Y126960D03*
Y124991D03*
Y123023D03*
Y138771D03*
Y136802D03*
G54D254*
X796079Y1334469D03*
G54D281*
X961084Y1547766D03*
Y1553882D03*
X992696Y1547782D03*
Y1553898D03*
X1024296Y1547782D03*
Y1553898D03*
X1055896Y1547782D03*
Y1553898D03*
X1091434Y1542225D03*
Y1559343D03*
G54D26*
X36882Y282916D03*
Y277798D03*
X35017Y288500D03*
X36882Y312916D03*
Y307798D03*
X31329Y517025D03*
X31613Y1497914D03*
Y1502214D03*
X35444Y1668587D03*
Y1663587D03*
X51017Y303500D03*
X44017D03*
X38150Y1622896D03*
Y1626896D03*
X59742Y268223D03*
X59872Y280357D03*
Y276357D03*
Y272357D03*
X64517Y290000D03*
X59872Y310357D03*
X65625Y423746D03*
X61713Y1552869D03*
X82118Y140950D03*
X74271Y157191D03*
Y161191D03*
Y165191D03*
X81891Y386502D03*
X81908Y376026D03*
X72150Y521613D03*
Y525513D03*
Y543213D03*
Y539313D03*
X78713Y1549369D03*
X87072Y1307499D03*
X87092Y1311619D03*
X96017Y1412500D03*
Y1408000D03*
Y1417000D03*
Y1421500D03*
Y1444500D03*
X87017Y1440000D03*
Y1444500D03*
X96017Y1448500D03*
X87017D03*
X95528Y1552796D03*
X84000Y1663138D03*
X83959Y1667127D03*
X85437Y1698511D03*
Y1702511D03*
X85274Y1724331D03*
Y1720331D03*
X101771Y153691D03*
Y158191D03*
X105982Y1385562D03*
X107017Y1414500D03*
X104610Y1597797D03*
X112870Y1670313D03*
Y1674313D03*
X114517Y1712450D03*
X141509Y526997D03*
X134994Y679290D03*
Y675290D03*
X127434Y1382305D03*
X138582Y1385562D03*
X129585Y1709346D03*
X136835Y1709166D03*
X139784Y1718241D03*
X145017Y1433500D03*
Y1429500D03*
Y1437500D03*
X149870Y1670087D03*
X143870Y1682587D03*
X168377Y400560D03*
X160134Y1382305D03*
X171282Y1385562D03*
X172017Y1715000D03*
X162832Y1726500D03*
X172017Y1721000D03*
X174617Y412350D03*
X192937Y144962D03*
X194017Y149000D03*
X194517Y156500D03*
X193034Y1382305D03*
X204182Y1385562D03*
X210590Y1419187D03*
X206017Y1707000D03*
X206332Y1723000D03*
X220997Y120662D03*
Y124662D03*
X222369Y148750D03*
X218017Y156500D03*
X224537Y206820D03*
X229150Y571129D03*
X225834Y1382305D03*
X242237Y71862D03*
X232803Y711602D03*
X236982Y1385562D03*
X247314Y111743D03*
X256678Y140882D03*
X259828Y144882D03*
X260227Y207660D03*
X247557Y224370D03*
X248144Y640909D03*
X271973Y74536D03*
X273784Y99183D03*
X267067Y142892D03*
X267070Y159203D03*
Y155203D03*
X270017Y215000D03*
X262017Y221500D03*
X267936Y611172D03*
X262108Y644555D03*
X271515Y676901D03*
X270582Y1339416D03*
X276917Y136962D03*
X277017Y207000D03*
Y211000D03*
X283808Y570398D03*
X276918Y585178D03*
X282374Y674150D03*
X295464Y75673D03*
X298183Y71128D03*
X296570Y156203D03*
Y151703D03*
X294838Y678796D03*
X304245Y711142D03*
X292330Y1336131D03*
X303478Y1339388D03*
X317074Y91803D03*
X316017Y263000D03*
X314160Y694525D03*
X322559Y69863D03*
X334431Y165170D03*
X325908Y545521D03*
X328746Y566086D03*
X327608Y698946D03*
X325234Y1336074D03*
X343233Y225070D03*
X339017Y285000D03*
X337015Y731292D03*
X336382Y1339331D03*
X363713Y130165D03*
X352432Y215325D03*
X365832Y211361D03*
Y219361D03*
X352450Y211407D03*
X365832Y215361D03*
X358017Y307500D03*
X356124Y550415D03*
X353674Y562415D03*
Y566415D03*
Y570415D03*
Y574415D03*
X364649Y617438D03*
X360668Y698678D03*
X358034Y1336274D03*
X370980Y158028D03*
X373562Y225145D03*
Y228645D03*
X374072Y243615D03*
X370075Y731024D03*
X369182Y1339531D03*
X371279Y1387697D03*
X386510Y142937D03*
X392813Y138980D03*
X381105Y280370D03*
Y294370D03*
X391517Y311500D03*
X394017Y304000D03*
X393708Y698746D03*
X395923Y134980D03*
X405658Y148300D03*
X399888Y551915D03*
X403115Y731092D03*
X401764Y1358862D03*
X404523Y1631219D03*
X409017Y1637000D03*
X406017Y1645500D03*
Y1653500D03*
X419510Y59935D03*
X419354Y71665D03*
Y66865D03*
X420318Y99148D03*
X416768Y104148D03*
X412658Y144300D03*
Y148300D03*
X414457Y235442D03*
X415232Y250165D03*
Y258165D03*
Y266165D03*
X415683Y1006123D03*
Y1009864D03*
X425133Y1014766D03*
X415683Y1013604D03*
Y1028564D03*
X425115Y1018879D03*
X415683Y1021084D03*
Y1024824D03*
Y1017344D03*
X425115Y1023013D03*
X414017Y1657500D03*
X426708Y680946D03*
X436115Y713292D03*
X434962Y1014745D03*
X434958Y1018879D03*
Y1023013D03*
X438517Y1604200D03*
Y1600200D03*
X449422Y270911D03*
X443816Y1014745D03*
X454052D03*
X443816Y1018879D03*
X454052D03*
X443816Y1023013D03*
X454052D03*
X442017Y1622700D03*
Y1618700D03*
X462745Y70016D03*
X465913Y239764D03*
Y227764D03*
Y231764D03*
Y247764D03*
X459108Y656346D03*
X468515Y688692D03*
X465017Y1668000D03*
Y1659500D03*
X470017Y1680000D03*
X465017Y1676000D03*
X465517Y1697000D03*
X472370Y60029D03*
X472300Y55135D03*
X472370Y64975D03*
X473642Y90574D03*
Y105574D03*
Y100574D03*
Y95574D03*
X473707Y119644D03*
Y115644D03*
X473642Y110574D03*
X473707Y123644D03*
X483270Y206827D03*
X473445Y284738D03*
Y280858D03*
X481982Y578572D03*
X472517Y1655500D03*
Y1672000D03*
Y1701000D03*
Y1706500D03*
Y1714500D03*
X490014Y171625D03*
X489199Y193516D03*
Y189516D03*
X497749Y193516D03*
Y185516D03*
Y189516D03*
X486201Y233000D03*
X494551Y238119D03*
X491708Y629846D03*
X506024Y185516D03*
X501293Y205285D03*
X508293Y202404D03*
X501115Y662192D03*
X526517Y432500D03*
X525008Y595746D03*
X541713Y195256D03*
X543505Y218441D03*
Y230441D03*
Y239566D03*
X536517Y445500D03*
X534415Y628092D03*
X544254Y663689D03*
X551353Y152742D03*
X556095Y193541D03*
X553190Y399586D03*
Y414274D03*
Y423949D03*
X550517Y451000D03*
X559017Y477500D03*
X571253Y235821D03*
X560445Y293738D03*
Y289858D03*
X560517Y451000D03*
X572017Y462000D03*
Y466000D03*
X570017Y471500D03*
Y475500D03*
X583720Y164356D03*
Y169415D03*
X575554Y193516D03*
X575569Y197481D03*
X578041Y261171D03*
X583140Y411846D03*
Y423949D03*
Y435949D03*
X583723Y454242D03*
X577017Y475500D03*
Y479500D03*
X600284Y136408D03*
X600287Y132270D03*
X600286Y141640D03*
X591040Y208991D03*
X591046Y221277D03*
Y217277D03*
Y225277D03*
Y229277D03*
X590327Y400287D03*
Y404287D03*
X603017Y412000D03*
X590644Y458461D03*
X590723Y454242D03*
X590520Y468893D03*
X590538Y479631D03*
X594017Y493500D03*
X600288Y1266598D03*
Y1262598D03*
X612017Y440000D03*
X620546Y221777D03*
Y226277D03*
X629938Y474020D03*
X627419Y1357114D03*
X619376Y1367166D03*
X619294Y1386732D03*
X646331Y166053D03*
Y161862D03*
X646383Y174201D03*
X646331Y170053D03*
X643178Y473905D03*
X648917Y1728000D03*
Y1717138D03*
X641917Y1728000D03*
Y1722138D03*
Y1717138D03*
X648917Y1722138D03*
X641917Y1733000D03*
X648917D03*
X652517Y390000D03*
X656457Y461818D03*
X656440Y457755D03*
X661472Y486941D03*
X650582D03*
X661334Y495126D03*
X655753Y1371199D03*
X655685Y1378931D03*
X655719Y1375061D03*
X653317Y1698400D03*
X662517Y1708184D03*
X653317Y1712084D03*
X672562Y401567D03*
Y409320D03*
Y405488D03*
X672517Y457862D03*
Y453862D03*
Y461862D03*
Y477862D03*
Y465862D03*
X672433Y474268D03*
X672517Y482862D03*
X666803Y504895D03*
X674803D03*
X665517Y529500D03*
X671117Y1308002D03*
X677810Y1639704D03*
Y1643904D03*
X680470Y115868D03*
X680294Y1530526D03*
Y1526526D03*
X706940Y103308D03*
X702157Y1560573D03*
X702127Y1580523D03*
X702017Y1608500D03*
Y1600500D03*
X702658Y1616656D03*
X696934Y1670408D03*
X696972Y1674429D03*
X696856Y1678474D03*
X710217Y157762D03*
X730010Y90998D03*
X730040Y95158D03*
X735172Y1400414D03*
X725378Y1614743D03*
X751650Y111288D03*
X745752Y142050D03*
X748217Y167537D03*
X752127Y1576023D03*
Y1589023D03*
Y1584023D03*
X757135Y89348D03*
X756784Y276322D03*
X763760Y299279D03*
X763167Y1591733D03*
X757179Y1693369D03*
X774806Y158026D03*
X774820Y153728D03*
X777560Y299279D03*
X779017Y371000D03*
Y364000D03*
X772017D03*
X775186Y419464D03*
X775169Y455344D03*
Y463344D03*
Y459344D03*
Y476344D03*
Y472344D03*
Y487344D03*
Y491344D03*
Y499344D03*
Y495344D03*
X788283Y267822D03*
Y281822D03*
X789619Y415344D03*
X789517Y407500D03*
X789669Y439344D03*
Y451344D03*
Y463344D03*
Y459344D03*
Y455344D03*
Y471344D03*
X789838Y467646D03*
X790179Y483458D03*
X790396Y479511D03*
X790017Y507000D03*
X792363Y1328662D03*
X805576Y386791D03*
X805583Y381020D03*
Y376753D03*
X798517Y392500D03*
X806592Y422687D03*
X806403Y431344D03*
X806319Y463578D03*
X806231Y449802D03*
X806450Y471344D03*
X806563Y476159D03*
X806450Y487344D03*
X806519Y491344D03*
X806563Y480159D03*
X806517Y504000D03*
X806636Y495344D03*
X806517Y512000D03*
Y516000D03*
X808517Y534500D03*
X808225Y541448D03*
X804381Y1340762D03*
Y1336334D03*
X799517Y1330000D03*
X804788Y1351988D03*
X807928Y1364193D03*
X804667Y1574633D03*
Y1590633D03*
Y1598633D03*
Y1606633D03*
X820936Y415344D03*
Y419344D03*
X827200Y405347D03*
X820928Y423099D03*
X820936Y455344D03*
X820875Y463578D03*
Y471344D03*
Y467568D03*
X827685Y497912D03*
X831479Y58632D03*
X828237Y166862D03*
Y176362D03*
X836017Y393000D03*
X832017Y471000D03*
X840718Y490567D03*
X840754Y486478D03*
X840717Y482128D03*
X840603Y494661D03*
X848837Y162762D03*
X856320Y269057D03*
X856350Y273217D03*
X856238Y384030D03*
X846274Y507106D03*
X853036Y494585D03*
X852842Y503154D03*
X853108Y498861D03*
X846667Y1574633D03*
Y1590633D03*
Y1598633D03*
Y1606633D03*
X871237Y166362D03*
X859017Y395500D03*
X868537Y418720D03*
X879237Y171362D03*
Y176862D03*
X881242Y187449D03*
X881232Y183169D03*
X883945Y267407D03*
X877932Y289439D03*
X885017Y326000D03*
X885999Y1056033D03*
X902298Y606915D03*
X888667Y1574633D03*
Y1590633D03*
Y1598633D03*
Y1606633D03*
X916973Y570706D03*
X930667Y1582233D03*
Y1578233D03*
Y1586233D03*
X945060Y585200D03*
X945748Y614150D03*
X944573Y628662D03*
X958142Y198171D03*
X958994Y1498695D03*
X981641Y189347D03*
X984972Y260781D03*
Y271443D03*
X984601Y295641D03*
X988573Y516014D03*
Y521014D03*
Y526074D03*
Y531074D03*
X982360Y1498695D03*
X994429Y221233D03*
Y225233D03*
X1000851Y446175D03*
Y457175D03*
Y451675D03*
Y462675D03*
Y468175D03*
Y479175D03*
Y473675D03*
Y494175D03*
Y490175D03*
Y484675D03*
Y499675D03*
X1005726Y1498695D03*
X1009827Y153868D03*
X1013737Y198999D03*
X1013712Y207423D03*
X1013637Y203099D03*
X1013712Y214423D03*
Y222423D03*
Y218423D03*
Y226423D03*
X1015351Y287311D03*
Y298311D03*
X1021476Y397726D03*
X1007219Y433426D03*
X1014074Y420902D03*
X1011281Y484155D03*
X1008723Y510304D03*
X1013017Y560500D03*
X1021517Y566000D03*
X1029092Y1498695D03*
X1042619Y1646205D03*
X1042487Y1652082D03*
X1055034Y406560D03*
X1065763Y445499D03*
X1065813Y457959D03*
X1065781Y453655D03*
Y449655D03*
X1065811Y462525D03*
Y467000D03*
Y471500D03*
X1055997Y490037D03*
X1065781Y479655D03*
X1057663Y1311203D03*
Y1307203D03*
X1052458Y1498695D03*
X1074727Y457959D03*
X1077720Y1385543D03*
X1075824Y1498695D03*
X1090455Y446105D03*
Y440605D03*
Y462605D03*
Y457105D03*
Y451605D03*
Y468105D03*
X1083455Y472105D03*
X1090455Y489641D03*
Y484605D03*
Y494641D03*
X1091356Y1633726D03*
X1091398Y1629945D03*
X1098965Y479355D03*
X1099172Y1382286D03*
X1110320Y1385543D03*
X1099190Y1498695D03*
X1099540Y1634400D03*
X1099733Y1630123D03*
X1099017Y1639000D03*
X1124426Y398020D03*
X1126750Y52651D03*
X1133923Y52599D03*
X1133155Y56512D03*
X1133422Y380533D03*
Y385698D03*
X1131872Y1382286D03*
X1147335Y74738D03*
X1152210Y204835D03*
Y209835D03*
X1144755Y489819D03*
X1143020Y1385543D03*
X1147400Y1436579D03*
X1157655Y461691D03*
Y457691D03*
Y449691D03*
Y453691D03*
Y465691D03*
Y469691D03*
Y481691D03*
X1169049Y580602D03*
X1169109Y584622D03*
X1164772Y1382286D03*
X1171946Y89556D03*
Y93556D03*
X1179708Y95864D03*
X1175920Y1385543D03*
X1181117Y1433000D03*
X1192804Y61515D03*
X1192904Y57015D03*
X1192824Y52815D03*
X1186005Y87125D03*
Y91125D03*
X1192219Y164987D03*
Y160987D03*
X1188444Y436202D03*
Y444202D03*
X1199944Y460202D03*
X1188444Y452202D03*
X1200004Y465272D03*
X1200080Y470376D03*
X1197632Y1382088D03*
X1197017Y1396500D03*
Y1401000D03*
Y1410000D03*
Y1405500D03*
Y1424000D03*
X1188117Y1428500D03*
Y1433000D03*
X1197017Y1437500D03*
Y1447500D03*
Y1442500D03*
X1189872Y1673050D03*
X1189554Y1697850D03*
X1196554D03*
X1210098Y94846D03*
X1202273Y133866D03*
Y128748D03*
X1202529Y177187D03*
Y181187D03*
X1202560Y188942D03*
X1208720Y1385543D03*
X1208017Y1401000D03*
X1205214Y1673059D03*
X1204896Y1697859D03*
X1211896D03*
X1241710Y145239D03*
X1236971Y447255D03*
Y443255D03*
X1241834Y1418462D03*
X1241876Y1422362D03*
X1258124Y155730D03*
Y164051D03*
Y160051D03*
Y176051D03*
Y180551D03*
Y168051D03*
Y172051D03*
Y185051D03*
X1254964Y464372D03*
X1245844Y468152D03*
X1256017Y765000D03*
X1246711Y1339397D03*
X1272628Y150030D03*
X1270566Y390884D03*
X1262517Y390500D03*
X1262719Y411125D03*
Y407125D03*
Y415125D03*
X1268459Y1336112D03*
X1286624Y162051D03*
Y166051D03*
Y171551D03*
Y184051D03*
X1279607Y1339369D03*
X1281617Y1430000D03*
Y1434000D03*
X1295210Y133739D03*
Y125739D03*
Y129739D03*
Y145739D03*
X1290219Y403625D03*
Y408125D03*
X1304159Y537299D03*
X1293273Y552147D03*
X1304275Y556545D03*
X1291883Y597013D03*
X1301363Y1336055D03*
X1312511Y1339312D03*
X1334163Y1336255D03*
X1343277Y674443D03*
X1345311Y1339512D03*
X1368201Y100509D03*
X1372660Y613889D03*
X1366923Y1355715D03*
X1377893Y1358843D03*
X1382067Y646235D03*
X1391825Y1009863D03*
Y1013603D03*
Y1006122D03*
Y1017343D03*
Y1028563D03*
Y1024823D03*
Y1021083D03*
X1389010Y1670391D03*
X1382010Y1674391D03*
X1384562Y1704038D03*
X1382321Y1733118D03*
X1396774Y642765D03*
X1405360Y646789D03*
X1401257Y1014744D03*
Y1018878D03*
Y1023012D03*
X1405150Y1622167D03*
X1398150Y1626167D03*
X1402000Y1630167D03*
X1414767Y679135D03*
X1419958Y1014744D03*
X1411104D03*
X1419958Y1023012D03*
X1411100Y1018878D03*
X1419958D03*
X1411100Y1023012D03*
X1423814Y1619504D03*
Y1613966D03*
X1418832Y1642967D03*
X1432136Y244450D03*
X1430774Y675765D03*
X1437960Y679369D03*
X1430194Y1014744D03*
Y1023012D03*
Y1018878D03*
X1432826Y1609966D03*
X1433014Y1619566D03*
X1445136Y244450D03*
X1447367Y711715D03*
X1464922Y61563D03*
X1455759Y128242D03*
X1466774Y548977D03*
Y552977D03*
Y544977D03*
X1458774Y564977D03*
X1466774Y556977D03*
Y560977D03*
Y564977D03*
X1462274Y695265D03*
X1471922Y61563D03*
X1470878Y698946D03*
X1480285Y731292D03*
X1510774Y543977D03*
X1503960Y698946D03*
X1513367Y731292D03*
X1523836Y201250D03*
X1539034Y300816D03*
Y308816D03*
Y304816D03*
X1536760Y698946D03*
X1546881Y284575D03*
X1546167Y731292D03*
X1547191Y1266271D03*
X1547194Y1282188D03*
Y1278188D03*
Y1286188D03*
X1566534Y297316D03*
Y301816D03*
X1570160Y531220D03*
X1569890Y677006D03*
X1562005Y1273445D03*
X1579297Y709352D03*
X1581789Y1302278D03*
X1595970Y225250D03*
X1602660Y643237D03*
X1615826Y530739D03*
X1610636Y542733D03*
X1612067Y675583D03*
X1622459Y282728D03*
Y278520D03*
X1622426Y286742D03*
X1629766Y1420450D03*
X1629684Y1444016D03*
Y1440016D03*
X1642705Y627206D03*
X1635660Y624237D03*
X1645067Y656583D03*
X1634850Y1306874D03*
X1638007Y1410398D03*
X1639684Y1442228D03*
X1655042Y141762D03*
Y146762D03*
Y151762D03*
Y161762D03*
X1656683Y696318D03*
X1666273Y1432215D03*
X1666307Y1428345D03*
X1666341Y1424483D03*
X1666359Y1420567D03*
X1682905Y1399703D03*
X1688168Y1559526D03*
Y1563526D03*
X1692044Y1696422D03*
X1701811Y373773D03*
Y369773D03*
X1699901Y401485D03*
X1722435Y112867D03*
X1714707Y364962D03*
X1709851Y666238D03*
Y662238D03*
X1736826Y85339D03*
X1730096Y1530950D03*
Y1535250D03*
X1735446Y1649456D03*
X1726980Y1663465D03*
Y1667965D03*
Y1658965D03*
Y1672465D03*
X1748905Y100307D03*
X1746127Y305106D03*
X1751237Y372452D03*
X1740014Y1435005D03*
X1748996Y1585905D03*
X1738980Y1653965D03*
X1760585Y76797D03*
X1760555Y72637D03*
X1753453Y85407D03*
X1765996Y1582405D03*
X1778592Y190799D03*
X1768445Y1666984D03*
X1768406Y1670514D03*
X1767980Y1685465D03*
X1768325Y1674057D03*
X1767980Y1681702D03*
Y1678172D03*
Y1689965D03*
X1787680Y70987D03*
X1782195Y92927D03*
X1789907Y146834D03*
Y151834D03*
Y165834D03*
X1792288Y367866D03*
X1784816Y403932D03*
X1792288Y390411D03*
X1784816Y410432D03*
Y418932D03*
Y425432D03*
X1782811Y1585832D03*
X1822097Y147834D03*
X1815097Y151834D03*
X1817249Y371329D03*
X1824249D03*
Y367359D03*
X1823186Y383952D03*
Y379552D03*
X1817086Y395552D03*
X1816316Y407932D03*
X1815816Y421432D03*
Y427432D03*
X1815809Y431678D03*
X1844808Y161834D03*
G54D146*
X304992Y880671D03*
Y887049D03*
Y893427D03*
Y899805D03*
Y906182D03*
Y912560D03*
Y918938D03*
Y925316D03*
Y931694D03*
Y938072D03*
Y944450D03*
Y950828D03*
Y957206D03*
Y963584D03*
Y969962D03*
Y976340D03*
Y982718D03*
Y989096D03*
Y995474D03*
Y1001852D03*
Y1008230D03*
X319795Y874293D03*
X316094D03*
X312393D03*
X317944Y877482D03*
X314244D03*
X310543D03*
X319795Y880671D03*
X316094D03*
X312393D03*
X308693D03*
X317944Y883860D03*
X314244D03*
X310543D03*
X306842D03*
X319795Y887049D03*
X316094D03*
X312393D03*
X308693D03*
X317944Y890238D03*
X314244D03*
X310543D03*
X306842D03*
X319795Y893427D03*
X316094D03*
X312393D03*
X308693D03*
X317944Y896616D03*
X314244D03*
X310543D03*
X306842D03*
X319795Y899805D03*
X316094D03*
X312393D03*
X308693D03*
X317944Y902994D03*
X314244D03*
X310543D03*
X306842D03*
X319795Y906182D03*
X316094D03*
X312393D03*
X308693D03*
X317944Y909371D03*
X314244D03*
X310543D03*
X306842D03*
X319795Y912560D03*
X316094D03*
X312393D03*
X308693D03*
X317944Y915749D03*
X314244D03*
X310543D03*
X306842D03*
X319795Y918938D03*
X316094D03*
X312393D03*
X308693D03*
X317944Y922127D03*
X314244D03*
X310543D03*
X306842D03*
X319795Y925316D03*
X316094D03*
X312393D03*
X308693D03*
X317944Y928505D03*
X314244D03*
X310543D03*
X306842D03*
X319795Y931694D03*
X316094D03*
X312393D03*
X308693D03*
X317944Y934883D03*
X314244D03*
X310543D03*
X306842D03*
X319795Y938072D03*
X316094D03*
X312393D03*
X308693D03*
X317944Y941261D03*
X314244D03*
X310543D03*
X306842D03*
X319795Y944450D03*
X316094D03*
X312393D03*
X308693D03*
X317944Y947639D03*
X314244D03*
X310543D03*
X306842D03*
X319795Y950828D03*
X316094D03*
X312393D03*
X308693D03*
X317944Y954017D03*
X314244D03*
X310543D03*
X306842D03*
X319795Y957206D03*
X316094D03*
X312393D03*
X308693D03*
X317944Y960395D03*
X314244D03*
X310543D03*
X306842D03*
X319795Y963584D03*
X316094D03*
X312393D03*
X308693D03*
X317944Y966773D03*
X314244D03*
X310543D03*
X306842D03*
X319795Y969962D03*
X316094D03*
X312393D03*
X308693D03*
X317944Y973151D03*
X314244D03*
X310543D03*
X306842D03*
X319795Y976340D03*
X316094D03*
X312393D03*
X308693D03*
X317944Y979529D03*
X314244D03*
X310543D03*
X306842D03*
X319795Y982718D03*
X316094D03*
X312393D03*
X308693D03*
X317944Y985907D03*
X314244D03*
X310543D03*
X306842D03*
X319795Y989096D03*
X316094D03*
X312393D03*
X308693D03*
X317944Y992285D03*
X314244D03*
X310543D03*
X306842D03*
X319795Y995474D03*
X316094D03*
X312393D03*
X308693D03*
X317944Y998663D03*
X314244D03*
X310543D03*
X306842D03*
X319795Y1001852D03*
X316094D03*
X312393D03*
X308693D03*
X317944Y1005041D03*
X314244D03*
X310543D03*
X306842D03*
X319795Y1008230D03*
X316094D03*
X312393D03*
X308693D03*
X317944Y1011419D03*
X314244D03*
X310543D03*
X306842D03*
X319126Y1027009D03*
X315425D03*
X311724D03*
X308023D03*
X320976Y1030198D03*
X317275D03*
X313574D03*
X309874D03*
X306173D03*
X319126Y1033387D03*
X315425D03*
X311724D03*
X308023D03*
X320976Y1036576D03*
X317275D03*
X313574D03*
X309874D03*
X306173D03*
X319126Y1039765D03*
X315425D03*
X311724D03*
X308023D03*
X320976Y1042954D03*
X317275D03*
X313574D03*
X309874D03*
X306173D03*
X319126Y1046143D03*
X315425D03*
X311724D03*
X308023D03*
X320976Y1049332D03*
X317275D03*
X313574D03*
X309874D03*
X306173D03*
X319126Y1052521D03*
X315425D03*
X311724D03*
X308023D03*
X320976Y1055710D03*
X317275D03*
X313574D03*
X309874D03*
X306173D03*
X319126Y1058899D03*
X315425D03*
X311724D03*
X308023D03*
X320976Y1062088D03*
X317275D03*
X313574D03*
X309874D03*
X306173D03*
X319126Y1065277D03*
X315425D03*
X311724D03*
X308023D03*
X320976Y1068466D03*
X317275D03*
X313574D03*
X309874D03*
X306173D03*
X319126Y1071655D03*
X315425D03*
X311724D03*
X308023D03*
X320976Y1074844D03*
X317275D03*
X313574D03*
X309874D03*
X306173D03*
X319126Y1078033D03*
X315425D03*
X311724D03*
X308023D03*
X320976Y1081222D03*
X317275D03*
X313574D03*
X309874D03*
X306173D03*
X319126Y1084411D03*
X315425D03*
X311724D03*
X308023D03*
X320976Y1087600D03*
X317275D03*
X313574D03*
X309874D03*
X306173D03*
X319126Y1090789D03*
X315425D03*
X311724D03*
X308023D03*
X320976Y1093978D03*
X317275D03*
X313574D03*
X309874D03*
X306173D03*
X319126Y1097167D03*
X315425D03*
X311724D03*
X308023D03*
X320976Y1100356D03*
X317275D03*
X313574D03*
X309874D03*
X306173D03*
X319126Y1103545D03*
X315425D03*
X311724D03*
X308023D03*
X320976Y1106734D03*
X317275D03*
X313574D03*
X309874D03*
X306173D03*
X319126Y1109923D03*
X315425D03*
X311724D03*
X308023D03*
X320976Y1113112D03*
X317275D03*
X313574D03*
X309874D03*
X306173D03*
X319126Y1116301D03*
X315425D03*
X311724D03*
X308023D03*
X320976Y1119490D03*
X317275D03*
X313574D03*
X309874D03*
X306173D03*
X319126Y1122679D03*
X315425D03*
X311724D03*
X308023D03*
X320976Y1125868D03*
X317275D03*
X313574D03*
X309874D03*
X306173D03*
X319126Y1129057D03*
X315425D03*
X311724D03*
X308023D03*
X320976Y1132246D03*
X317275D03*
X313574D03*
X309874D03*
X306173D03*
X319126Y1135434D03*
X315425D03*
X311724D03*
X308023D03*
X320976Y1138623D03*
X317275D03*
X313574D03*
X309874D03*
X306173D03*
X319126Y1141812D03*
X315425D03*
X311724D03*
X308023D03*
X320976Y1145001D03*
X317275D03*
X313574D03*
X309874D03*
X306173D03*
X319126Y1148190D03*
X315425D03*
X311724D03*
X308023D03*
X320976Y1151379D03*
X317275D03*
X313574D03*
X309874D03*
X306173D03*
X319126Y1154568D03*
X315425D03*
X311724D03*
X308023D03*
X320976Y1157757D03*
X317275D03*
X313574D03*
X309874D03*
X306173D03*
X319126Y1160946D03*
X315425D03*
X311724D03*
X320976Y1164135D03*
X317275D03*
X313574D03*
X334598Y874293D03*
X330897D03*
X327196D03*
X332748Y877482D03*
X329047D03*
X325346D03*
X321645D03*
X334598Y880671D03*
X330897D03*
X327196D03*
X323496D03*
X332748Y883860D03*
X329047D03*
X325346D03*
X321645D03*
X334598Y887049D03*
X330897D03*
X327196D03*
X323496D03*
X332748Y890238D03*
X329047D03*
X325346D03*
X321645D03*
X334598Y893427D03*
X330897D03*
X327196D03*
X323496D03*
X332748Y896616D03*
X329047D03*
X325346D03*
X321645D03*
X334598Y899805D03*
X330897D03*
X327196D03*
X323496D03*
X332748Y902994D03*
X329047D03*
X325346D03*
X321645D03*
X334598Y906182D03*
X330897D03*
X327196D03*
X323496D03*
X332748Y909371D03*
X329047D03*
X325346D03*
X321645D03*
X334598Y912560D03*
X330897D03*
X327196D03*
X323496D03*
X332748Y915749D03*
X329047D03*
X325346D03*
X321645D03*
X334598Y918938D03*
X330897D03*
X327196D03*
X323496D03*
X332748Y922127D03*
X329047D03*
X325346D03*
X321645D03*
X334598Y925316D03*
X330897D03*
X327196D03*
X323496D03*
X332748Y928505D03*
X329047D03*
X325346D03*
X321645D03*
X334598Y931694D03*
X330897D03*
X327196D03*
X323496D03*
X332748Y934883D03*
X329047D03*
X325346D03*
X321645D03*
X334598Y938072D03*
X330897D03*
X327196D03*
X323496D03*
X332748Y941261D03*
X329047D03*
X325346D03*
X321645D03*
X334598Y944450D03*
X330897D03*
X327196D03*
X323496D03*
X332748Y947639D03*
X329047D03*
X325346D03*
X321645D03*
X334598Y950828D03*
X330897D03*
X327196D03*
X323496D03*
X332748Y954017D03*
X329047D03*
X325346D03*
X321645D03*
X334598Y957206D03*
X330897D03*
X327196D03*
X323496D03*
X332748Y960395D03*
X329047D03*
X325346D03*
X321645D03*
X334598Y963584D03*
X330897D03*
X327196D03*
X323496D03*
X332748Y966773D03*
X329047D03*
X325346D03*
X321645D03*
X334598Y969962D03*
X330897D03*
X327196D03*
X323496D03*
X332748Y973151D03*
X329047D03*
X325346D03*
X321645D03*
X334598Y976340D03*
X330897D03*
X327196D03*
X323496D03*
X332748Y979529D03*
X329047D03*
X325346D03*
X321645D03*
X334598Y982718D03*
X330897D03*
X327196D03*
X323496D03*
X332748Y985907D03*
X329047D03*
X325346D03*
X321645D03*
X334598Y989096D03*
X330897D03*
X327196D03*
X323496D03*
X332748Y992285D03*
X329047D03*
X325346D03*
X321645D03*
X334598Y995474D03*
X330897D03*
X327196D03*
X323496D03*
X332748Y998663D03*
X329047D03*
X325346D03*
X321645D03*
X334598Y1001852D03*
X330897D03*
X327196D03*
X323496D03*
X332748Y1005041D03*
X329047D03*
X325346D03*
X321645D03*
X334598Y1008230D03*
X330897D03*
X327196D03*
X323496D03*
X332748Y1011419D03*
X329047D03*
X325346D03*
X321645D03*
X333929Y1027009D03*
X330228D03*
X326527D03*
X322826D03*
X335779Y1030198D03*
X332078D03*
X328378D03*
X324677D03*
X333929Y1033387D03*
X330228D03*
X326527D03*
X322826D03*
X335779Y1036576D03*
X332078D03*
X328378D03*
X324677D03*
X333929Y1039765D03*
X330228D03*
X326527D03*
X322826D03*
X335779Y1042954D03*
X332078D03*
X328378D03*
X324677D03*
X333929Y1046143D03*
X330228D03*
X326527D03*
X322826D03*
X335779Y1049332D03*
X332078D03*
X328378D03*
X324677D03*
X333929Y1052521D03*
X330228D03*
X326527D03*
X322826D03*
X335779Y1055710D03*
X332078D03*
X328378D03*
X324677D03*
X333929Y1058899D03*
X330228D03*
X326527D03*
X322826D03*
X335779Y1062088D03*
X332078D03*
X328378D03*
X324677D03*
X333929Y1065277D03*
X330228D03*
X326527D03*
X322826D03*
X335779Y1068466D03*
X332078D03*
X328378D03*
X324677D03*
X333929Y1071655D03*
X330228D03*
X326527D03*
X322826D03*
X335779Y1074844D03*
X332078D03*
X328378D03*
X324677D03*
X333929Y1078033D03*
X330228D03*
X326527D03*
X322826D03*
X335779Y1081222D03*
X332078D03*
X328378D03*
X324677D03*
X333929Y1084411D03*
X330228D03*
X326527D03*
X322826D03*
X335779Y1087600D03*
X332078D03*
X328378D03*
X324677D03*
X333929Y1090789D03*
X330228D03*
X326527D03*
X322826D03*
X335779Y1093978D03*
X332078D03*
X328378D03*
X324677D03*
X333929Y1097167D03*
X330228D03*
X326527D03*
X322826D03*
X335779Y1100356D03*
X332078D03*
X328378D03*
X324677D03*
X333929Y1103545D03*
X330228D03*
X326527D03*
X322826D03*
X335779Y1106734D03*
X332078D03*
X328378D03*
X324677D03*
X333929Y1109923D03*
X330228D03*
X326527D03*
X322826D03*
X335779Y1113112D03*
X332078D03*
X328378D03*
X324677D03*
X333929Y1116301D03*
X330228D03*
X326527D03*
X322826D03*
X335779Y1119490D03*
X332078D03*
X328378D03*
X324677D03*
X333929Y1122679D03*
X330228D03*
X326527D03*
X322826D03*
X335779Y1125868D03*
X332078D03*
X328378D03*
X324677D03*
X333929Y1129057D03*
X330228D03*
X326527D03*
X322826D03*
X335779Y1132246D03*
X332078D03*
X328378D03*
X324677D03*
X333929Y1135434D03*
X330228D03*
X326527D03*
X322826D03*
X335779Y1138623D03*
X332078D03*
X328378D03*
X324677D03*
X333929Y1141812D03*
X330228D03*
X326527D03*
X322826D03*
X335779Y1145001D03*
X332078D03*
X328378D03*
X324677D03*
X333929Y1148190D03*
X330228D03*
X326527D03*
X322826D03*
X335779Y1151379D03*
X332078D03*
X328378D03*
X324677D03*
X333929Y1154568D03*
X330228D03*
X326527D03*
X322826D03*
X335779Y1157757D03*
X332078D03*
X328378D03*
X324677D03*
X333929Y1160946D03*
X330228D03*
X326527D03*
X322826D03*
X335779Y1164135D03*
X332078D03*
X328378D03*
X349401Y874293D03*
X342000D03*
X338299D03*
X347551Y877482D03*
X343850D03*
X340149D03*
X336448D03*
X349401Y880671D03*
X345700D03*
X342000D03*
X338299D03*
X347551Y883860D03*
X343850D03*
X340149D03*
X336448D03*
X349401Y887049D03*
X345700D03*
X342000D03*
X338299D03*
X347551Y890238D03*
X343850D03*
X340149D03*
X336448D03*
X349401Y893427D03*
X345700D03*
X342000D03*
X338299D03*
X347551Y896616D03*
X343850D03*
X340149D03*
X336448D03*
X349401Y899805D03*
X345700D03*
X342000D03*
X338299D03*
X347551Y902994D03*
X343850D03*
X340149D03*
X336448D03*
X349401Y906182D03*
X345700D03*
X342000D03*
X338299D03*
X347551Y909371D03*
X343850D03*
X340149D03*
X336448D03*
X349401Y912560D03*
X345700D03*
X342000D03*
X338299D03*
X347551Y915749D03*
X343850D03*
X340149D03*
X336448D03*
X349401Y918938D03*
X345700D03*
X342000D03*
X338299D03*
X347551Y922127D03*
X343850D03*
X340149D03*
X336448D03*
X349401Y925316D03*
X345700D03*
X342000D03*
X338299D03*
X347551Y928505D03*
X343850D03*
X340149D03*
X336448D03*
X349401Y931694D03*
X345700D03*
X342000D03*
X338299D03*
X347551Y934883D03*
X343850D03*
X340149D03*
X336448D03*
X349401Y938072D03*
X345700D03*
X342000D03*
X338299D03*
X347551Y941261D03*
X343850D03*
X340149D03*
X336448D03*
X349401Y944450D03*
X345700D03*
X342000D03*
X338299D03*
X347551Y947639D03*
X343850D03*
X340149D03*
X336448D03*
X349401Y950828D03*
X345700D03*
X342000D03*
X338299D03*
X347551Y954017D03*
X343850D03*
X340149D03*
X336448D03*
X349401Y957206D03*
X345700D03*
X342000D03*
X338299D03*
X347551Y960395D03*
X343850D03*
X340149D03*
X336448D03*
X349401Y963584D03*
X345700D03*
X342000D03*
X338299D03*
X347551Y966773D03*
X343850D03*
X340149D03*
X336448D03*
X349401Y969962D03*
X345700D03*
X342000D03*
X338299D03*
X347551Y973151D03*
X343850D03*
X340149D03*
X336448D03*
X349401Y976340D03*
X345700D03*
X342000D03*
X338299D03*
X347551Y979529D03*
X343850D03*
X340149D03*
X336448D03*
X349401Y982718D03*
X345700D03*
X342000D03*
X338299D03*
X347551Y985907D03*
X343850D03*
X340149D03*
X336448D03*
X349401Y989096D03*
X345700D03*
X342000D03*
X338299D03*
X347551Y992285D03*
X343850D03*
X340149D03*
X336448D03*
X349401Y995474D03*
X345700D03*
X342000D03*
X338299D03*
X347551Y998663D03*
X343850D03*
X340149D03*
X336448D03*
X349401Y1001852D03*
X345700D03*
X342000D03*
X338299D03*
X347551Y1005041D03*
X343850D03*
X340149D03*
X336448D03*
X349401Y1008230D03*
X345700D03*
X342000D03*
X338299D03*
X347551Y1011419D03*
X343850D03*
X340149D03*
X336448D03*
X348732Y1027009D03*
X345031D03*
X341330D03*
X337629D03*
X350582Y1030198D03*
X346881D03*
X343181D03*
X339480D03*
X348732Y1033387D03*
X345031D03*
X341330D03*
X337629D03*
X350582Y1036576D03*
X346881D03*
X343181D03*
X339480D03*
X348732Y1039765D03*
X345031D03*
X341330D03*
X337629D03*
X350582Y1042954D03*
X346881D03*
X343181D03*
X339480D03*
X348732Y1046143D03*
X345031D03*
X341330D03*
X337629D03*
X350582Y1049332D03*
X346881D03*
X343181D03*
X339480D03*
X348732Y1052521D03*
X345031D03*
X341330D03*
X337629D03*
X350582Y1055710D03*
X346881D03*
X343181D03*
X339480D03*
X348732Y1058899D03*
X345031D03*
X341330D03*
X337629D03*
X350582Y1062088D03*
X346881D03*
X343181D03*
X339480D03*
X348732Y1065277D03*
X345031D03*
X341330D03*
X337629D03*
X350582Y1068466D03*
X346881D03*
X343181D03*
X339480D03*
X348732Y1071655D03*
X345031D03*
X341330D03*
X337629D03*
X350582Y1074844D03*
X346881D03*
X343181D03*
X339480D03*
X348732Y1078033D03*
X345031D03*
X341330D03*
X337629D03*
X350582Y1081222D03*
X346881D03*
X343181D03*
X339480D03*
X348732Y1084411D03*
X345031D03*
X341330D03*
X337629D03*
X350582Y1087600D03*
X346881D03*
X343181D03*
X339480D03*
X348732Y1090789D03*
X345031D03*
X341330D03*
X337629D03*
X350582Y1093978D03*
X346881D03*
X343181D03*
X339480D03*
X348732Y1097167D03*
X345031D03*
X341330D03*
X337629D03*
X350582Y1100356D03*
X346881D03*
X343181D03*
X339480D03*
X348732Y1103545D03*
X345031D03*
X341330D03*
X337629D03*
X350582Y1106734D03*
X346881D03*
X343181D03*
X339480D03*
X348732Y1109923D03*
X345031D03*
X341330D03*
X337629D03*
X350582Y1113112D03*
X346881D03*
X343181D03*
X339480D03*
X348732Y1116301D03*
X345031D03*
X341330D03*
X337629D03*
X350582Y1119490D03*
X346881D03*
X343181D03*
X339480D03*
X348732Y1122679D03*
X345031D03*
X341330D03*
X337629D03*
X350582Y1125868D03*
X346881D03*
X343181D03*
X339480D03*
X348732Y1129057D03*
X345031D03*
X341330D03*
X337629D03*
X350582Y1132246D03*
X346881D03*
X343181D03*
X339480D03*
X348732Y1135434D03*
X345031D03*
X341330D03*
X337629D03*
X350582Y1138623D03*
X346881D03*
X343181D03*
X339480D03*
X348732Y1141812D03*
X345031D03*
X341330D03*
X337629D03*
X350582Y1145001D03*
X346881D03*
X343181D03*
X339480D03*
X348732Y1148190D03*
X345031D03*
X341330D03*
X337629D03*
X350582Y1151379D03*
X346881D03*
X343181D03*
X339480D03*
X348732Y1154568D03*
X345031D03*
X341330D03*
X337629D03*
X350582Y1157757D03*
X346881D03*
X343181D03*
X339480D03*
X348732Y1160946D03*
X345031D03*
X341330D03*
X337629D03*
X350582Y1164135D03*
X343181D03*
X339480D03*
X364204Y874293D03*
X360504D03*
X356803D03*
X353102D03*
X362354Y877482D03*
X358653D03*
X354952D03*
X351252D03*
X364204Y880671D03*
X360504D03*
X356803D03*
X353102D03*
X362354Y883860D03*
X358653D03*
X354952D03*
X351252D03*
X364204Y887049D03*
X360504D03*
X356803D03*
X353102D03*
X362354Y890238D03*
X358653D03*
X354952D03*
X351252D03*
X364204Y893427D03*
X360504D03*
X356803D03*
X353102D03*
X362354Y896616D03*
X358653D03*
X354952D03*
X351252D03*
X364204Y899805D03*
X360504D03*
X356803D03*
X353102D03*
X362354Y902994D03*
X358653D03*
X354952D03*
X351252D03*
X364204Y906182D03*
X360504D03*
X356803D03*
X353102D03*
X362354Y909371D03*
X358653D03*
X354952D03*
X351252D03*
X364204Y912560D03*
X360504D03*
X356803D03*
X353102D03*
X362354Y915749D03*
X358653D03*
X354952D03*
X351252D03*
X364204Y918938D03*
X360504D03*
X356803D03*
X353102D03*
X362354Y922127D03*
X358653D03*
X354952D03*
X351252D03*
X364204Y925316D03*
X360504D03*
X356803D03*
X353102D03*
X362354Y928505D03*
X358653D03*
X354952D03*
X351252D03*
X364204Y931694D03*
X360504D03*
X356803D03*
X353102D03*
X362354Y934883D03*
X358653D03*
X354952D03*
X351252D03*
X364204Y938072D03*
X360504D03*
X356803D03*
X353102D03*
X362354Y941261D03*
X358653D03*
X354952D03*
X351252D03*
X364204Y944450D03*
X360504D03*
X356803D03*
X353102D03*
X362354Y947639D03*
X358653D03*
X354952D03*
X351252D03*
X364204Y950828D03*
X360504D03*
X356803D03*
X353102D03*
X362354Y954017D03*
X358653D03*
X354952D03*
X351252D03*
X364204Y957206D03*
X360504D03*
X356803D03*
X353102D03*
X362354Y960395D03*
X358653D03*
X354952D03*
X351252D03*
X364204Y963584D03*
X360504D03*
X356803D03*
X353102D03*
X362354Y966773D03*
X358653D03*
X354952D03*
X351252D03*
X364204Y969962D03*
X360504D03*
X356803D03*
X353102D03*
X362354Y973151D03*
X358653D03*
X354952D03*
X351252D03*
X364204Y976340D03*
X360504D03*
X356803D03*
X353102D03*
X362354Y979529D03*
X358653D03*
X354952D03*
X351252D03*
X364204Y982718D03*
X360504D03*
X356803D03*
X353102D03*
X362354Y985907D03*
X358653D03*
X354952D03*
X351252D03*
X364204Y989096D03*
X360504D03*
X356803D03*
X353102D03*
X362354Y992285D03*
X358653D03*
X354952D03*
X351252D03*
X364204Y995474D03*
X360504D03*
X356803D03*
X353102D03*
X362354Y998663D03*
X358653D03*
X354952D03*
X351252D03*
X364204Y1001852D03*
X360504D03*
X356803D03*
X353102D03*
X362354Y1005041D03*
X358653D03*
X354952D03*
X351252D03*
X364204Y1008230D03*
X360504D03*
X356803D03*
X353102D03*
X362354Y1011419D03*
X358653D03*
X354952D03*
X351252D03*
X363535Y1027009D03*
X359834D03*
X356133D03*
X352433D03*
X365385Y1030198D03*
X361685D03*
X357984D03*
X354283D03*
X363535Y1033387D03*
X359834D03*
X356133D03*
X352433D03*
X365385Y1036576D03*
X361685D03*
X357984D03*
X354283D03*
X363535Y1039765D03*
X359834D03*
X356133D03*
X352433D03*
X365385Y1042954D03*
X361685D03*
X357984D03*
X354283D03*
X363535Y1046143D03*
X359834D03*
X356133D03*
X352433D03*
X365385Y1049332D03*
X361685D03*
X357984D03*
X354283D03*
X363535Y1052521D03*
X359834D03*
X356133D03*
X352433D03*
X365385Y1055710D03*
X361685D03*
X357984D03*
X354283D03*
X363535Y1058899D03*
X359834D03*
X356133D03*
X352433D03*
X365385Y1062088D03*
X361685D03*
X357984D03*
X354283D03*
X363535Y1065277D03*
X359834D03*
X356133D03*
X352433D03*
X365385Y1068466D03*
X361685D03*
X357984D03*
X354283D03*
X363535Y1071655D03*
X359834D03*
X356133D03*
X352433D03*
X365385Y1074844D03*
X361685D03*
X357984D03*
X354283D03*
X363535Y1078033D03*
X359834D03*
X356133D03*
X352433D03*
X365385Y1081222D03*
X361685D03*
X357984D03*
X354283D03*
X363535Y1084411D03*
X359834D03*
X356133D03*
X352433D03*
X365385Y1087600D03*
X361685D03*
X357984D03*
X354283D03*
X363535Y1090789D03*
X359834D03*
X356133D03*
X352433D03*
X365385Y1093978D03*
X361685D03*
X357984D03*
X354283D03*
X363535Y1097167D03*
X359834D03*
X356133D03*
X352433D03*
X365385Y1100356D03*
X361685D03*
X357984D03*
X354283D03*
X363535Y1103545D03*
X359834D03*
X356133D03*
X352433D03*
X365385Y1106734D03*
X361685D03*
X357984D03*
X354283D03*
X363535Y1109923D03*
X359834D03*
X356133D03*
X352433D03*
X365385Y1113112D03*
X361685D03*
X357984D03*
X354283D03*
X363535Y1116301D03*
X359834D03*
X356133D03*
X352433D03*
X365385Y1119490D03*
X361685D03*
X357984D03*
X354283D03*
X363535Y1122679D03*
X359834D03*
X356133D03*
X352433D03*
X365385Y1125868D03*
X361685D03*
X357984D03*
X354283D03*
X363535Y1129057D03*
X359834D03*
X356133D03*
X352433D03*
X365385Y1132246D03*
X361685D03*
X357984D03*
X354283D03*
X363535Y1135434D03*
X359834D03*
X356133D03*
X352433D03*
X365385Y1138623D03*
X361685D03*
X357984D03*
X354283D03*
X363535Y1141812D03*
X359834D03*
X356133D03*
X352433D03*
X365385Y1145001D03*
X361685D03*
X357984D03*
X354283D03*
X363535Y1148190D03*
X359834D03*
X356133D03*
X352433D03*
X365385Y1151379D03*
X361685D03*
X357984D03*
X354283D03*
X363535Y1154568D03*
X359834D03*
X356133D03*
X352433D03*
X365385Y1157757D03*
X361685D03*
X357984D03*
X354283D03*
X363535Y1160946D03*
X359834D03*
X356133D03*
X352433D03*
X365385Y1164135D03*
X361685D03*
X357984D03*
X354283D03*
X379007Y874293D03*
X375307D03*
X371606D03*
X377157Y877482D03*
X373456D03*
X369755D03*
X366055D03*
X379007Y880671D03*
X375307D03*
X371606D03*
X367905D03*
X377157Y883860D03*
X373456D03*
X369755D03*
X366055D03*
X379007Y887049D03*
X375307D03*
X371606D03*
X367905D03*
X377157Y890238D03*
X373456D03*
X369755D03*
X366055D03*
X379007Y893427D03*
X375307D03*
X371606D03*
X367905D03*
X377157Y896616D03*
X373456D03*
X369755D03*
X366055D03*
X379007Y899805D03*
X375307D03*
X371606D03*
X367905D03*
X377157Y902994D03*
X373456D03*
X369755D03*
X366055D03*
X379007Y906182D03*
X375307D03*
X371606D03*
X367905D03*
X377157Y909371D03*
X373456D03*
X369755D03*
X366055D03*
X379007Y912560D03*
X375307D03*
X371606D03*
X367905D03*
X377157Y915749D03*
X373456D03*
X369755D03*
X366055D03*
X379007Y918938D03*
X375307D03*
X371606D03*
X367905D03*
X377157Y922127D03*
X373456D03*
X369755D03*
X366055D03*
X379007Y925316D03*
X375307D03*
X371606D03*
X367905D03*
X377157Y928505D03*
X373456D03*
X369755D03*
X366055D03*
X379007Y931694D03*
X375307D03*
X371606D03*
X367905D03*
X377157Y934883D03*
X373456D03*
X369755D03*
X366055D03*
X379007Y938072D03*
X375307D03*
X371606D03*
X367905D03*
X377157Y941261D03*
X373456D03*
X369755D03*
X366055D03*
X379007Y944450D03*
X375307D03*
X371606D03*
X367905D03*
X377157Y947639D03*
X373456D03*
X369755D03*
X366055D03*
X379007Y950828D03*
X375307D03*
X371606D03*
X367905D03*
X377157Y954017D03*
X373456D03*
X369755D03*
X366055D03*
X379007Y957206D03*
X375307D03*
X371606D03*
X367905D03*
X377157Y960395D03*
X373456D03*
X369755D03*
X366055D03*
X379007Y963584D03*
X375307D03*
X371606D03*
X367905D03*
X377157Y966773D03*
X373456D03*
X369755D03*
X366055D03*
X379007Y969962D03*
X375307D03*
X371606D03*
X367905D03*
X377157Y973151D03*
X373456D03*
X369755D03*
X366055D03*
X379007Y976340D03*
X375307D03*
X371606D03*
X367905D03*
X377157Y979529D03*
X373456D03*
X369755D03*
X366055D03*
X379007Y982718D03*
X375307D03*
X371606D03*
X367905D03*
X377157Y985907D03*
X373456D03*
X369755D03*
X366055D03*
X379007Y989096D03*
X375307D03*
X371606D03*
X367905D03*
X377157Y992285D03*
X373456D03*
X369755D03*
X366055D03*
X379007Y995474D03*
X375307D03*
X371606D03*
X367905D03*
X377157Y998663D03*
X373456D03*
X369755D03*
X366055D03*
X379007Y1001852D03*
X375307D03*
X371606D03*
X367905D03*
X377157Y1005041D03*
X373456D03*
X369755D03*
X366055D03*
X379007Y1008230D03*
X375307D03*
X371606D03*
X367905D03*
X377157Y1011419D03*
X373456D03*
X369755D03*
X366055D03*
X378338Y1027009D03*
X374637D03*
X370937D03*
X367236D03*
X380189Y1030198D03*
X376488D03*
X372787D03*
X369086D03*
X378338Y1033387D03*
X374637D03*
X370937D03*
X367236D03*
X380189Y1036576D03*
X376488D03*
X372787D03*
X369086D03*
X378338Y1039765D03*
X374637D03*
X370937D03*
X367236D03*
X380189Y1042954D03*
X376488D03*
X372787D03*
X369086D03*
X378338Y1046143D03*
X374637D03*
X370937D03*
X367236D03*
X380189Y1049332D03*
X376488D03*
X372787D03*
X369086D03*
X378338Y1052521D03*
X374637D03*
X370937D03*
X367236D03*
X380189Y1055710D03*
X376488D03*
X372787D03*
X369086D03*
X378338Y1058899D03*
X374637D03*
X370937D03*
X367236D03*
X380189Y1062088D03*
X376488D03*
X372787D03*
X369086D03*
X378338Y1065277D03*
X374637D03*
X370937D03*
X367236D03*
X380189Y1068466D03*
X376488D03*
X372787D03*
X369086D03*
X378338Y1071655D03*
X374637D03*
X370937D03*
X367236D03*
X380189Y1074844D03*
X376488D03*
X372787D03*
X369086D03*
X378338Y1078033D03*
X374637D03*
X370937D03*
X367236D03*
X380189Y1081222D03*
X376488D03*
X372787D03*
X369086D03*
X378338Y1084411D03*
X374637D03*
X370937D03*
X367236D03*
X380189Y1087600D03*
X376488D03*
X372787D03*
X369086D03*
X378338Y1090789D03*
X374637D03*
X370937D03*
X367236D03*
X380189Y1093978D03*
X376488D03*
X372787D03*
X369086D03*
X378338Y1097167D03*
X374637D03*
X370937D03*
X367236D03*
X380189Y1100356D03*
X376488D03*
X372787D03*
X369086D03*
X378338Y1103545D03*
X374637D03*
X370937D03*
X367236D03*
X380189Y1106734D03*
X376488D03*
X372787D03*
X369086D03*
X378338Y1109923D03*
X374637D03*
X370937D03*
X367236D03*
X380189Y1113112D03*
X376488D03*
X372787D03*
X369086D03*
X378338Y1116301D03*
X374637D03*
X370937D03*
X367236D03*
X380189Y1119490D03*
X376488D03*
X372787D03*
X369086D03*
X378338Y1122679D03*
X374637D03*
X370937D03*
X367236D03*
X380189Y1125868D03*
X376488D03*
X372787D03*
X369086D03*
X378338Y1129057D03*
X374637D03*
X370937D03*
X367236D03*
X380189Y1132246D03*
X376488D03*
X372787D03*
X369086D03*
X378338Y1135434D03*
X374637D03*
X370937D03*
X367236D03*
X380189Y1138623D03*
X376488D03*
X372787D03*
X369086D03*
X378338Y1141812D03*
X374637D03*
X370937D03*
X367236D03*
X380189Y1145001D03*
X376488D03*
X372787D03*
X369086D03*
X378338Y1148190D03*
X374637D03*
X370937D03*
X367236D03*
X380189Y1151379D03*
X376488D03*
X372787D03*
X369086D03*
X378338Y1154568D03*
X374637D03*
X370937D03*
X367236D03*
X380189Y1157757D03*
X376488D03*
X372787D03*
X369086D03*
X378338Y1160946D03*
X374637D03*
X370937D03*
X367236D03*
X380189Y1164135D03*
X376488D03*
X372787D03*
X393811Y874293D03*
X386409D03*
X382708D03*
X391960Y877482D03*
X388259D03*
X384559D03*
X380858D03*
X393811Y880671D03*
X390110D03*
X386409D03*
X382708D03*
X391960Y883860D03*
X388259D03*
X384559D03*
X380858D03*
X393811Y887049D03*
X390110D03*
X386409D03*
X382708D03*
X391960Y890238D03*
X388259D03*
X384559D03*
X380858D03*
X393811Y893427D03*
X390110D03*
X386409D03*
X382708D03*
X391960Y896616D03*
X388259D03*
X384559D03*
X380858D03*
X393811Y899805D03*
X390110D03*
X386409D03*
X382708D03*
X391960Y902994D03*
X388259D03*
X384559D03*
X380858D03*
X393811Y906182D03*
X390110D03*
X386409D03*
X382708D03*
X391960Y909371D03*
X388259D03*
X384559D03*
X380858D03*
X393811Y912560D03*
X390110D03*
X386409D03*
X382708D03*
X391960Y915749D03*
X388259D03*
X384559D03*
X380858D03*
X393811Y918938D03*
X390110D03*
X386409D03*
X382708D03*
X391960Y922127D03*
X388259D03*
X384559D03*
X380858D03*
X393811Y925316D03*
X390110D03*
X386409D03*
X382708D03*
X391960Y928505D03*
X388259D03*
X384559D03*
X380858D03*
X393811Y931694D03*
X390110D03*
X386409D03*
X382708D03*
X391960Y934883D03*
X388259D03*
X384559D03*
X380858D03*
X393811Y938072D03*
X390110D03*
X386409D03*
X382708D03*
X391960Y941261D03*
X388259D03*
X384559D03*
X380858D03*
X393811Y944450D03*
X390110D03*
X386409D03*
X382708D03*
X391960Y947639D03*
X388259D03*
X384559D03*
X380858D03*
X393811Y950828D03*
X390110D03*
X386409D03*
X382708D03*
X391960Y954017D03*
X388259D03*
X384559D03*
X380858D03*
X393811Y957206D03*
X390110D03*
X386409D03*
X382708D03*
X391960Y960395D03*
X388259D03*
X384559D03*
X380858D03*
X393811Y963584D03*
X390110D03*
X386409D03*
X382708D03*
X391960Y966773D03*
X388259D03*
X384559D03*
X380858D03*
X393811Y969962D03*
X390110D03*
X386409D03*
X382708D03*
X391960Y973151D03*
X388259D03*
X384559D03*
X380858D03*
X393811Y976340D03*
X390110D03*
X386409D03*
X382708D03*
X391960Y979529D03*
X388259D03*
X384559D03*
X380858D03*
X393811Y982718D03*
X390110D03*
X386409D03*
X382708D03*
X391960Y985907D03*
X388259D03*
X384559D03*
X380858D03*
X393811Y989096D03*
X390110D03*
X386409D03*
X382708D03*
X391960Y992285D03*
X388259D03*
X384559D03*
X380858D03*
X393811Y995474D03*
X390110D03*
X386409D03*
X382708D03*
X391960Y998663D03*
X388259D03*
X384559D03*
X380858D03*
X393811Y1001852D03*
X390110D03*
X386409D03*
X382708D03*
X391960Y1005041D03*
X388259D03*
X384559D03*
X380858D03*
X393811Y1008230D03*
X390110D03*
X386409D03*
X382708D03*
X391960Y1011419D03*
X388259D03*
X384559D03*
X380858D03*
X393141Y1027009D03*
X389441D03*
X385740D03*
X382039D03*
X394992Y1030198D03*
X391291D03*
X387590D03*
X383889D03*
X393141Y1033387D03*
X389441D03*
X385740D03*
X382039D03*
X394992Y1036576D03*
X391291D03*
X387590D03*
X383889D03*
X393141Y1039765D03*
X389441D03*
X385740D03*
X382039D03*
X394992Y1042954D03*
X391291D03*
X387590D03*
X383889D03*
X393141Y1046143D03*
X389441D03*
X385740D03*
X382039D03*
X394992Y1049332D03*
X391291D03*
X387590D03*
X383889D03*
X393141Y1052521D03*
X389441D03*
X385740D03*
X382039D03*
X394992Y1055710D03*
X391291D03*
X387590D03*
X383889D03*
X393141Y1058899D03*
X389441D03*
X385740D03*
X382039D03*
X394992Y1062088D03*
X391291D03*
X387590D03*
X383889D03*
X393141Y1065277D03*
X389441D03*
X385740D03*
X382039D03*
X394992Y1068466D03*
X391291D03*
X387590D03*
X383889D03*
X393141Y1071655D03*
X389441D03*
X385740D03*
X382039D03*
X394992Y1074844D03*
X391291D03*
X387590D03*
X383889D03*
X393141Y1078033D03*
X389441D03*
X385740D03*
X382039D03*
X394992Y1081222D03*
X391291D03*
X387590D03*
X383889D03*
X393141Y1084411D03*
X389441D03*
X385740D03*
X382039D03*
X394992Y1087600D03*
X391291D03*
X387590D03*
X383889D03*
X393141Y1090789D03*
X389441D03*
X385740D03*
X382039D03*
X394992Y1093978D03*
X391291D03*
X387590D03*
X383889D03*
X393141Y1097167D03*
X389441D03*
X385740D03*
X382039D03*
X394992Y1100356D03*
X391291D03*
X387590D03*
X383889D03*
X393141Y1103545D03*
X389441D03*
X385740D03*
X382039D03*
X394992Y1106734D03*
X391291D03*
X387590D03*
X383889D03*
X393141Y1109923D03*
X389441D03*
X385740D03*
X382039D03*
X394992Y1113112D03*
X391291D03*
X387590D03*
X383889D03*
X393141Y1116301D03*
X389441D03*
X385740D03*
X382039D03*
X394992Y1119490D03*
X391291D03*
X387590D03*
X383889D03*
X393141Y1122679D03*
X389441D03*
X385740D03*
X382039D03*
X394992Y1125868D03*
X391291D03*
X387590D03*
X383889D03*
X393141Y1129057D03*
X389441D03*
X385740D03*
X382039D03*
X394992Y1132246D03*
X391291D03*
X387590D03*
X383889D03*
X393141Y1135434D03*
X389441D03*
X385740D03*
X382039D03*
X394992Y1138623D03*
X391291D03*
X387590D03*
X383889D03*
X393141Y1141812D03*
X389441D03*
X385740D03*
X382039D03*
X394992Y1145001D03*
X391291D03*
X387590D03*
X383889D03*
X393141Y1148190D03*
X389441D03*
X385740D03*
X382039D03*
X394992Y1151379D03*
X391291D03*
X387590D03*
X383889D03*
X393141Y1154568D03*
X389441D03*
X385740D03*
X382039D03*
X394992Y1157757D03*
X391291D03*
X387590D03*
X383889D03*
X393141Y1160946D03*
X389441D03*
X385740D03*
X382039D03*
X394992Y1164135D03*
X387590D03*
X383889D03*
X408614Y874293D03*
X404913D03*
X401212D03*
X397511D03*
X410464Y877482D03*
X406763D03*
X403063D03*
X399362D03*
X395661D03*
X408614Y880671D03*
X404913D03*
X401212D03*
X397511D03*
X410464Y883860D03*
X406763D03*
X403063D03*
X399362D03*
X395661D03*
X408614Y887049D03*
X404913D03*
X401212D03*
X397511D03*
X410464Y890238D03*
X406763D03*
X403063D03*
X399362D03*
X395661D03*
X408614Y893427D03*
X404913D03*
X401212D03*
X397511D03*
X410464Y896616D03*
X406763D03*
X403063D03*
X399362D03*
X395661D03*
X408614Y899805D03*
X404913D03*
X401212D03*
X397511D03*
X410464Y902994D03*
X406763D03*
X403063D03*
X399362D03*
X395661D03*
X408614Y906182D03*
X404913D03*
X401212D03*
X397511D03*
X410464Y909371D03*
X406763D03*
X403063D03*
X399362D03*
X395661D03*
X408614Y912560D03*
X404913D03*
X401212D03*
X397511D03*
X410464Y915749D03*
X406763D03*
X403063D03*
X399362D03*
X395661D03*
X408614Y918938D03*
X404913D03*
X401212D03*
X397511D03*
X410464Y922127D03*
X406763D03*
X403063D03*
X399362D03*
X395661D03*
X408614Y925316D03*
X404913D03*
X401212D03*
X397511D03*
X410464Y928505D03*
X406763D03*
X403063D03*
X399362D03*
X395661D03*
X408614Y931694D03*
X404913D03*
X401212D03*
X397511D03*
X410464Y934883D03*
X406763D03*
X403063D03*
X399362D03*
X395661D03*
X408614Y938072D03*
X404913D03*
X401212D03*
X397511D03*
X410464Y941261D03*
X406763D03*
X403063D03*
X399362D03*
X395661D03*
X408614Y944450D03*
X404913D03*
X401212D03*
X397511D03*
X410464Y947639D03*
X406763D03*
X403063D03*
X399362D03*
X395661D03*
X408614Y950828D03*
X404913D03*
X401212D03*
X397511D03*
X410464Y954017D03*
X406763D03*
X403063D03*
X399362D03*
X395661D03*
X408614Y957206D03*
X404913D03*
X401212D03*
X397511D03*
X410464Y960395D03*
X406763D03*
X403063D03*
X399362D03*
X395661D03*
X408614Y963584D03*
X404913D03*
X401212D03*
X397511D03*
X410464Y966773D03*
X406763D03*
X403063D03*
X399362D03*
X395661D03*
X408614Y969962D03*
X404913D03*
X401212D03*
X397511D03*
X410464Y973151D03*
X406763D03*
X403063D03*
X399362D03*
X395661D03*
X408614Y976340D03*
X404913D03*
X401212D03*
X397511D03*
X410464Y979529D03*
X406763D03*
X403063D03*
X399362D03*
X395661D03*
X408614Y982718D03*
X404913D03*
X401212D03*
X397511D03*
X410464Y985907D03*
X406763D03*
X403063D03*
X399362D03*
X395661D03*
X408614Y989096D03*
X404913D03*
X401212D03*
X397511D03*
X410464Y992285D03*
X406763D03*
X403063D03*
X399362D03*
X395661D03*
X404913Y995474D03*
X401212D03*
X397511D03*
X403063Y998663D03*
X399362D03*
X395661D03*
X404913Y1001852D03*
X401212D03*
X397511D03*
X403063Y1005041D03*
X399362D03*
X395661D03*
X404913Y1008230D03*
X401212D03*
X397511D03*
X403063Y1011419D03*
X399362D03*
X395661D03*
X404244Y1027009D03*
X400543D03*
X396842D03*
X406094Y1030198D03*
X402393D03*
X398693D03*
X404244Y1033387D03*
X400543D03*
X396842D03*
X406094Y1036576D03*
X402393D03*
X398693D03*
X404244Y1039765D03*
X400543D03*
X396842D03*
X406094Y1042954D03*
X402393D03*
X398693D03*
X407944Y1046143D03*
X404244D03*
X400543D03*
X396842D03*
X409795Y1049332D03*
X406094D03*
X402393D03*
X398693D03*
X407944Y1052521D03*
X404244D03*
X400543D03*
X396842D03*
X409795Y1055710D03*
X406094D03*
X402393D03*
X398693D03*
X407944Y1058899D03*
X404244D03*
X400543D03*
X396842D03*
X409795Y1062088D03*
X406094D03*
X402393D03*
X398693D03*
X407944Y1065277D03*
X404244D03*
X400543D03*
X396842D03*
X409795Y1068466D03*
X406094D03*
X402393D03*
X398693D03*
X407944Y1071655D03*
X404244D03*
X400543D03*
X396842D03*
X409795Y1074844D03*
X406094D03*
X402393D03*
X398693D03*
X407944Y1078033D03*
X404244D03*
X400543D03*
X396842D03*
X409795Y1081222D03*
X406094D03*
X402393D03*
X398693D03*
X407944Y1084411D03*
X404244D03*
X400543D03*
X396842D03*
X409795Y1087600D03*
X406094D03*
X402393D03*
X398693D03*
X407944Y1090789D03*
X404244D03*
X400543D03*
X396842D03*
X409795Y1093978D03*
X406094D03*
X402393D03*
X398693D03*
X407944Y1097167D03*
X404244D03*
X400543D03*
X396842D03*
X409795Y1100356D03*
X406094D03*
X402393D03*
X398693D03*
X407944Y1103545D03*
X404244D03*
X400543D03*
X396842D03*
X409795Y1106734D03*
X406094D03*
X402393D03*
X398693D03*
X407944Y1109923D03*
X404244D03*
X400543D03*
X396842D03*
X409795Y1113112D03*
X406094D03*
X402393D03*
X398693D03*
X407944Y1116301D03*
X404244D03*
X400543D03*
X396842D03*
X409795Y1119490D03*
X406094D03*
X402393D03*
X398693D03*
X407944Y1122679D03*
X404244D03*
X400543D03*
X396842D03*
X409795Y1125868D03*
X406094D03*
X402393D03*
X398693D03*
X407944Y1129057D03*
X404244D03*
X400543D03*
X396842D03*
X409795Y1132246D03*
X406094D03*
X402393D03*
X398693D03*
X407944Y1135434D03*
X404244D03*
X400543D03*
X396842D03*
X409795Y1138623D03*
X406094D03*
X402393D03*
X398693D03*
X407944Y1141812D03*
X404244D03*
X400543D03*
X396842D03*
X409795Y1145001D03*
X406094D03*
X402393D03*
X398693D03*
X407944Y1148190D03*
X404244D03*
X400543D03*
X396842D03*
X409795Y1151379D03*
X406094D03*
X402393D03*
X398693D03*
X407944Y1154568D03*
X404244D03*
X400543D03*
X396842D03*
X409795Y1157757D03*
X406094D03*
X402393D03*
X398693D03*
X407944Y1160946D03*
X404244D03*
X400543D03*
X396842D03*
X409795Y1164135D03*
X406094D03*
X402393D03*
X398693D03*
X423417Y874293D03*
X419716D03*
X416015D03*
X425267Y877482D03*
X421567D03*
X417866D03*
X414165D03*
X423417Y880671D03*
X419716D03*
X416015D03*
X412315D03*
X425267Y883860D03*
X421567D03*
X417866D03*
X414165D03*
X423417Y887049D03*
X419716D03*
X416015D03*
X412315D03*
X425267Y890238D03*
X421567D03*
X417866D03*
X414165D03*
X423417Y893427D03*
X419716D03*
X416015D03*
X412315D03*
X425267Y896616D03*
X421567D03*
X417866D03*
X414165D03*
X423417Y899805D03*
X419716D03*
X416015D03*
X412315D03*
X425267Y902994D03*
X421567D03*
X417866D03*
X414165D03*
X423417Y906182D03*
X419716D03*
X416015D03*
X412315D03*
X425267Y909371D03*
X421567D03*
X417866D03*
X414165D03*
X423417Y912560D03*
X419716D03*
X416015D03*
X412315D03*
X425267Y915749D03*
X421567D03*
X417866D03*
X414165D03*
X423417Y918938D03*
X419716D03*
X416015D03*
X412315D03*
X425267Y922127D03*
X421567D03*
X417866D03*
X414165D03*
X423417Y925316D03*
X419716D03*
X416015D03*
X412315D03*
X425267Y928505D03*
X421567D03*
X417866D03*
X414165D03*
X423417Y931694D03*
X419716D03*
X416015D03*
X412315D03*
X425267Y934883D03*
X421567D03*
X417866D03*
X414165D03*
X423417Y938072D03*
X419716D03*
X416015D03*
X412315D03*
X425267Y941261D03*
X421567D03*
X417866D03*
X414165D03*
X423417Y944450D03*
X419716D03*
X416015D03*
X412315D03*
X425267Y947639D03*
X421567D03*
X417866D03*
X414165D03*
X423417Y950828D03*
X419716D03*
X416015D03*
X412315D03*
X425267Y954017D03*
X421567D03*
X417866D03*
X414165D03*
X423417Y957206D03*
X419716D03*
X416015D03*
X412315D03*
X425267Y960395D03*
X421567D03*
X417866D03*
X414165D03*
X423417Y963584D03*
X419716D03*
X416015D03*
X412315D03*
X425267Y966773D03*
X421567D03*
X417866D03*
X414165D03*
X423417Y969962D03*
X419716D03*
X416015D03*
X412315D03*
X425267Y973151D03*
X421567D03*
X417866D03*
X414165D03*
X423417Y976340D03*
X419716D03*
X416015D03*
X412315D03*
X425267Y979529D03*
X421567D03*
X417866D03*
X414165D03*
X423417Y982718D03*
X419716D03*
X416015D03*
X412315D03*
X425267Y985907D03*
X421567D03*
X417866D03*
X414165D03*
X423417Y989096D03*
X419716D03*
X416015D03*
X412315D03*
X425267Y992285D03*
X421567D03*
X417866D03*
X414165D03*
X422748Y1046143D03*
X419047D03*
X415346D03*
X411645D03*
X424598Y1049332D03*
X420897D03*
X417196D03*
X413496D03*
X422748Y1052521D03*
X419047D03*
X415346D03*
X411645D03*
X424598Y1055710D03*
X420897D03*
X417196D03*
X413496D03*
X422748Y1058899D03*
X419047D03*
X415346D03*
X411645D03*
X424598Y1062088D03*
X420897D03*
X417196D03*
X413496D03*
X422748Y1065277D03*
X419047D03*
X415346D03*
X411645D03*
X424598Y1068466D03*
X420897D03*
X417196D03*
X413496D03*
X422748Y1071655D03*
X419047D03*
X415346D03*
X411645D03*
X424598Y1074844D03*
X420897D03*
X417196D03*
X413496D03*
X422748Y1078033D03*
X419047D03*
X415346D03*
X411645D03*
X424598Y1081222D03*
X420897D03*
X417196D03*
X413496D03*
X422748Y1084411D03*
X419047D03*
X415346D03*
X411645D03*
X424598Y1087600D03*
X420897D03*
X417196D03*
X413496D03*
X422748Y1090789D03*
X419047D03*
X415346D03*
X411645D03*
X424598Y1093978D03*
X420897D03*
X417196D03*
X413496D03*
X422748Y1097167D03*
X419047D03*
X415346D03*
X411645D03*
X424598Y1100356D03*
X420897D03*
X417196D03*
X413496D03*
X422748Y1103545D03*
X419047D03*
X415346D03*
X411645D03*
X424598Y1106734D03*
X420897D03*
X417196D03*
X413496D03*
X422748Y1109923D03*
X419047D03*
X415346D03*
X411645D03*
X424598Y1113112D03*
X420897D03*
X417196D03*
X413496D03*
X422748Y1116301D03*
X419047D03*
X415346D03*
X411645D03*
X424598Y1119490D03*
X420897D03*
X417196D03*
X413496D03*
X422748Y1122679D03*
X419047D03*
X415346D03*
X411645D03*
X424598Y1125868D03*
X420897D03*
X417196D03*
X413496D03*
X422748Y1129057D03*
X419047D03*
X415346D03*
X411645D03*
X424598Y1132246D03*
X420897D03*
X417196D03*
X413496D03*
X422748Y1135434D03*
X419047D03*
X415346D03*
X411645D03*
X424598Y1138623D03*
X420897D03*
X417196D03*
X413496D03*
X422748Y1141812D03*
X419047D03*
X415346D03*
X411645D03*
X424598Y1145001D03*
X420897D03*
X417196D03*
X413496D03*
X422748Y1148190D03*
X419047D03*
X415346D03*
X411645D03*
X424598Y1151379D03*
X420897D03*
X417196D03*
X413496D03*
X422748Y1154568D03*
X419047D03*
X415346D03*
X411645D03*
X424598Y1157757D03*
X420897D03*
X417196D03*
X413496D03*
X422748Y1160946D03*
X419047D03*
X415346D03*
X411645D03*
X424598Y1164135D03*
X420897D03*
X417196D03*
X430818Y874293D03*
X427118D03*
X436370Y877482D03*
X432669D03*
X428968D03*
X434519Y880671D03*
X430818D03*
X427118D03*
X436370Y883860D03*
X432669D03*
X428968D03*
X434519Y887049D03*
X430818D03*
X427118D03*
X436370Y890238D03*
X432669D03*
X428968D03*
X434519Y893427D03*
X430818D03*
X427118D03*
X436370Y896616D03*
X432669D03*
X428968D03*
X434519Y899805D03*
X430818D03*
X427118D03*
X436370Y902994D03*
X432669D03*
X428968D03*
X434519Y906182D03*
X430818D03*
X427118D03*
X436370Y909371D03*
X432669D03*
X428968D03*
X434519Y912560D03*
X430818D03*
X427118D03*
X436370Y915749D03*
X432669D03*
X428968D03*
X434519Y918938D03*
X430818D03*
X427118D03*
X436370Y922127D03*
X432669D03*
X428968D03*
X434519Y925316D03*
X430818D03*
X427118D03*
X436370Y928505D03*
X432669D03*
X428968D03*
X434519Y931694D03*
X430818D03*
X427118D03*
X436370Y934883D03*
X432669D03*
X428968D03*
X434519Y938072D03*
X430818D03*
X427118D03*
X436370Y941261D03*
X432669D03*
X428968D03*
X434519Y944450D03*
X430818D03*
X427118D03*
X436370Y947639D03*
X432669D03*
X428968D03*
X434519Y950828D03*
X430818D03*
X427118D03*
X436370Y954017D03*
X432669D03*
X428968D03*
X434519Y957206D03*
X430818D03*
X427118D03*
X436370Y960395D03*
X432669D03*
X428968D03*
X434519Y963584D03*
X430818D03*
X427118D03*
X436370Y966773D03*
X432669D03*
X428968D03*
X434519Y969962D03*
X430818D03*
X427118D03*
X436370Y973151D03*
X432669D03*
X428968D03*
X434519Y976340D03*
X430818D03*
X427118D03*
X436370Y979529D03*
X432669D03*
X428968D03*
X434519Y982718D03*
X430818D03*
X427118D03*
X436370Y985907D03*
X432669D03*
X428968D03*
X434519Y989096D03*
X430818D03*
X427118D03*
X436370Y992285D03*
X432669D03*
X428968D03*
X437551Y1046143D03*
X433850D03*
X430149D03*
X426448D03*
X435700Y1049332D03*
X432000D03*
X428299D03*
X437551Y1052521D03*
X433850D03*
X430149D03*
X426448D03*
X435700Y1055710D03*
X432000D03*
X428299D03*
X437551Y1058899D03*
X433850D03*
X430149D03*
X426448D03*
X435700Y1062088D03*
X432000D03*
X428299D03*
X437551Y1065277D03*
X433850D03*
X430149D03*
X426448D03*
X435700Y1068466D03*
X432000D03*
X428299D03*
X437551Y1071655D03*
X433850D03*
X430149D03*
X426448D03*
X435700Y1074844D03*
X432000D03*
X428299D03*
X437551Y1078033D03*
X433850D03*
X430149D03*
X426448D03*
X435700Y1081222D03*
X432000D03*
X428299D03*
X437551Y1084411D03*
X433850D03*
X430149D03*
X426448D03*
X435700Y1087600D03*
X432000D03*
X428299D03*
X437551Y1090789D03*
X433850D03*
X430149D03*
X426448D03*
X435700Y1093978D03*
X432000D03*
X428299D03*
X437551Y1097167D03*
X433850D03*
X430149D03*
X426448D03*
X435700Y1100356D03*
X432000D03*
X428299D03*
X437551Y1103545D03*
X433850D03*
X430149D03*
X426448D03*
X435700Y1106734D03*
X432000D03*
X428299D03*
X437551Y1109923D03*
X433850D03*
X430149D03*
X426448D03*
X435700Y1113112D03*
X432000D03*
X428299D03*
X437551Y1116301D03*
X433850D03*
X430149D03*
X426448D03*
X435700Y1119490D03*
X432000D03*
X428299D03*
X437551Y1122679D03*
X433850D03*
X430149D03*
X426448D03*
X435700Y1125868D03*
X432000D03*
X428299D03*
X437551Y1129057D03*
X433850D03*
X430149D03*
X426448D03*
X435700Y1132246D03*
X432000D03*
X428299D03*
X437551Y1135434D03*
X433850D03*
X430149D03*
X426448D03*
X435700Y1138623D03*
X432000D03*
X428299D03*
X437551Y1141812D03*
X433850D03*
X430149D03*
X426448D03*
X435700Y1145001D03*
X432000D03*
X428299D03*
X437551Y1148190D03*
X433850D03*
X430149D03*
X426448D03*
X435700Y1151379D03*
X432000D03*
X428299D03*
X437551Y1154568D03*
X433850D03*
X430149D03*
X426448D03*
X435700Y1157757D03*
X432000D03*
X428299D03*
X437551Y1160946D03*
X433850D03*
X430149D03*
X426448D03*
X432000Y1164135D03*
X428299D03*
X453023Y874293D03*
X449322D03*
X454874Y877482D03*
X451173D03*
X447472D03*
X443771D03*
X453023Y880671D03*
X449322D03*
X445622D03*
X454874Y883860D03*
X451173D03*
X447472D03*
X443771D03*
X453023Y887049D03*
X449322D03*
X445622D03*
X454874Y890238D03*
X451173D03*
X447472D03*
X443771D03*
X453023Y893427D03*
X449322D03*
X445622D03*
X454874Y896616D03*
X451173D03*
X447472D03*
X443771D03*
X453023Y899805D03*
X449322D03*
X445622D03*
X454874Y902994D03*
X451173D03*
X447472D03*
X443771D03*
X453023Y906182D03*
X449322D03*
X445622D03*
X454874Y909371D03*
X451173D03*
X447472D03*
X443771D03*
X453023Y912560D03*
X449322D03*
X445622D03*
X454874Y915749D03*
X451173D03*
X447472D03*
X443771D03*
X453023Y918938D03*
X449322D03*
X445622D03*
X454874Y922127D03*
X451173D03*
X447472D03*
X443771D03*
X453023Y925316D03*
X449322D03*
X445622D03*
X454874Y928505D03*
X451173D03*
X447472D03*
X443771D03*
X453023Y931694D03*
X449322D03*
X445622D03*
X454874Y934883D03*
X451173D03*
X447472D03*
X443771D03*
X453023Y938072D03*
X449322D03*
X445622D03*
X454874Y941261D03*
X451173D03*
X447472D03*
X443771D03*
X453023Y944450D03*
X449322D03*
X445622D03*
X454874Y947639D03*
X451173D03*
X447472D03*
X443771D03*
X453023Y950828D03*
X449322D03*
X445622D03*
X454874Y954017D03*
X451173D03*
X447472D03*
X443771D03*
X453023Y957206D03*
X449322D03*
X445622D03*
X454874Y960395D03*
X451173D03*
X447472D03*
X443771D03*
X453023Y963584D03*
X449322D03*
X445622D03*
X454874Y966773D03*
X451173D03*
X447472D03*
X443771D03*
X453023Y969962D03*
X449322D03*
X445622D03*
X454874Y973151D03*
X451173D03*
X447472D03*
X443771D03*
X453023Y976340D03*
X449322D03*
X445622D03*
X454874Y979529D03*
X451173D03*
X447472D03*
X443771D03*
X453023Y982718D03*
X449322D03*
X445622D03*
X454874Y985907D03*
X451173D03*
X447472D03*
X443771D03*
X453023Y989096D03*
X449322D03*
X445622D03*
X454874Y992285D03*
X451173D03*
X447472D03*
X443771D03*
X452354Y1046143D03*
X448653D03*
X444952D03*
X454204Y1049332D03*
X450504D03*
X446803D03*
X452354Y1052521D03*
X448653D03*
X444952D03*
X454204Y1055710D03*
X450504D03*
X446803D03*
X452354Y1058899D03*
X448653D03*
X444952D03*
X454204Y1062088D03*
X450504D03*
X446803D03*
X452354Y1065277D03*
X448653D03*
X444952D03*
X454204Y1068466D03*
X450504D03*
X446803D03*
X452354Y1071655D03*
X448653D03*
X444952D03*
X454204Y1074844D03*
X450504D03*
X446803D03*
X452354Y1078033D03*
X448653D03*
X444952D03*
X454204Y1081222D03*
X450504D03*
X446803D03*
X452354Y1084411D03*
X448653D03*
X444952D03*
X454204Y1087600D03*
X450504D03*
X446803D03*
X452354Y1090789D03*
X448653D03*
X444952D03*
X454204Y1093978D03*
X450504D03*
X446803D03*
X452354Y1097167D03*
X448653D03*
X444952D03*
X454204Y1100356D03*
X450504D03*
X446803D03*
X452354Y1103545D03*
X448653D03*
X444952D03*
X454204Y1106734D03*
X450504D03*
X446803D03*
X452354Y1109923D03*
X448653D03*
X444952D03*
X454204Y1113112D03*
X450504D03*
X446803D03*
X452354Y1116301D03*
X448653D03*
X444952D03*
X454204Y1119490D03*
X450504D03*
X446803D03*
X452354Y1122679D03*
X448653D03*
X444952D03*
X454204Y1125868D03*
X450504D03*
X446803D03*
X452354Y1129057D03*
X448653D03*
X444952D03*
X454204Y1132246D03*
X450504D03*
X446803D03*
X452354Y1135434D03*
X448653D03*
X444952D03*
X454204Y1138623D03*
X450504D03*
X446803D03*
X452354Y1141812D03*
X448653D03*
X444952D03*
X454204Y1145001D03*
X450504D03*
X446803D03*
X452354Y1148190D03*
X448653D03*
X444952D03*
X454204Y1151379D03*
X450504D03*
X446803D03*
X452354Y1154568D03*
X448653D03*
X444952D03*
X454204Y1157757D03*
X450504D03*
X446803D03*
X452354Y1160946D03*
X448653D03*
X444952D03*
X454204Y1164135D03*
X450504D03*
X464126Y874293D03*
X460425D03*
X456724D03*
X469677Y877482D03*
X465976D03*
X462275D03*
X458574D03*
X467826Y880671D03*
X464126D03*
X460425D03*
X456724D03*
X469677Y883860D03*
X465976D03*
X462275D03*
X458574D03*
X467826Y887049D03*
X464126D03*
X460425D03*
X456724D03*
X469677Y890238D03*
X465976D03*
X462275D03*
X458574D03*
X467826Y893427D03*
X464126D03*
X460425D03*
X456724D03*
X469677Y896616D03*
X465976D03*
X462275D03*
X458574D03*
X467826Y899805D03*
X464126D03*
X460425D03*
X456724D03*
X469677Y902994D03*
X465976D03*
X462275D03*
X458574D03*
X467826Y906182D03*
X464126D03*
X460425D03*
X456724D03*
X469677Y909371D03*
X465976D03*
X462275D03*
X458574D03*
X467826Y912560D03*
X464126D03*
X460425D03*
X456724D03*
X469677Y915749D03*
X465976D03*
X462275D03*
X458574D03*
X467826Y918938D03*
X464126D03*
X460425D03*
X456724D03*
X469677Y922127D03*
X465976D03*
X462275D03*
X458574D03*
X467826Y925316D03*
X464126D03*
X460425D03*
X456724D03*
X469677Y928505D03*
X465976D03*
X462275D03*
X458574D03*
X467826Y931694D03*
X464126D03*
X460425D03*
X456724D03*
X469677Y934883D03*
X465976D03*
X462275D03*
X458574D03*
X467826Y938072D03*
X464126D03*
X460425D03*
X456724D03*
X469677Y941261D03*
X465976D03*
X462275D03*
X458574D03*
X467826Y944450D03*
X464126D03*
X460425D03*
X456724D03*
X469677Y947639D03*
X465976D03*
X462275D03*
X458574D03*
X467826Y950828D03*
X464126D03*
X460425D03*
X456724D03*
X469677Y954017D03*
X465976D03*
X462275D03*
X458574D03*
X467826Y957206D03*
X464126D03*
X460425D03*
X456724D03*
X469677Y960395D03*
X465976D03*
X462275D03*
X458574D03*
X467826Y963584D03*
X464126D03*
X460425D03*
X456724D03*
X469677Y966773D03*
X465976D03*
X462275D03*
X458574D03*
X467826Y969962D03*
X464126D03*
X460425D03*
X456724D03*
X469677Y973151D03*
X465976D03*
X462275D03*
X458574D03*
X467826Y976340D03*
X464126D03*
X460425D03*
X456724D03*
X469677Y979529D03*
X465976D03*
X462275D03*
X458574D03*
X467826Y982718D03*
X464126D03*
X460425D03*
X456724D03*
X469677Y985907D03*
X465976D03*
X462275D03*
X458574D03*
X467826Y989096D03*
X464126D03*
X460425D03*
X456724D03*
X469677Y992285D03*
X465976D03*
X462275D03*
X458574D03*
X467157Y1046143D03*
X463456D03*
X459755D03*
X456055D03*
X469007Y1049332D03*
X465307D03*
X461606D03*
X457905D03*
X467157Y1052521D03*
X463456D03*
X459755D03*
X456055D03*
X469007Y1055710D03*
X465307D03*
X461606D03*
X457905D03*
X467157Y1058899D03*
X463456D03*
X459755D03*
X456055D03*
X469007Y1062088D03*
X465307D03*
X461606D03*
X457905D03*
X467157Y1065277D03*
X463456D03*
X459755D03*
X456055D03*
X469007Y1068466D03*
X465307D03*
X461606D03*
X457905D03*
X467157Y1071655D03*
X463456D03*
X459755D03*
X456055D03*
X469007Y1074844D03*
X465307D03*
X461606D03*
X457905D03*
X467157Y1078033D03*
X463456D03*
X459755D03*
X456055D03*
X469007Y1081222D03*
X465307D03*
X461606D03*
X457905D03*
X467157Y1084411D03*
X463456D03*
X459755D03*
X456055D03*
X469007Y1087600D03*
X465307D03*
X461606D03*
X457905D03*
X467157Y1090789D03*
X463456D03*
X459755D03*
X456055D03*
X469007Y1093978D03*
X465307D03*
X461606D03*
X457905D03*
X467157Y1097167D03*
X463456D03*
X459755D03*
X456055D03*
X469007Y1100356D03*
X465307D03*
X461606D03*
X457905D03*
X467157Y1103545D03*
X463456D03*
X459755D03*
X456055D03*
X469007Y1106734D03*
X465307D03*
X461606D03*
X457905D03*
X467157Y1109923D03*
X463456D03*
X459755D03*
X456055D03*
X469007Y1113112D03*
X465307D03*
X461606D03*
X457905D03*
X467157Y1116301D03*
X463456D03*
X459755D03*
X456055D03*
X469007Y1119490D03*
X465307D03*
X461606D03*
X457905D03*
X467157Y1122679D03*
X463456D03*
X459755D03*
X456055D03*
X469007Y1125868D03*
X465307D03*
X461606D03*
X457905D03*
X467157Y1129057D03*
X463456D03*
X459755D03*
X456055D03*
X469007Y1132246D03*
X465307D03*
X461606D03*
X457905D03*
X467157Y1135434D03*
X463456D03*
X459755D03*
X456055D03*
X469007Y1138623D03*
X465307D03*
X461606D03*
X457905D03*
X467157Y1141812D03*
X463456D03*
X459755D03*
X456055D03*
X469007Y1145001D03*
X465307D03*
X461606D03*
X457905D03*
X467157Y1148190D03*
X463456D03*
X459755D03*
X456055D03*
X469007Y1151379D03*
X465307D03*
X461606D03*
X457905D03*
X467157Y1154568D03*
X463456D03*
X459755D03*
X456055D03*
X469007Y1157757D03*
X465307D03*
X461606D03*
X457905D03*
X467157Y1160946D03*
X463456D03*
X459755D03*
X456055D03*
X465307Y1164135D03*
X461606D03*
X457905D03*
X482629Y874293D03*
X478929D03*
X475228D03*
X471527D03*
X484480Y877482D03*
X480779D03*
X477078D03*
X473378D03*
X482629Y880671D03*
X478929D03*
X475228D03*
X471527D03*
X484480Y883860D03*
X480779D03*
X477078D03*
X473378D03*
X482629Y887049D03*
X478929D03*
X475228D03*
X471527D03*
X484480Y890238D03*
X480779D03*
X477078D03*
X473378D03*
X482629Y893427D03*
X478929D03*
X475228D03*
X471527D03*
X484480Y896616D03*
X480779D03*
X477078D03*
X473378D03*
X482629Y899805D03*
X478929D03*
X475228D03*
X471527D03*
X484480Y902994D03*
X480779D03*
X477078D03*
X473378D03*
X482629Y906182D03*
X478929D03*
X475228D03*
X471527D03*
X484480Y909371D03*
X480779D03*
X477078D03*
X473378D03*
X482629Y912560D03*
X478929D03*
X475228D03*
X471527D03*
X484480Y915749D03*
X480779D03*
X477078D03*
X473378D03*
X482629Y918938D03*
X478929D03*
X475228D03*
X471527D03*
X484480Y922127D03*
X480779D03*
X477078D03*
X473378D03*
X482629Y925316D03*
X478929D03*
X475228D03*
X471527D03*
X484480Y928505D03*
X480779D03*
X477078D03*
X473378D03*
X482629Y931694D03*
X478929D03*
X475228D03*
X471527D03*
X484480Y934883D03*
X480779D03*
X477078D03*
X473378D03*
X482629Y938072D03*
X478929D03*
X475228D03*
X471527D03*
X484480Y941261D03*
X480779D03*
X477078D03*
X473378D03*
X482629Y944450D03*
X478929D03*
X475228D03*
X471527D03*
X484480Y947639D03*
X480779D03*
X477078D03*
X473378D03*
X482629Y950828D03*
X478929D03*
X475228D03*
X471527D03*
X484480Y954017D03*
X480779D03*
X477078D03*
X473378D03*
X482629Y957206D03*
X478929D03*
X475228D03*
X471527D03*
X484480Y960395D03*
X480779D03*
X477078D03*
X473378D03*
X482629Y963584D03*
X478929D03*
X475228D03*
X471527D03*
X484480Y966773D03*
X480779D03*
X477078D03*
X473378D03*
X482629Y969962D03*
X478929D03*
X475228D03*
X471527D03*
X484480Y973151D03*
X480779D03*
X477078D03*
X473378D03*
X482629Y976340D03*
X478929D03*
X475228D03*
X471527D03*
X484480Y979529D03*
X480779D03*
X477078D03*
X473378D03*
X482629Y982718D03*
X478929D03*
X475228D03*
X471527D03*
X484480Y985907D03*
X480779D03*
X477078D03*
X473378D03*
X482629Y989096D03*
X478929D03*
X475228D03*
X471527D03*
X484480Y992285D03*
X480779D03*
X477078D03*
X473378D03*
X482629Y995474D03*
X478929D03*
X475228D03*
X484480Y998663D03*
X480779D03*
X477078D03*
X482629Y1001852D03*
X478929D03*
X475228D03*
X484480Y1005041D03*
X480779D03*
X477078D03*
X482629Y1008230D03*
X478929D03*
X475228D03*
X484480Y1011419D03*
X480779D03*
X477078D03*
X481960Y1027009D03*
X478259D03*
X483811Y1030198D03*
X480110D03*
X476409D03*
X481960Y1033387D03*
X478259D03*
X483811Y1036576D03*
X480110D03*
X476409D03*
X481960Y1039765D03*
X478259D03*
X483811Y1042954D03*
X480110D03*
X476409D03*
X481960Y1046143D03*
X478259D03*
X474559D03*
X470858D03*
X483811Y1049332D03*
X480110D03*
X476409D03*
X472708D03*
X481960Y1052521D03*
X478259D03*
X474559D03*
X470858D03*
X483811Y1055710D03*
X480110D03*
X476409D03*
X472708D03*
X481960Y1058899D03*
X478259D03*
X474559D03*
X470858D03*
X483811Y1062088D03*
X480110D03*
X476409D03*
X472708D03*
X481960Y1065277D03*
X478259D03*
X474559D03*
X470858D03*
X483811Y1068466D03*
X480110D03*
X476409D03*
X472708D03*
X481960Y1071655D03*
X478259D03*
X474559D03*
X470858D03*
X483811Y1074844D03*
X480110D03*
X476409D03*
X472708D03*
X481960Y1078033D03*
X478259D03*
X474559D03*
X470858D03*
X483811Y1081222D03*
X480110D03*
X476409D03*
X472708D03*
X481960Y1084411D03*
X478259D03*
X474559D03*
X470858D03*
X483811Y1087600D03*
X480110D03*
X476409D03*
X472708D03*
X481960Y1090789D03*
X478259D03*
X474559D03*
X470858D03*
X483811Y1093978D03*
X480110D03*
X476409D03*
X472708D03*
X481960Y1097167D03*
X478259D03*
X474559D03*
X470858D03*
X483811Y1100356D03*
X480110D03*
X476409D03*
X472708D03*
X481960Y1103545D03*
X478259D03*
X474559D03*
X470858D03*
X483811Y1106734D03*
X480110D03*
X476409D03*
X472708D03*
X481960Y1109923D03*
X478259D03*
X474559D03*
X470858D03*
X483811Y1113112D03*
X480110D03*
X476409D03*
X472708D03*
X481960Y1116301D03*
X478259D03*
X474559D03*
X470858D03*
X483811Y1119490D03*
X480110D03*
X476409D03*
X472708D03*
X481960Y1122679D03*
X478259D03*
X474559D03*
X470858D03*
X483811Y1125868D03*
X480110D03*
X476409D03*
X472708D03*
X481960Y1129057D03*
X478259D03*
X474559D03*
X470858D03*
X483811Y1132246D03*
X480110D03*
X476409D03*
X472708D03*
X481960Y1135434D03*
X478259D03*
X474559D03*
X470858D03*
X483811Y1138623D03*
X480110D03*
X476409D03*
X472708D03*
X481960Y1141812D03*
X478259D03*
X474559D03*
X470858D03*
X483811Y1145001D03*
X480110D03*
X476409D03*
X472708D03*
X481960Y1148190D03*
X478259D03*
X474559D03*
X470858D03*
X483811Y1151379D03*
X480110D03*
X476409D03*
X472708D03*
X481960Y1154568D03*
X478259D03*
X474559D03*
X470858D03*
X483811Y1157757D03*
X480110D03*
X476409D03*
X472708D03*
X481960Y1160946D03*
X478259D03*
X474559D03*
X470858D03*
X483811Y1164135D03*
X480110D03*
X476409D03*
X472708D03*
X497433Y874293D03*
X493732D03*
X486330D03*
X499283Y877482D03*
X495582D03*
X491881D03*
X488181D03*
X497433Y880671D03*
X493732D03*
X490031D03*
X486330D03*
X499283Y883860D03*
X495582D03*
X491881D03*
X488181D03*
X497433Y887049D03*
X493732D03*
X490031D03*
X486330D03*
X499283Y890238D03*
X495582D03*
X491881D03*
X488181D03*
X497433Y893427D03*
X493732D03*
X490031D03*
X486330D03*
X499283Y896616D03*
X495582D03*
X491881D03*
X488181D03*
X497433Y899805D03*
X493732D03*
X490031D03*
X486330D03*
X499283Y902994D03*
X495582D03*
X491881D03*
X488181D03*
X497433Y906182D03*
X493732D03*
X490031D03*
X486330D03*
X499283Y909371D03*
X495582D03*
X491881D03*
X488181D03*
X497433Y912560D03*
X493732D03*
X490031D03*
X486330D03*
X499283Y915749D03*
X495582D03*
X491881D03*
X488181D03*
X497433Y918938D03*
X493732D03*
X490031D03*
X486330D03*
X499283Y922127D03*
X495582D03*
X491881D03*
X488181D03*
X497433Y925316D03*
X493732D03*
X490031D03*
X486330D03*
X499283Y928505D03*
X495582D03*
X491881D03*
X488181D03*
X497433Y931694D03*
X493732D03*
X490031D03*
X486330D03*
X499283Y934883D03*
X495582D03*
X491881D03*
X488181D03*
X497433Y938072D03*
X493732D03*
X490031D03*
X486330D03*
X499283Y941261D03*
X495582D03*
X491881D03*
X488181D03*
X497433Y944450D03*
X493732D03*
X490031D03*
X486330D03*
X499283Y947639D03*
X495582D03*
X491881D03*
X488181D03*
X497433Y950828D03*
X493732D03*
X490031D03*
X486330D03*
X499283Y954017D03*
X495582D03*
X491881D03*
X488181D03*
X497433Y957206D03*
X493732D03*
X490031D03*
X486330D03*
X499283Y960395D03*
X495582D03*
X491881D03*
X488181D03*
X497433Y963584D03*
X493732D03*
X490031D03*
X486330D03*
X499283Y966773D03*
X495582D03*
X491881D03*
X488181D03*
X497433Y969962D03*
X493732D03*
X490031D03*
X486330D03*
X499283Y973151D03*
X495582D03*
X491881D03*
X488181D03*
X497433Y976340D03*
X493732D03*
X490031D03*
X486330D03*
X499283Y979529D03*
X495582D03*
X491881D03*
X488181D03*
X497433Y982718D03*
X493732D03*
X490031D03*
X486330D03*
X499283Y985907D03*
X495582D03*
X491881D03*
X488181D03*
X497433Y989096D03*
X493732D03*
X490031D03*
X486330D03*
X499283Y992285D03*
X495582D03*
X491881D03*
X488181D03*
X497433Y995474D03*
X493732D03*
X490031D03*
X486330D03*
X499283Y998663D03*
X495582D03*
X491881D03*
X488181D03*
X497433Y1001852D03*
X493732D03*
X490031D03*
X486330D03*
X499283Y1005041D03*
X495582D03*
X491881D03*
X488181D03*
X497433Y1008230D03*
X493732D03*
X490031D03*
X486330D03*
X499283Y1011419D03*
X495582D03*
X491881D03*
X488181D03*
X496763Y1027009D03*
X493063D03*
X489362D03*
X485661D03*
X498614Y1030198D03*
X494913D03*
X491212D03*
X487511D03*
X496763Y1033387D03*
X493063D03*
X489362D03*
X485661D03*
X498614Y1036576D03*
X494913D03*
X491212D03*
X487511D03*
X496763Y1039765D03*
X493063D03*
X489362D03*
X485661D03*
X498614Y1042954D03*
X494913D03*
X491212D03*
X487511D03*
X496763Y1046143D03*
X493063D03*
X489362D03*
X485661D03*
X498614Y1049332D03*
X494913D03*
X491212D03*
X487511D03*
X496763Y1052521D03*
X493063D03*
X489362D03*
X485661D03*
X498614Y1055710D03*
X494913D03*
X491212D03*
X487511D03*
X496763Y1058899D03*
X493063D03*
X489362D03*
X485661D03*
X498614Y1062088D03*
X494913D03*
X491212D03*
X487511D03*
X496763Y1065277D03*
X493063D03*
X489362D03*
X485661D03*
X498614Y1068466D03*
X494913D03*
X491212D03*
X487511D03*
X496763Y1071655D03*
X493063D03*
X489362D03*
X485661D03*
X498614Y1074844D03*
X494913D03*
X491212D03*
X487511D03*
X496763Y1078033D03*
X493063D03*
X489362D03*
X485661D03*
X498614Y1081222D03*
X494913D03*
X491212D03*
X487511D03*
X496763Y1084411D03*
X493063D03*
X489362D03*
X485661D03*
X498614Y1087600D03*
X494913D03*
X491212D03*
X487511D03*
X496763Y1090789D03*
X493063D03*
X489362D03*
X485661D03*
X498614Y1093978D03*
X494913D03*
X491212D03*
X487511D03*
X496763Y1097167D03*
X493063D03*
X489362D03*
X485661D03*
X498614Y1100356D03*
X494913D03*
X491212D03*
X487511D03*
X496763Y1103545D03*
X493063D03*
X489362D03*
X485661D03*
X498614Y1106734D03*
X494913D03*
X491212D03*
X487511D03*
X496763Y1109923D03*
X493063D03*
X489362D03*
X485661D03*
X498614Y1113112D03*
X494913D03*
X491212D03*
X487511D03*
X496763Y1116301D03*
X493063D03*
X489362D03*
X485661D03*
X498614Y1119490D03*
X494913D03*
X491212D03*
X487511D03*
X496763Y1122679D03*
X493063D03*
X489362D03*
X485661D03*
X498614Y1125868D03*
X494913D03*
X491212D03*
X487511D03*
X496763Y1129057D03*
X493063D03*
X489362D03*
X485661D03*
X498614Y1132246D03*
X494913D03*
X491212D03*
X487511D03*
X496763Y1135434D03*
X493063D03*
X489362D03*
X485661D03*
X498614Y1138623D03*
X494913D03*
X491212D03*
X487511D03*
X496763Y1141812D03*
X493063D03*
X489362D03*
X485661D03*
X498614Y1145001D03*
X494913D03*
X491212D03*
X487511D03*
X496763Y1148190D03*
X493063D03*
X489362D03*
X485661D03*
X498614Y1151379D03*
X494913D03*
X491212D03*
X487511D03*
X496763Y1154568D03*
X493063D03*
X489362D03*
X485661D03*
X498614Y1157757D03*
X494913D03*
X491212D03*
X487511D03*
X496763Y1160946D03*
X493063D03*
X489362D03*
X485661D03*
X498614Y1164135D03*
X494913D03*
X487511D03*
X508535Y874293D03*
X504834D03*
X501133D03*
X514086Y877482D03*
X510385D03*
X506685D03*
X502984D03*
X512236Y880671D03*
X508535D03*
X504834D03*
X501133D03*
X514086Y883860D03*
X510385D03*
X506685D03*
X502984D03*
X512236Y887049D03*
X508535D03*
X504834D03*
X501133D03*
X514086Y890238D03*
X510385D03*
X506685D03*
X502984D03*
X512236Y893427D03*
X508535D03*
X504834D03*
X501133D03*
X514086Y896616D03*
X510385D03*
X506685D03*
X502984D03*
X512236Y899805D03*
X508535D03*
X504834D03*
X501133D03*
X514086Y902994D03*
X510385D03*
X506685D03*
X502984D03*
X512236Y906182D03*
X508535D03*
X504834D03*
X501133D03*
X514086Y909371D03*
X510385D03*
X506685D03*
X502984D03*
X512236Y912560D03*
X508535D03*
X504834D03*
X501133D03*
X514086Y915749D03*
X510385D03*
X506685D03*
X502984D03*
X512236Y918938D03*
X508535D03*
X504834D03*
X501133D03*
X514086Y922127D03*
X510385D03*
X506685D03*
X502984D03*
X512236Y925316D03*
X508535D03*
X504834D03*
X501133D03*
X514086Y928505D03*
X510385D03*
X506685D03*
X502984D03*
X512236Y931694D03*
X508535D03*
X504834D03*
X501133D03*
X514086Y934883D03*
X510385D03*
X506685D03*
X502984D03*
X512236Y938072D03*
X508535D03*
X504834D03*
X501133D03*
X514086Y941261D03*
X510385D03*
X506685D03*
X502984D03*
X512236Y944450D03*
X508535D03*
X504834D03*
X501133D03*
X514086Y947639D03*
X510385D03*
X506685D03*
X502984D03*
X512236Y950828D03*
X508535D03*
X504834D03*
X501133D03*
X514086Y954017D03*
X510385D03*
X506685D03*
X502984D03*
X512236Y957206D03*
X508535D03*
X504834D03*
X501133D03*
X514086Y960395D03*
X510385D03*
X506685D03*
X502984D03*
X512236Y963584D03*
X508535D03*
X504834D03*
X501133D03*
X514086Y966773D03*
X510385D03*
X506685D03*
X502984D03*
X512236Y969962D03*
X508535D03*
X504834D03*
X501133D03*
X514086Y973151D03*
X510385D03*
X506685D03*
X502984D03*
X512236Y976340D03*
X508535D03*
X504834D03*
X501133D03*
X514086Y979529D03*
X510385D03*
X506685D03*
X502984D03*
X512236Y982718D03*
X508535D03*
X504834D03*
X501133D03*
X514086Y985907D03*
X510385D03*
X506685D03*
X502984D03*
X512236Y989096D03*
X508535D03*
X504834D03*
X501133D03*
X514086Y992285D03*
X510385D03*
X506685D03*
X502984D03*
X512236Y995474D03*
X508535D03*
X504834D03*
X501133D03*
X514086Y998663D03*
X510385D03*
X506685D03*
X502984D03*
X512236Y1001852D03*
X508535D03*
X504834D03*
X501133D03*
X514086Y1005041D03*
X510385D03*
X506685D03*
X502984D03*
X512236Y1008230D03*
X508535D03*
X504834D03*
X501133D03*
X514086Y1011419D03*
X510385D03*
X506685D03*
X502984D03*
X511567Y1027009D03*
X507866D03*
X504165D03*
X500464D03*
X513417Y1030198D03*
X509716D03*
X506015D03*
X502315D03*
X511567Y1033387D03*
X507866D03*
X504165D03*
X500464D03*
X513417Y1036576D03*
X509716D03*
X506015D03*
X502315D03*
X511567Y1039765D03*
X507866D03*
X504165D03*
X500464D03*
X513417Y1042954D03*
X509716D03*
X506015D03*
X502315D03*
X511567Y1046143D03*
X507866D03*
X504165D03*
X500464D03*
X513417Y1049332D03*
X509716D03*
X506015D03*
X502315D03*
X511567Y1052521D03*
X507866D03*
X504165D03*
X500464D03*
X513417Y1055710D03*
X509716D03*
X506015D03*
X502315D03*
X511567Y1058899D03*
X507866D03*
X504165D03*
X500464D03*
X513417Y1062088D03*
X509716D03*
X506015D03*
X502315D03*
X511567Y1065277D03*
X507866D03*
X504165D03*
X500464D03*
X513417Y1068466D03*
X509716D03*
X506015D03*
X502315D03*
X511567Y1071655D03*
X507866D03*
X504165D03*
X500464D03*
X513417Y1074844D03*
X509716D03*
X506015D03*
X502315D03*
X511567Y1078033D03*
X507866D03*
X504165D03*
X500464D03*
X513417Y1081222D03*
X509716D03*
X506015D03*
X502315D03*
X511567Y1084411D03*
X507866D03*
X504165D03*
X500464D03*
X513417Y1087600D03*
X509716D03*
X506015D03*
X502315D03*
X511567Y1090789D03*
X507866D03*
X504165D03*
X500464D03*
X513417Y1093978D03*
X509716D03*
X506015D03*
X502315D03*
X511567Y1097167D03*
X507866D03*
X504165D03*
X500464D03*
X513417Y1100356D03*
X509716D03*
X506015D03*
X502315D03*
X511567Y1103545D03*
X507866D03*
X504165D03*
X500464D03*
X513417Y1106734D03*
X509716D03*
X506015D03*
X502315D03*
X511567Y1109923D03*
X507866D03*
X504165D03*
X500464D03*
X513417Y1113112D03*
X509716D03*
X506015D03*
X502315D03*
X511567Y1116301D03*
X507866D03*
X504165D03*
X500464D03*
X513417Y1119490D03*
X509716D03*
X506015D03*
X502315D03*
X511567Y1122679D03*
X507866D03*
X504165D03*
X500464D03*
X513417Y1125868D03*
X509716D03*
X506015D03*
X502315D03*
X511567Y1129057D03*
X507866D03*
X504165D03*
X500464D03*
X513417Y1132246D03*
X509716D03*
X506015D03*
X502315D03*
X511567Y1135434D03*
X507866D03*
X504165D03*
X500464D03*
X513417Y1138623D03*
X509716D03*
X506015D03*
X502315D03*
X511567Y1141812D03*
X507866D03*
X504165D03*
X500464D03*
X513417Y1145001D03*
X509716D03*
X506015D03*
X502315D03*
X511567Y1148190D03*
X507866D03*
X504165D03*
X500464D03*
X513417Y1151379D03*
X509716D03*
X506015D03*
X502315D03*
X511567Y1154568D03*
X507866D03*
X504165D03*
X500464D03*
X513417Y1157757D03*
X509716D03*
X506015D03*
X502315D03*
X511567Y1160946D03*
X507866D03*
X504165D03*
X500464D03*
X509716Y1164135D03*
X506015D03*
X502315D03*
X527039Y874293D03*
X523338D03*
X519637D03*
X515937D03*
X528889Y877482D03*
X525189D03*
X521488D03*
X517787D03*
X527039Y880671D03*
X523338D03*
X519637D03*
X515937D03*
X528889Y883860D03*
X525189D03*
X521488D03*
X517787D03*
X527039Y887049D03*
X523338D03*
X519637D03*
X515937D03*
X528889Y890238D03*
X525189D03*
X521488D03*
X517787D03*
X527039Y893427D03*
X523338D03*
X519637D03*
X515937D03*
X528889Y896616D03*
X525189D03*
X521488D03*
X517787D03*
X527039Y899805D03*
X523338D03*
X519637D03*
X515937D03*
X528889Y902994D03*
X525189D03*
X521488D03*
X517787D03*
X527039Y906182D03*
X523338D03*
X519637D03*
X515937D03*
X528889Y909371D03*
X525189D03*
X521488D03*
X517787D03*
X527039Y912560D03*
X523338D03*
X519637D03*
X515937D03*
X528889Y915749D03*
X525189D03*
X521488D03*
X517787D03*
X527039Y918938D03*
X523338D03*
X519637D03*
X515937D03*
X528889Y922127D03*
X525189D03*
X521488D03*
X517787D03*
X527039Y925316D03*
X523338D03*
X519637D03*
X515937D03*
X528889Y928505D03*
X525189D03*
X521488D03*
X517787D03*
X527039Y931694D03*
X523338D03*
X519637D03*
X515937D03*
X528889Y934883D03*
X525189D03*
X521488D03*
X517787D03*
X527039Y938072D03*
X523338D03*
X519637D03*
X515937D03*
X528889Y941261D03*
X525189D03*
X521488D03*
X517787D03*
X527039Y944450D03*
X523338D03*
X519637D03*
X515937D03*
X528889Y947639D03*
X525189D03*
X521488D03*
X517787D03*
X527039Y950828D03*
X523338D03*
X519637D03*
X515937D03*
X528889Y954017D03*
X525189D03*
X521488D03*
X517787D03*
X527039Y957206D03*
X523338D03*
X519637D03*
X515937D03*
X528889Y960395D03*
X525189D03*
X521488D03*
X517787D03*
X527039Y963584D03*
X523338D03*
X519637D03*
X515937D03*
X528889Y966773D03*
X525189D03*
X521488D03*
X517787D03*
X527039Y969962D03*
X523338D03*
X519637D03*
X515937D03*
X528889Y973151D03*
X525189D03*
X521488D03*
X517787D03*
X527039Y976340D03*
X523338D03*
X519637D03*
X515937D03*
X528889Y979529D03*
X525189D03*
X521488D03*
X517787D03*
X527039Y982718D03*
X523338D03*
X519637D03*
X515937D03*
X528889Y985907D03*
X525189D03*
X521488D03*
X517787D03*
X527039Y989096D03*
X523338D03*
X519637D03*
X515937D03*
X528889Y992285D03*
X525189D03*
X521488D03*
X517787D03*
X527039Y995474D03*
X523338D03*
X519637D03*
X515937D03*
X528889Y998663D03*
X525189D03*
X521488D03*
X517787D03*
X527039Y1001852D03*
X523338D03*
X519637D03*
X515937D03*
X528889Y1005041D03*
X525189D03*
X521488D03*
X517787D03*
X527039Y1008230D03*
X523338D03*
X519637D03*
X515937D03*
X528889Y1011419D03*
X525189D03*
X521488D03*
X517787D03*
X526370Y1027009D03*
X522669D03*
X518968D03*
X515267D03*
X528220Y1030198D03*
X524519D03*
X520818D03*
X517118D03*
X526370Y1033387D03*
X522669D03*
X518968D03*
X515267D03*
X528220Y1036576D03*
X524519D03*
X520818D03*
X517118D03*
X526370Y1039765D03*
X522669D03*
X518968D03*
X515267D03*
X528220Y1042954D03*
X524519D03*
X520818D03*
X517118D03*
X526370Y1046143D03*
X522669D03*
X518968D03*
X515267D03*
X528220Y1049332D03*
X524519D03*
X520818D03*
X517118D03*
X526370Y1052521D03*
X522669D03*
X518968D03*
X515267D03*
X528220Y1055710D03*
X524519D03*
X520818D03*
X517118D03*
X526370Y1058899D03*
X522669D03*
X518968D03*
X515267D03*
X528220Y1062088D03*
X524519D03*
X520818D03*
X517118D03*
X526370Y1065277D03*
X522669D03*
X518968D03*
X515267D03*
X528220Y1068466D03*
X524519D03*
X520818D03*
X517118D03*
X526370Y1071655D03*
X522669D03*
X518968D03*
X515267D03*
X528220Y1074844D03*
X524519D03*
X520818D03*
X517118D03*
X526370Y1078033D03*
X522669D03*
X518968D03*
X515267D03*
X528220Y1081222D03*
X524519D03*
X520818D03*
X517118D03*
X526370Y1084411D03*
X522669D03*
X518968D03*
X515267D03*
X528220Y1087600D03*
X524519D03*
X520818D03*
X517118D03*
X526370Y1090789D03*
X522669D03*
X518968D03*
X515267D03*
X528220Y1093978D03*
X524519D03*
X520818D03*
X517118D03*
X526370Y1097167D03*
X522669D03*
X518968D03*
X515267D03*
X528220Y1100356D03*
X524519D03*
X520818D03*
X517118D03*
X526370Y1103545D03*
X522669D03*
X518968D03*
X515267D03*
X528220Y1106734D03*
X524519D03*
X520818D03*
X517118D03*
X526370Y1109923D03*
X522669D03*
X518968D03*
X515267D03*
X528220Y1113112D03*
X524519D03*
X520818D03*
X517118D03*
X526370Y1116301D03*
X522669D03*
X518968D03*
X515267D03*
X528220Y1119490D03*
X524519D03*
X520818D03*
X517118D03*
X526370Y1122679D03*
X522669D03*
X518968D03*
X515267D03*
X528220Y1125868D03*
X524519D03*
X520818D03*
X517118D03*
X526370Y1129057D03*
X522669D03*
X518968D03*
X515267D03*
X528220Y1132246D03*
X524519D03*
X520818D03*
X517118D03*
X526370Y1135434D03*
X522669D03*
X518968D03*
X515267D03*
X528220Y1138623D03*
X524519D03*
X520818D03*
X517118D03*
X526370Y1141812D03*
X522669D03*
X518968D03*
X515267D03*
X528220Y1145001D03*
X524519D03*
X520818D03*
X517118D03*
X526370Y1148190D03*
X522669D03*
X518968D03*
X515267D03*
X528220Y1151379D03*
X524519D03*
X520818D03*
X517118D03*
X526370Y1154568D03*
X522669D03*
X518968D03*
X515267D03*
X528220Y1157757D03*
X524519D03*
X520818D03*
X517118D03*
X526370Y1160946D03*
X522669D03*
X518968D03*
X515267D03*
X528220Y1164135D03*
X524519D03*
X520818D03*
X517118D03*
X541842Y874293D03*
X538141D03*
X530740D03*
X543693Y877482D03*
X539992D03*
X536291D03*
X532590D03*
X541842Y880671D03*
X538141D03*
X534441D03*
X530740D03*
X543693Y883860D03*
X539992D03*
X536291D03*
X532590D03*
X541842Y887049D03*
X538141D03*
X534441D03*
X530740D03*
X543693Y890238D03*
X539992D03*
X536291D03*
X532590D03*
X541842Y893427D03*
X538141D03*
X534441D03*
X530740D03*
X543693Y896616D03*
X539992D03*
X536291D03*
X532590D03*
X541842Y899805D03*
X538141D03*
X534441D03*
X530740D03*
X543693Y902994D03*
X539992D03*
X536291D03*
X532590D03*
X541842Y906182D03*
X538141D03*
X534441D03*
X530740D03*
X543693Y909371D03*
X539992D03*
X536291D03*
X532590D03*
X541842Y912560D03*
X538141D03*
X534441D03*
X530740D03*
X543693Y915749D03*
X539992D03*
X536291D03*
X532590D03*
X541842Y918938D03*
X538141D03*
X534441D03*
X530740D03*
X543693Y922127D03*
X539992D03*
X536291D03*
X532590D03*
X541842Y925316D03*
X538141D03*
X534441D03*
X530740D03*
X543693Y928505D03*
X539992D03*
X536291D03*
X532590D03*
X541842Y931694D03*
X538141D03*
X534441D03*
X530740D03*
X543693Y934883D03*
X539992D03*
X536291D03*
X532590D03*
X541842Y938072D03*
X538141D03*
X534441D03*
X530740D03*
X543693Y941261D03*
X539992D03*
X536291D03*
X532590D03*
X541842Y944450D03*
X538141D03*
X534441D03*
X530740D03*
X543693Y947639D03*
X539992D03*
X536291D03*
X532590D03*
X541842Y950828D03*
X538141D03*
X534441D03*
X530740D03*
X543693Y954017D03*
X539992D03*
X536291D03*
X532590D03*
X541842Y957206D03*
X538141D03*
X534441D03*
X530740D03*
X543693Y960395D03*
X539992D03*
X536291D03*
X532590D03*
X541842Y963584D03*
X538141D03*
X534441D03*
X530740D03*
X543693Y966773D03*
X539992D03*
X536291D03*
X532590D03*
X541842Y969962D03*
X538141D03*
X534441D03*
X530740D03*
X543693Y973151D03*
X539992D03*
X536291D03*
X532590D03*
X541842Y976340D03*
X538141D03*
X534441D03*
X530740D03*
X543693Y979529D03*
X539992D03*
X536291D03*
X532590D03*
X541842Y982718D03*
X538141D03*
X534441D03*
X530740D03*
X543693Y985907D03*
X539992D03*
X536291D03*
X532590D03*
X541842Y989096D03*
X538141D03*
X534441D03*
X530740D03*
X543693Y992285D03*
X539992D03*
X536291D03*
X532590D03*
X541842Y995474D03*
X538141D03*
X534441D03*
X530740D03*
X543693Y998663D03*
X539992D03*
X536291D03*
X532590D03*
X541842Y1001852D03*
X538141D03*
X534441D03*
X530740D03*
X543693Y1005041D03*
X539992D03*
X536291D03*
X532590D03*
X541842Y1008230D03*
X538141D03*
X534441D03*
X530740D03*
X543693Y1011419D03*
X539992D03*
X536291D03*
X532590D03*
X541173Y1027009D03*
X537472D03*
X533771D03*
X530070D03*
X543023Y1030198D03*
X539322D03*
X535622D03*
X531921D03*
X541173Y1033387D03*
X537472D03*
X533771D03*
X530070D03*
X543023Y1036576D03*
X539322D03*
X535622D03*
X531921D03*
X541173Y1039765D03*
X537472D03*
X533771D03*
X530070D03*
X543023Y1042954D03*
X539322D03*
X535622D03*
X531921D03*
X541173Y1046143D03*
X537472D03*
X533771D03*
X530070D03*
X543023Y1049332D03*
X539322D03*
X535622D03*
X531921D03*
X541173Y1052521D03*
X537472D03*
X533771D03*
X530070D03*
X543023Y1055710D03*
X539322D03*
X535622D03*
X531921D03*
X541173Y1058899D03*
X537472D03*
X533771D03*
X530070D03*
X543023Y1062088D03*
X539322D03*
X535622D03*
X531921D03*
X541173Y1065277D03*
X537472D03*
X533771D03*
X530070D03*
X543023Y1068466D03*
X539322D03*
X535622D03*
X531921D03*
X541173Y1071655D03*
X537472D03*
X533771D03*
X530070D03*
X543023Y1074844D03*
X539322D03*
X535622D03*
X531921D03*
X541173Y1078033D03*
X537472D03*
X533771D03*
X530070D03*
X543023Y1081222D03*
X539322D03*
X535622D03*
X531921D03*
X541173Y1084411D03*
X537472D03*
X533771D03*
X530070D03*
X543023Y1087600D03*
X539322D03*
X535622D03*
X531921D03*
X541173Y1090789D03*
X537472D03*
X533771D03*
X530070D03*
X543023Y1093978D03*
X539322D03*
X535622D03*
X531921D03*
X541173Y1097167D03*
X537472D03*
X533771D03*
X530070D03*
X543023Y1100356D03*
X539322D03*
X535622D03*
X531921D03*
X541173Y1103545D03*
X537472D03*
X533771D03*
X530070D03*
X543023Y1106734D03*
X539322D03*
X535622D03*
X531921D03*
X541173Y1109923D03*
X537472D03*
X533771D03*
X530070D03*
X543023Y1113112D03*
X539322D03*
X535622D03*
X531921D03*
X541173Y1116301D03*
X537472D03*
X533771D03*
X530070D03*
X543023Y1119490D03*
X539322D03*
X535622D03*
X531921D03*
X541173Y1122679D03*
X537472D03*
X533771D03*
X530070D03*
X543023Y1125868D03*
X539322D03*
X535622D03*
X531921D03*
X541173Y1129057D03*
X537472D03*
X533771D03*
X530070D03*
X543023Y1132246D03*
X539322D03*
X535622D03*
X531921D03*
X541173Y1135434D03*
X537472D03*
X533771D03*
X530070D03*
X543023Y1138623D03*
X539322D03*
X535622D03*
X531921D03*
X541173Y1141812D03*
X537472D03*
X533771D03*
X530070D03*
X543023Y1145001D03*
X539322D03*
X535622D03*
X531921D03*
X541173Y1148190D03*
X537472D03*
X533771D03*
X530070D03*
X543023Y1151379D03*
X539322D03*
X535622D03*
X531921D03*
X541173Y1154568D03*
X537472D03*
X533771D03*
X530070D03*
X543023Y1157757D03*
X539322D03*
X535622D03*
X531921D03*
X541173Y1160946D03*
X537472D03*
X533771D03*
X530070D03*
X543023Y1164135D03*
X539322D03*
X531921D03*
X552944Y874293D03*
X549244D03*
X545543D03*
X558496Y877482D03*
X554795D03*
X551094D03*
X547393D03*
X556645Y880671D03*
X552944D03*
X549244D03*
X545543D03*
X558496Y883860D03*
X554795D03*
X551094D03*
X547393D03*
X556645Y887049D03*
X552944D03*
X549244D03*
X545543D03*
X558496Y890238D03*
X554795D03*
X551094D03*
X547393D03*
X556645Y893427D03*
X552944D03*
X549244D03*
X545543D03*
X558496Y896616D03*
X554795D03*
X551094D03*
X547393D03*
X556645Y899805D03*
X552944D03*
X549244D03*
X545543D03*
X558496Y902994D03*
X554795D03*
X551094D03*
X547393D03*
X556645Y906182D03*
X552944D03*
X549244D03*
X545543D03*
X558496Y909371D03*
X554795D03*
X551094D03*
X547393D03*
X556645Y912560D03*
X552944D03*
X549244D03*
X545543D03*
X558496Y915749D03*
X554795D03*
X551094D03*
X547393D03*
X556645Y918938D03*
X552944D03*
X549244D03*
X545543D03*
X558496Y922127D03*
X554795D03*
X551094D03*
X547393D03*
X556645Y925316D03*
X552944D03*
X549244D03*
X545543D03*
X558496Y928505D03*
X554795D03*
X551094D03*
X547393D03*
X556645Y931694D03*
X552944D03*
X549244D03*
X545543D03*
X558496Y934883D03*
X554795D03*
X551094D03*
X547393D03*
X556645Y938072D03*
X552944D03*
X549244D03*
X545543D03*
X558496Y941261D03*
X554795D03*
X551094D03*
X547393D03*
X556645Y944450D03*
X552944D03*
X549244D03*
X545543D03*
X558496Y947639D03*
X554795D03*
X551094D03*
X547393D03*
X556645Y950828D03*
X552944D03*
X549244D03*
X545543D03*
X558496Y954017D03*
X554795D03*
X551094D03*
X547393D03*
X556645Y957206D03*
X552944D03*
X549244D03*
X545543D03*
X558496Y960395D03*
X554795D03*
X551094D03*
X547393D03*
X556645Y963584D03*
X552944D03*
X549244D03*
X545543D03*
X558496Y966773D03*
X554795D03*
X551094D03*
X547393D03*
X556645Y969962D03*
X552944D03*
X549244D03*
X545543D03*
X558496Y973151D03*
X554795D03*
X551094D03*
X547393D03*
X556645Y976340D03*
X552944D03*
X549244D03*
X545543D03*
X558496Y979529D03*
X554795D03*
X551094D03*
X547393D03*
X556645Y982718D03*
X552944D03*
X549244D03*
X545543D03*
X558496Y985907D03*
X554795D03*
X551094D03*
X547393D03*
X556645Y989096D03*
X552944D03*
X549244D03*
X545543D03*
X558496Y992285D03*
X554795D03*
X551094D03*
X547393D03*
X556645Y995474D03*
X552944D03*
X549244D03*
X545543D03*
X558496Y998663D03*
X554795D03*
X551094D03*
X547393D03*
X556645Y1001852D03*
X552944D03*
X549244D03*
X545543D03*
X558496Y1005041D03*
X554795D03*
X551094D03*
X547393D03*
X556645Y1008230D03*
X552944D03*
X549244D03*
X545543D03*
X558496Y1011419D03*
X554795D03*
X551094D03*
X547393D03*
X555976Y1027009D03*
X552275D03*
X548574D03*
X544874D03*
X557826Y1030198D03*
X554126D03*
X550425D03*
X546724D03*
X555976Y1033387D03*
X552275D03*
X548574D03*
X544874D03*
X557826Y1036576D03*
X554126D03*
X550425D03*
X546724D03*
X555976Y1039765D03*
X552275D03*
X548574D03*
X544874D03*
X557826Y1042954D03*
X554126D03*
X550425D03*
X546724D03*
X555976Y1046143D03*
X552275D03*
X548574D03*
X544874D03*
X557826Y1049332D03*
X554126D03*
X550425D03*
X546724D03*
X555976Y1052521D03*
X552275D03*
X548574D03*
X544874D03*
X557826Y1055710D03*
X554126D03*
X550425D03*
X546724D03*
X555976Y1058899D03*
X552275D03*
X548574D03*
X544874D03*
X557826Y1062088D03*
X554126D03*
X550425D03*
X546724D03*
X555976Y1065277D03*
X552275D03*
X548574D03*
X544874D03*
X557826Y1068466D03*
X554126D03*
X550425D03*
X546724D03*
X555976Y1071655D03*
X552275D03*
X548574D03*
X544874D03*
X557826Y1074844D03*
X554126D03*
X550425D03*
X546724D03*
X555976Y1078033D03*
X552275D03*
X548574D03*
X544874D03*
X557826Y1081222D03*
X554126D03*
X550425D03*
X546724D03*
X555976Y1084411D03*
X552275D03*
X548574D03*
X544874D03*
X557826Y1087600D03*
X554126D03*
X550425D03*
X546724D03*
X555976Y1090789D03*
X552275D03*
X548574D03*
X544874D03*
X557826Y1093978D03*
X554126D03*
X550425D03*
X546724D03*
X555976Y1097167D03*
X552275D03*
X548574D03*
X544874D03*
X557826Y1100356D03*
X554126D03*
X550425D03*
X546724D03*
X555976Y1103545D03*
X552275D03*
X548574D03*
X544874D03*
X557826Y1106734D03*
X554126D03*
X550425D03*
X546724D03*
X555976Y1109923D03*
X552275D03*
X548574D03*
X544874D03*
X557826Y1113112D03*
X554126D03*
X550425D03*
X546724D03*
X555976Y1116301D03*
X552275D03*
X548574D03*
X544874D03*
X557826Y1119490D03*
X554126D03*
X550425D03*
X546724D03*
X555976Y1122679D03*
X552275D03*
X548574D03*
X544874D03*
X557826Y1125868D03*
X554126D03*
X550425D03*
X546724D03*
X555976Y1129057D03*
X552275D03*
X548574D03*
X544874D03*
X557826Y1132246D03*
X554126D03*
X550425D03*
X546724D03*
X555976Y1135434D03*
X552275D03*
X548574D03*
X544874D03*
X557826Y1138623D03*
X554126D03*
X550425D03*
X546724D03*
X555976Y1141812D03*
X552275D03*
X548574D03*
X544874D03*
X557826Y1145001D03*
X554126D03*
X550425D03*
X546724D03*
X555976Y1148190D03*
X552275D03*
X548574D03*
X544874D03*
X557826Y1151379D03*
X554126D03*
X550425D03*
X546724D03*
X555976Y1154568D03*
X552275D03*
X548574D03*
X544874D03*
X557826Y1157757D03*
X554126D03*
X550425D03*
X546724D03*
X555976Y1160946D03*
X552275D03*
X548574D03*
X544874D03*
X554126Y1164135D03*
X550425D03*
X546724D03*
X567748Y874293D03*
X564047D03*
X560346D03*
X569598Y877482D03*
X565897D03*
X562196D03*
X571448Y880671D03*
X567748D03*
X564047D03*
X560346D03*
X573299Y883860D03*
X569598D03*
X565897D03*
X562196D03*
X571448Y887049D03*
X567748D03*
X564047D03*
X560346D03*
X573299Y890238D03*
X569598D03*
X565897D03*
X562196D03*
X571448Y893427D03*
X567748D03*
X564047D03*
X560346D03*
X573299Y896616D03*
X569598D03*
X565897D03*
X562196D03*
X571448Y899805D03*
X567748D03*
X564047D03*
X560346D03*
X573299Y902994D03*
X569598D03*
X565897D03*
X562196D03*
X571448Y906182D03*
X567748D03*
X564047D03*
X560346D03*
X573299Y909371D03*
X569598D03*
X565897D03*
X562196D03*
X571448Y912560D03*
X567748D03*
X564047D03*
X560346D03*
X573299Y915749D03*
X569598D03*
X565897D03*
X562196D03*
X571448Y918938D03*
X567748D03*
X564047D03*
X560346D03*
X573299Y922127D03*
X569598D03*
X565897D03*
X562196D03*
X571448Y925316D03*
X567748D03*
X564047D03*
X560346D03*
X573299Y928505D03*
X569598D03*
X565897D03*
X562196D03*
X571448Y931694D03*
X567748D03*
X564047D03*
X560346D03*
X573299Y934883D03*
X569598D03*
X565897D03*
X562196D03*
X571448Y938072D03*
X567748D03*
X564047D03*
X560346D03*
X573299Y941261D03*
X569598D03*
X565897D03*
X562196D03*
X571448Y944450D03*
X567748D03*
X564047D03*
X560346D03*
X573299Y947639D03*
X569598D03*
X565897D03*
X562196D03*
X571448Y950828D03*
X567748D03*
X564047D03*
X560346D03*
X573299Y954017D03*
X569598D03*
X565897D03*
X562196D03*
X571448Y957206D03*
X567748D03*
X564047D03*
X560346D03*
X573299Y960395D03*
X569598D03*
X565897D03*
X562196D03*
X571448Y963584D03*
X567748D03*
X564047D03*
X560346D03*
X573299Y966773D03*
X569598D03*
X565897D03*
X562196D03*
X571448Y969962D03*
X567748D03*
X564047D03*
X560346D03*
X573299Y973151D03*
X569598D03*
X565897D03*
X562196D03*
X571448Y976340D03*
X567748D03*
X564047D03*
X560346D03*
X573299Y979529D03*
X569598D03*
X565897D03*
X562196D03*
X571448Y982718D03*
X567748D03*
X564047D03*
X560346D03*
X573299Y985907D03*
X569598D03*
X565897D03*
X562196D03*
X571448Y989096D03*
X567748D03*
X564047D03*
X560346D03*
X573299Y992285D03*
X569598D03*
X565897D03*
X562196D03*
X571448Y995474D03*
X567748D03*
X564047D03*
X560346D03*
X573299Y998663D03*
X569598D03*
X565897D03*
X562196D03*
X571448Y1001852D03*
X567748D03*
X564047D03*
X560346D03*
X573299Y1005041D03*
X569598D03*
X565897D03*
X562196D03*
X571448Y1008230D03*
X567748D03*
X564047D03*
X560346D03*
X573299Y1011419D03*
X569598D03*
X565897D03*
X562196D03*
X570779Y1027009D03*
X567078D03*
X563378D03*
X559677D03*
X572629Y1030198D03*
X568929D03*
X565228D03*
X561527D03*
X570779Y1033387D03*
X567078D03*
X563378D03*
X559677D03*
X572629Y1036576D03*
X568929D03*
X565228D03*
X561527D03*
X570779Y1039765D03*
X567078D03*
X563378D03*
X559677D03*
X572629Y1042954D03*
X568929D03*
X565228D03*
X561527D03*
X570779Y1046143D03*
X567078D03*
X563378D03*
X559677D03*
X572629Y1049332D03*
X568929D03*
X565228D03*
X561527D03*
X570779Y1052521D03*
X567078D03*
X563378D03*
X559677D03*
X572629Y1055710D03*
X568929D03*
X565228D03*
X561527D03*
X570779Y1058899D03*
X567078D03*
X563378D03*
X559677D03*
X572629Y1062088D03*
X568929D03*
X565228D03*
X561527D03*
X570779Y1065277D03*
X567078D03*
X563378D03*
X559677D03*
X572629Y1068466D03*
X568929D03*
X565228D03*
X561527D03*
X570779Y1071655D03*
X567078D03*
X563378D03*
X559677D03*
X572629Y1074844D03*
X568929D03*
X565228D03*
X561527D03*
X570779Y1078033D03*
X567078D03*
X563378D03*
X559677D03*
X572629Y1081222D03*
X568929D03*
X565228D03*
X561527D03*
X570779Y1084411D03*
X567078D03*
X563378D03*
X559677D03*
X572629Y1087600D03*
X568929D03*
X565228D03*
X561527D03*
X570779Y1090789D03*
X567078D03*
X563378D03*
X559677D03*
X572629Y1093978D03*
X568929D03*
X565228D03*
X561527D03*
X570779Y1097167D03*
X567078D03*
X563378D03*
X559677D03*
X572629Y1100356D03*
X568929D03*
X565228D03*
X561527D03*
X570779Y1103545D03*
X567078D03*
X563378D03*
X559677D03*
X572629Y1106734D03*
X568929D03*
X565228D03*
X561527D03*
X570779Y1109923D03*
X567078D03*
X563378D03*
X559677D03*
X572629Y1113112D03*
X568929D03*
X565228D03*
X561527D03*
X570779Y1116301D03*
X567078D03*
X563378D03*
X559677D03*
X572629Y1119490D03*
X568929D03*
X565228D03*
X561527D03*
X570779Y1122679D03*
X567078D03*
X563378D03*
X559677D03*
X572629Y1125868D03*
X568929D03*
X565228D03*
X561527D03*
X570779Y1129057D03*
X567078D03*
X563378D03*
X559677D03*
X572629Y1132246D03*
X568929D03*
X565228D03*
X561527D03*
X570779Y1135434D03*
X567078D03*
X563378D03*
X559677D03*
X572629Y1138623D03*
X568929D03*
X565228D03*
X561527D03*
X570779Y1141812D03*
X567078D03*
X563378D03*
X559677D03*
X572629Y1145001D03*
X568929D03*
X565228D03*
X561527D03*
X570779Y1148190D03*
X567078D03*
X563378D03*
X559677D03*
X572629Y1151379D03*
X568929D03*
X565228D03*
X561527D03*
X570779Y1154568D03*
X567078D03*
X563378D03*
X559677D03*
X572629Y1157757D03*
X568929D03*
X565228D03*
X561527D03*
X570779Y1160946D03*
X567078D03*
X563378D03*
X559677D03*
X568929Y1164135D03*
X565228D03*
X561527D03*
X575149Y880671D03*
Y887049D03*
Y893427D03*
Y899805D03*
Y906182D03*
Y912560D03*
Y918938D03*
Y925316D03*
Y931694D03*
Y938072D03*
Y944450D03*
Y950828D03*
Y957206D03*
Y963584D03*
Y969962D03*
Y976340D03*
Y982718D03*
Y989096D03*
Y995474D03*
Y1001852D03*
Y1008230D03*
X574480Y1027009D03*
X576330Y1030198D03*
X574480Y1033387D03*
X576330Y1036576D03*
X574480Y1039765D03*
X576330Y1042954D03*
X574480Y1046143D03*
X576330Y1049332D03*
X574480Y1052521D03*
X576330Y1055710D03*
X574480Y1058899D03*
X576330Y1062088D03*
X574480Y1065277D03*
X576330Y1068466D03*
X574480Y1071655D03*
X576330Y1074844D03*
X574480Y1078033D03*
X576330Y1081222D03*
X574480Y1084411D03*
X576330Y1087600D03*
X574480Y1090789D03*
X576330Y1093978D03*
X574480Y1097167D03*
X576330Y1100356D03*
X574480Y1103545D03*
X576330Y1106734D03*
X574480Y1109923D03*
X576330Y1113112D03*
X574480Y1116301D03*
X576330Y1119490D03*
X574480Y1122679D03*
X576330Y1125868D03*
X574480Y1129057D03*
X576330Y1132246D03*
X574480Y1135434D03*
X576330Y1138623D03*
X574480Y1141812D03*
X576330Y1145001D03*
X574480Y1148190D03*
X576330Y1151379D03*
X574480Y1154568D03*
X576330Y1157757D03*
X1288535Y874292D03*
X1286685Y877481D03*
X1288535Y880670D03*
X1284835D03*
X1281134D03*
X1286685Y883859D03*
X1282984D03*
X1288535Y887048D03*
X1284835D03*
X1281134D03*
X1286685Y890237D03*
X1282984D03*
X1288535Y893426D03*
X1284835D03*
X1281134D03*
X1286685Y896615D03*
X1282984D03*
X1288535Y899804D03*
X1284835D03*
X1281134D03*
X1286685Y902993D03*
X1282984D03*
X1288535Y906181D03*
X1284835D03*
X1281134D03*
X1286685Y909370D03*
X1282984D03*
X1288535Y912559D03*
X1284835D03*
X1281134D03*
X1286685Y915748D03*
X1282984D03*
X1288535Y918937D03*
X1284835D03*
X1281134D03*
X1286685Y922126D03*
X1282984D03*
X1288535Y925315D03*
X1284835D03*
X1281134D03*
X1286685Y928504D03*
X1282984D03*
X1288535Y931693D03*
X1284835D03*
X1281134D03*
X1286685Y934882D03*
X1282984D03*
X1288535Y938071D03*
X1284835D03*
X1281134D03*
X1286685Y941260D03*
X1282984D03*
X1288535Y944449D03*
X1284835D03*
X1281134D03*
X1286685Y947638D03*
X1282984D03*
X1288535Y950827D03*
X1284835D03*
X1281134D03*
X1286685Y954016D03*
X1282984D03*
X1288535Y957205D03*
X1284835D03*
X1281134D03*
X1286685Y960394D03*
X1282984D03*
X1288535Y963583D03*
X1284835D03*
X1281134D03*
X1286685Y966772D03*
X1282984D03*
X1288535Y969961D03*
X1284835D03*
X1281134D03*
X1286685Y973150D03*
X1282984D03*
X1288535Y976339D03*
X1284835D03*
X1281134D03*
X1286685Y979528D03*
X1282984D03*
X1288535Y982717D03*
X1284835D03*
X1281134D03*
X1286685Y985906D03*
X1282984D03*
X1288535Y989095D03*
X1284835D03*
X1281134D03*
X1286685Y992284D03*
X1282984D03*
X1288535Y995473D03*
X1284835D03*
X1281134D03*
X1286685Y998662D03*
X1282984D03*
X1288535Y1001851D03*
X1284835D03*
X1281134D03*
X1286685Y1005040D03*
X1282984D03*
X1288535Y1008229D03*
X1284835D03*
X1281134D03*
X1286685Y1011418D03*
X1282984D03*
X1287866Y1027008D03*
X1284165D03*
X1289716Y1030197D03*
X1286016D03*
X1282315D03*
X1287866Y1033386D03*
X1284165D03*
X1289716Y1036575D03*
X1286016D03*
X1282315D03*
X1287866Y1039764D03*
X1284165D03*
X1289716Y1042953D03*
X1286016D03*
X1282315D03*
X1287866Y1046142D03*
X1284165D03*
X1289716Y1049331D03*
X1286016D03*
X1282315D03*
X1287866Y1052520D03*
X1284165D03*
X1289716Y1055709D03*
X1286016D03*
X1282315D03*
X1287866Y1058898D03*
X1284165D03*
X1289716Y1062087D03*
X1286016D03*
X1282315D03*
X1287866Y1065276D03*
X1284165D03*
X1289716Y1068465D03*
X1286016D03*
X1282315D03*
X1287866Y1071654D03*
X1284165D03*
X1289716Y1074843D03*
X1286016D03*
X1282315D03*
X1287866Y1078032D03*
X1284165D03*
X1289716Y1081221D03*
X1286016D03*
X1282315D03*
X1287866Y1084410D03*
X1284165D03*
X1289716Y1087599D03*
X1286016D03*
X1282315D03*
X1287866Y1090788D03*
X1284165D03*
X1289716Y1093977D03*
X1286016D03*
X1282315D03*
X1287866Y1097166D03*
X1284165D03*
X1289716Y1100355D03*
X1286016D03*
X1282315D03*
X1287866Y1103544D03*
X1284165D03*
X1289716Y1106733D03*
X1286016D03*
X1282315D03*
X1287866Y1109922D03*
X1284165D03*
X1289716Y1113111D03*
X1286016D03*
X1282315D03*
X1287866Y1116300D03*
X1284165D03*
X1289716Y1119489D03*
X1286016D03*
X1282315D03*
X1287866Y1122678D03*
X1284165D03*
X1289716Y1125867D03*
X1286016D03*
X1282315D03*
X1287866Y1129056D03*
X1284165D03*
X1289716Y1132245D03*
X1286016D03*
X1282315D03*
X1287866Y1135433D03*
X1284165D03*
X1289716Y1138622D03*
X1286016D03*
X1282315D03*
X1287866Y1141811D03*
X1284165D03*
X1289716Y1145000D03*
X1286016D03*
X1282315D03*
X1287866Y1148189D03*
X1284165D03*
X1289716Y1151378D03*
X1286016D03*
X1282315D03*
X1287866Y1154567D03*
X1284165D03*
X1289716Y1157756D03*
X1286016D03*
X1282315D03*
X1287866Y1160945D03*
X1289716Y1164134D03*
X1303338Y874292D03*
X1295937D03*
X1292236D03*
X1301488Y877481D03*
X1297787D03*
X1294086D03*
X1290386D03*
X1303338Y880670D03*
X1299638D03*
X1295937D03*
X1292236D03*
X1301488Y883859D03*
X1297787D03*
X1294086D03*
X1290386D03*
X1303338Y887048D03*
X1299638D03*
X1295937D03*
X1292236D03*
X1301488Y890237D03*
X1297787D03*
X1294086D03*
X1290386D03*
X1303338Y893426D03*
X1299638D03*
X1295937D03*
X1292236D03*
X1301488Y896615D03*
X1297787D03*
X1294086D03*
X1290386D03*
X1303338Y899804D03*
X1299638D03*
X1295937D03*
X1292236D03*
X1301488Y902993D03*
X1297787D03*
X1294086D03*
X1290386D03*
X1303338Y906181D03*
X1299638D03*
X1295937D03*
X1292236D03*
X1301488Y909370D03*
X1297787D03*
X1294086D03*
X1290386D03*
X1303338Y912559D03*
X1299638D03*
X1295937D03*
X1292236D03*
X1301488Y915748D03*
X1297787D03*
X1294086D03*
X1290386D03*
X1303338Y918937D03*
X1299638D03*
X1295937D03*
X1292236D03*
X1301488Y922126D03*
X1297787D03*
X1294086D03*
X1290386D03*
X1303338Y925315D03*
X1299638D03*
X1295937D03*
X1292236D03*
X1301488Y928504D03*
X1297787D03*
X1294086D03*
X1290386D03*
X1303338Y931693D03*
X1299638D03*
X1295937D03*
X1292236D03*
X1301488Y934882D03*
X1297787D03*
X1294086D03*
X1290386D03*
X1303338Y938071D03*
X1299638D03*
X1295937D03*
X1292236D03*
X1301488Y941260D03*
X1297787D03*
X1294086D03*
X1290386D03*
X1303338Y944449D03*
X1299638D03*
X1295937D03*
X1292236D03*
X1301488Y947638D03*
X1297787D03*
X1294086D03*
X1290386D03*
X1303338Y950827D03*
X1299638D03*
X1295937D03*
X1292236D03*
X1301488Y954016D03*
X1297787D03*
X1294086D03*
X1290386D03*
X1303338Y957205D03*
X1299638D03*
X1295937D03*
X1292236D03*
X1301488Y960394D03*
X1297787D03*
X1294086D03*
X1290386D03*
X1303338Y963583D03*
X1299638D03*
X1295937D03*
X1292236D03*
X1301488Y966772D03*
X1297787D03*
X1294086D03*
X1290386D03*
X1303338Y969961D03*
X1299638D03*
X1295937D03*
X1292236D03*
X1301488Y973150D03*
X1297787D03*
X1294086D03*
X1290386D03*
X1303338Y976339D03*
X1299638D03*
X1295937D03*
X1292236D03*
X1301488Y979528D03*
X1297787D03*
X1294086D03*
X1290386D03*
X1303338Y982717D03*
X1299638D03*
X1295937D03*
X1292236D03*
X1301488Y985906D03*
X1297787D03*
X1294086D03*
X1290386D03*
X1303338Y989095D03*
X1299638D03*
X1295937D03*
X1292236D03*
X1301488Y992284D03*
X1297787D03*
X1294086D03*
X1290386D03*
X1303338Y995473D03*
X1299638D03*
X1295937D03*
X1292236D03*
X1301488Y998662D03*
X1297787D03*
X1294086D03*
X1290386D03*
X1303338Y1001851D03*
X1299638D03*
X1295937D03*
X1292236D03*
X1301488Y1005040D03*
X1297787D03*
X1294086D03*
X1290386D03*
X1303338Y1008229D03*
X1299638D03*
X1295937D03*
X1292236D03*
X1301488Y1011418D03*
X1297787D03*
X1294086D03*
X1290386D03*
X1302669Y1027008D03*
X1298968D03*
X1295268D03*
X1291567D03*
X1304520Y1030197D03*
X1300819D03*
X1297118D03*
X1293417D03*
X1302669Y1033386D03*
X1298968D03*
X1295268D03*
X1291567D03*
X1304520Y1036575D03*
X1300819D03*
X1297118D03*
X1293417D03*
X1302669Y1039764D03*
X1298968D03*
X1295268D03*
X1291567D03*
X1304520Y1042953D03*
X1300819D03*
X1297118D03*
X1293417D03*
X1302669Y1046142D03*
X1298968D03*
X1295268D03*
X1291567D03*
X1304520Y1049331D03*
X1300819D03*
X1297118D03*
X1293417D03*
X1302669Y1052520D03*
X1298968D03*
X1295268D03*
X1291567D03*
X1304520Y1055709D03*
X1300819D03*
X1297118D03*
X1293417D03*
X1302669Y1058898D03*
X1298968D03*
X1295268D03*
X1291567D03*
X1304520Y1062087D03*
X1300819D03*
X1297118D03*
X1293417D03*
X1302669Y1065276D03*
X1298968D03*
X1295268D03*
X1291567D03*
X1304520Y1068465D03*
X1300819D03*
X1297118D03*
X1293417D03*
X1302669Y1071654D03*
X1298968D03*
X1295268D03*
X1291567D03*
X1304520Y1074843D03*
X1300819D03*
X1297118D03*
X1293417D03*
X1302669Y1078032D03*
X1298968D03*
X1295268D03*
X1291567D03*
X1304520Y1081221D03*
X1300819D03*
X1297118D03*
X1293417D03*
X1302669Y1084410D03*
X1298968D03*
X1295268D03*
X1291567D03*
X1304520Y1087599D03*
X1300819D03*
X1297118D03*
X1293417D03*
X1302669Y1090788D03*
X1298968D03*
X1295268D03*
X1291567D03*
X1304520Y1093977D03*
X1300819D03*
X1297118D03*
X1293417D03*
X1302669Y1097166D03*
X1298968D03*
X1295268D03*
X1291567D03*
X1304520Y1100355D03*
X1300819D03*
X1297118D03*
X1293417D03*
X1302669Y1103544D03*
X1298968D03*
X1295268D03*
X1291567D03*
X1304520Y1106733D03*
X1300819D03*
X1297118D03*
X1293417D03*
X1302669Y1109922D03*
X1298968D03*
X1295268D03*
X1291567D03*
X1304520Y1113111D03*
X1300819D03*
X1297118D03*
X1293417D03*
X1302669Y1116300D03*
X1298968D03*
X1295268D03*
X1291567D03*
X1304520Y1119489D03*
X1300819D03*
X1297118D03*
X1293417D03*
X1302669Y1122678D03*
X1298968D03*
X1295268D03*
X1291567D03*
X1304520Y1125867D03*
X1300819D03*
X1297118D03*
X1293417D03*
X1302669Y1129056D03*
X1298968D03*
X1295268D03*
X1291567D03*
X1304520Y1132245D03*
X1300819D03*
X1297118D03*
X1293417D03*
X1302669Y1135433D03*
X1298968D03*
X1295268D03*
X1291567D03*
X1304520Y1138622D03*
X1300819D03*
X1297118D03*
X1293417D03*
X1302669Y1141811D03*
X1298968D03*
X1295268D03*
X1291567D03*
X1304520Y1145000D03*
X1300819D03*
X1297118D03*
X1293417D03*
X1302669Y1148189D03*
X1298968D03*
X1295268D03*
X1291567D03*
X1304520Y1151378D03*
X1300819D03*
X1297118D03*
X1293417D03*
X1302669Y1154567D03*
X1298968D03*
X1295268D03*
X1291567D03*
X1304520Y1157756D03*
X1300819D03*
X1297118D03*
X1293417D03*
X1302669Y1160945D03*
X1298968D03*
X1295268D03*
X1291567D03*
X1304520Y1164134D03*
X1297118D03*
X1293417D03*
X1318142Y874292D03*
X1314441D03*
X1310740D03*
X1307039D03*
X1316291Y877481D03*
X1312590D03*
X1308890D03*
X1305189D03*
X1318142Y880670D03*
X1314441D03*
X1310740D03*
X1307039D03*
X1316291Y883859D03*
X1312590D03*
X1308890D03*
X1305189D03*
X1318142Y887048D03*
X1314441D03*
X1310740D03*
X1307039D03*
X1316291Y890237D03*
X1312590D03*
X1308890D03*
X1305189D03*
X1318142Y893426D03*
X1314441D03*
X1310740D03*
X1307039D03*
X1316291Y896615D03*
X1312590D03*
X1308890D03*
X1305189D03*
X1318142Y899804D03*
X1314441D03*
X1310740D03*
X1307039D03*
X1316291Y902993D03*
X1312590D03*
X1308890D03*
X1305189D03*
X1318142Y906181D03*
X1314441D03*
X1310740D03*
X1307039D03*
X1316291Y909370D03*
X1312590D03*
X1308890D03*
X1305189D03*
X1318142Y912559D03*
X1314441D03*
X1310740D03*
X1307039D03*
X1316291Y915748D03*
X1312590D03*
X1308890D03*
X1305189D03*
X1318142Y918937D03*
X1314441D03*
X1310740D03*
X1307039D03*
X1316291Y922126D03*
X1312590D03*
X1308890D03*
X1305189D03*
X1318142Y925315D03*
X1314441D03*
X1310740D03*
X1307039D03*
X1316291Y928504D03*
X1312590D03*
X1308890D03*
X1305189D03*
X1318142Y931693D03*
X1314441D03*
X1310740D03*
X1307039D03*
X1316291Y934882D03*
X1312590D03*
X1308890D03*
X1305189D03*
X1318142Y938071D03*
X1314441D03*
X1310740D03*
X1307039D03*
X1316291Y941260D03*
X1312590D03*
X1308890D03*
X1305189D03*
X1318142Y944449D03*
X1314441D03*
X1310740D03*
X1307039D03*
X1316291Y947638D03*
X1312590D03*
X1308890D03*
X1305189D03*
X1318142Y950827D03*
X1314441D03*
X1310740D03*
X1307039D03*
X1316291Y954016D03*
X1312590D03*
X1308890D03*
X1305189D03*
X1318142Y957205D03*
X1314441D03*
X1310740D03*
X1307039D03*
X1316291Y960394D03*
X1312590D03*
X1308890D03*
X1305189D03*
X1318142Y963583D03*
X1314441D03*
X1310740D03*
X1307039D03*
X1316291Y966772D03*
X1312590D03*
X1308890D03*
X1305189D03*
X1318142Y969961D03*
X1314441D03*
X1310740D03*
X1307039D03*
X1316291Y973150D03*
X1312590D03*
X1308890D03*
X1305189D03*
X1318142Y976339D03*
X1314441D03*
X1310740D03*
X1307039D03*
X1316291Y979528D03*
X1312590D03*
X1308890D03*
X1305189D03*
X1318142Y982717D03*
X1314441D03*
X1310740D03*
X1307039D03*
X1316291Y985906D03*
X1312590D03*
X1308890D03*
X1305189D03*
X1318142Y989095D03*
X1314441D03*
X1310740D03*
X1307039D03*
X1316291Y992284D03*
X1312590D03*
X1308890D03*
X1305189D03*
X1318142Y995473D03*
X1314441D03*
X1310740D03*
X1307039D03*
X1316291Y998662D03*
X1312590D03*
X1308890D03*
X1305189D03*
X1318142Y1001851D03*
X1314441D03*
X1310740D03*
X1307039D03*
X1316291Y1005040D03*
X1312590D03*
X1308890D03*
X1305189D03*
X1318142Y1008229D03*
X1314441D03*
X1310740D03*
X1307039D03*
X1316291Y1011418D03*
X1312590D03*
X1308890D03*
X1305189D03*
X1317472Y1027008D03*
X1313771D03*
X1310071D03*
X1306370D03*
X1319323Y1030197D03*
X1315622D03*
X1311921D03*
X1308220D03*
X1317472Y1033386D03*
X1313771D03*
X1310071D03*
X1306370D03*
X1319323Y1036575D03*
X1315622D03*
X1311921D03*
X1308220D03*
X1317472Y1039764D03*
X1313771D03*
X1310071D03*
X1306370D03*
X1319323Y1042953D03*
X1315622D03*
X1311921D03*
X1308220D03*
X1317472Y1046142D03*
X1313771D03*
X1310071D03*
X1306370D03*
X1319323Y1049331D03*
X1315622D03*
X1311921D03*
X1308220D03*
X1317472Y1052520D03*
X1313771D03*
X1310071D03*
X1306370D03*
X1319323Y1055709D03*
X1315622D03*
X1311921D03*
X1308220D03*
X1317472Y1058898D03*
X1313771D03*
X1310071D03*
X1306370D03*
X1319323Y1062087D03*
X1315622D03*
X1311921D03*
X1308220D03*
X1317472Y1065276D03*
X1313771D03*
X1310071D03*
X1306370D03*
X1319323Y1068465D03*
X1315622D03*
X1311921D03*
X1308220D03*
X1317472Y1071654D03*
X1313771D03*
X1310071D03*
X1306370D03*
X1319323Y1074843D03*
X1315622D03*
X1311921D03*
X1308220D03*
X1317472Y1078032D03*
X1313771D03*
X1310071D03*
X1306370D03*
X1319323Y1081221D03*
X1315622D03*
X1311921D03*
X1308220D03*
X1317472Y1084410D03*
X1313771D03*
X1310071D03*
X1306370D03*
X1319323Y1087599D03*
X1315622D03*
X1311921D03*
X1308220D03*
X1317472Y1090788D03*
X1313771D03*
X1310071D03*
X1306370D03*
X1319323Y1093977D03*
X1315622D03*
X1311921D03*
X1308220D03*
X1317472Y1097166D03*
X1313771D03*
X1310071D03*
X1306370D03*
X1319323Y1100355D03*
X1315622D03*
X1311921D03*
X1308220D03*
X1317472Y1103544D03*
X1313771D03*
X1310071D03*
X1306370D03*
X1319323Y1106733D03*
X1315622D03*
X1311921D03*
X1308220D03*
X1317472Y1109922D03*
X1313771D03*
X1310071D03*
X1306370D03*
X1319323Y1113111D03*
X1315622D03*
X1311921D03*
X1308220D03*
X1317472Y1116300D03*
X1313771D03*
X1310071D03*
X1306370D03*
X1319323Y1119489D03*
X1315622D03*
X1311921D03*
X1308220D03*
X1317472Y1122678D03*
X1313771D03*
X1310071D03*
X1306370D03*
X1319323Y1125867D03*
X1315622D03*
X1311921D03*
X1308220D03*
X1317472Y1129056D03*
X1313771D03*
X1310071D03*
X1306370D03*
X1319323Y1132245D03*
X1315622D03*
X1311921D03*
X1308220D03*
X1317472Y1135433D03*
X1313771D03*
X1310071D03*
X1306370D03*
X1319323Y1138622D03*
X1315622D03*
X1311921D03*
X1308220D03*
X1317472Y1141811D03*
X1313771D03*
X1310071D03*
X1306370D03*
X1319323Y1145000D03*
X1315622D03*
X1311921D03*
X1308220D03*
X1317472Y1148189D03*
X1313771D03*
X1310071D03*
X1306370D03*
X1319323Y1151378D03*
X1315622D03*
X1311921D03*
X1308220D03*
X1317472Y1154567D03*
X1313771D03*
X1310071D03*
X1306370D03*
X1319323Y1157756D03*
X1315622D03*
X1311921D03*
X1308220D03*
X1317472Y1160945D03*
X1313771D03*
X1310071D03*
X1306370D03*
X1319323Y1164134D03*
X1315622D03*
X1311921D03*
X1308220D03*
X1332945Y874292D03*
X1329244D03*
X1325543D03*
X1331094Y877481D03*
X1327394D03*
X1323693D03*
X1319992D03*
X1332945Y880670D03*
X1329244D03*
X1325543D03*
X1321842D03*
X1331094Y883859D03*
X1327394D03*
X1323693D03*
X1319992D03*
X1332945Y887048D03*
X1329244D03*
X1325543D03*
X1321842D03*
X1331094Y890237D03*
X1327394D03*
X1323693D03*
X1319992D03*
X1332945Y893426D03*
X1329244D03*
X1325543D03*
X1321842D03*
X1331094Y896615D03*
X1327394D03*
X1323693D03*
X1319992D03*
X1332945Y899804D03*
X1329244D03*
X1325543D03*
X1321842D03*
X1331094Y902993D03*
X1327394D03*
X1323693D03*
X1319992D03*
X1332945Y906181D03*
X1329244D03*
X1325543D03*
X1321842D03*
X1331094Y909370D03*
X1327394D03*
X1323693D03*
X1319992D03*
X1332945Y912559D03*
X1329244D03*
X1325543D03*
X1321842D03*
X1331094Y915748D03*
X1327394D03*
X1323693D03*
X1319992D03*
X1332945Y918937D03*
X1329244D03*
X1325543D03*
X1321842D03*
X1331094Y922126D03*
X1327394D03*
X1323693D03*
X1319992D03*
X1332945Y925315D03*
X1329244D03*
X1325543D03*
X1321842D03*
X1331094Y928504D03*
X1327394D03*
X1323693D03*
X1319992D03*
X1332945Y931693D03*
X1329244D03*
X1325543D03*
X1321842D03*
X1331094Y934882D03*
X1327394D03*
X1323693D03*
X1319992D03*
X1332945Y938071D03*
X1329244D03*
X1325543D03*
X1321842D03*
X1331094Y941260D03*
X1327394D03*
X1323693D03*
X1319992D03*
X1332945Y944449D03*
X1329244D03*
X1325543D03*
X1321842D03*
X1331094Y947638D03*
X1327394D03*
X1323693D03*
X1319992D03*
X1332945Y950827D03*
X1329244D03*
X1325543D03*
X1321842D03*
X1331094Y954016D03*
X1327394D03*
X1323693D03*
X1319992D03*
X1332945Y957205D03*
X1329244D03*
X1325543D03*
X1321842D03*
X1331094Y960394D03*
X1327394D03*
X1323693D03*
X1319992D03*
X1332945Y963583D03*
X1329244D03*
X1325543D03*
X1321842D03*
X1331094Y966772D03*
X1327394D03*
X1323693D03*
X1319992D03*
X1332945Y969961D03*
X1329244D03*
X1325543D03*
X1321842D03*
X1331094Y973150D03*
X1327394D03*
X1323693D03*
X1319992D03*
X1332945Y976339D03*
X1329244D03*
X1325543D03*
X1321842D03*
X1331094Y979528D03*
X1327394D03*
X1323693D03*
X1319992D03*
X1332945Y982717D03*
X1329244D03*
X1325543D03*
X1321842D03*
X1331094Y985906D03*
X1327394D03*
X1323693D03*
X1319992D03*
X1332945Y989095D03*
X1329244D03*
X1325543D03*
X1321842D03*
X1331094Y992284D03*
X1327394D03*
X1323693D03*
X1319992D03*
X1332945Y995473D03*
X1329244D03*
X1325543D03*
X1321842D03*
X1331094Y998662D03*
X1327394D03*
X1323693D03*
X1319992D03*
X1332945Y1001851D03*
X1329244D03*
X1325543D03*
X1321842D03*
X1331094Y1005040D03*
X1327394D03*
X1323693D03*
X1319992D03*
X1332945Y1008229D03*
X1329244D03*
X1325543D03*
X1321842D03*
X1331094Y1011418D03*
X1327394D03*
X1323693D03*
X1319992D03*
X1332275Y1027008D03*
X1328575D03*
X1324874D03*
X1321173D03*
X1334126Y1030197D03*
X1330425D03*
X1326724D03*
X1323023D03*
X1332275Y1033386D03*
X1328575D03*
X1324874D03*
X1321173D03*
X1334126Y1036575D03*
X1330425D03*
X1326724D03*
X1323023D03*
X1332275Y1039764D03*
X1328575D03*
X1324874D03*
X1321173D03*
X1334126Y1042953D03*
X1330425D03*
X1326724D03*
X1323023D03*
X1332275Y1046142D03*
X1328575D03*
X1324874D03*
X1321173D03*
X1334126Y1049331D03*
X1330425D03*
X1326724D03*
X1323023D03*
X1332275Y1052520D03*
X1328575D03*
X1324874D03*
X1321173D03*
X1334126Y1055709D03*
X1330425D03*
X1326724D03*
X1323023D03*
X1332275Y1058898D03*
X1328575D03*
X1324874D03*
X1321173D03*
X1334126Y1062087D03*
X1330425D03*
X1326724D03*
X1323023D03*
X1332275Y1065276D03*
X1328575D03*
X1324874D03*
X1321173D03*
X1334126Y1068465D03*
X1330425D03*
X1326724D03*
X1323023D03*
X1332275Y1071654D03*
X1328575D03*
X1324874D03*
X1321173D03*
X1334126Y1074843D03*
X1330425D03*
X1326724D03*
X1323023D03*
X1332275Y1078032D03*
X1328575D03*
X1324874D03*
X1321173D03*
X1334126Y1081221D03*
X1330425D03*
X1326724D03*
X1323023D03*
X1332275Y1084410D03*
X1328575D03*
X1324874D03*
X1321173D03*
X1334126Y1087599D03*
X1330425D03*
X1326724D03*
X1323023D03*
X1332275Y1090788D03*
X1328575D03*
X1324874D03*
X1321173D03*
X1334126Y1093977D03*
X1330425D03*
X1326724D03*
X1323023D03*
X1332275Y1097166D03*
X1328575D03*
X1324874D03*
X1321173D03*
X1334126Y1100355D03*
X1330425D03*
X1326724D03*
X1323023D03*
X1332275Y1103544D03*
X1328575D03*
X1324874D03*
X1321173D03*
X1334126Y1106733D03*
X1330425D03*
X1326724D03*
X1323023D03*
X1332275Y1109922D03*
X1328575D03*
X1324874D03*
X1321173D03*
X1334126Y1113111D03*
X1330425D03*
X1326724D03*
X1323023D03*
X1332275Y1116300D03*
X1328575D03*
X1324874D03*
X1321173D03*
X1334126Y1119489D03*
X1330425D03*
X1326724D03*
X1323023D03*
X1332275Y1122678D03*
X1328575D03*
X1324874D03*
X1321173D03*
X1334126Y1125867D03*
X1330425D03*
X1326724D03*
X1323023D03*
X1332275Y1129056D03*
X1328575D03*
X1324874D03*
X1321173D03*
X1334126Y1132245D03*
X1330425D03*
X1326724D03*
X1323023D03*
X1332275Y1135433D03*
X1328575D03*
X1324874D03*
X1321173D03*
X1334126Y1138622D03*
X1330425D03*
X1326724D03*
X1323023D03*
X1332275Y1141811D03*
X1328575D03*
X1324874D03*
X1321173D03*
X1334126Y1145000D03*
X1330425D03*
X1326724D03*
X1323023D03*
X1332275Y1148189D03*
X1328575D03*
X1324874D03*
X1321173D03*
X1334126Y1151378D03*
X1330425D03*
X1326724D03*
X1323023D03*
X1332275Y1154567D03*
X1328575D03*
X1324874D03*
X1321173D03*
X1334126Y1157756D03*
X1330425D03*
X1326724D03*
X1323023D03*
X1332275Y1160945D03*
X1328575D03*
X1324874D03*
X1321173D03*
X1334126Y1164134D03*
X1330425D03*
X1326724D03*
X1347748Y874292D03*
X1340346D03*
X1336646D03*
X1349598Y877481D03*
X1345897D03*
X1342197D03*
X1338496D03*
X1334795D03*
X1347748Y880670D03*
X1344047D03*
X1340346D03*
X1336646D03*
X1349598Y883859D03*
X1345897D03*
X1342197D03*
X1338496D03*
X1334795D03*
X1347748Y887048D03*
X1344047D03*
X1340346D03*
X1336646D03*
X1349598Y890237D03*
X1345897D03*
X1342197D03*
X1338496D03*
X1334795D03*
X1347748Y893426D03*
X1344047D03*
X1340346D03*
X1336646D03*
X1349598Y896615D03*
X1345897D03*
X1342197D03*
X1338496D03*
X1334795D03*
X1347748Y899804D03*
X1344047D03*
X1340346D03*
X1336646D03*
X1349598Y902993D03*
X1345897D03*
X1342197D03*
X1338496D03*
X1334795D03*
X1347748Y906181D03*
X1344047D03*
X1340346D03*
X1336646D03*
X1349598Y909370D03*
X1345897D03*
X1342197D03*
X1338496D03*
X1334795D03*
X1347748Y912559D03*
X1344047D03*
X1340346D03*
X1336646D03*
X1349598Y915748D03*
X1345897D03*
X1342197D03*
X1338496D03*
X1334795D03*
X1347748Y918937D03*
X1344047D03*
X1340346D03*
X1336646D03*
X1349598Y922126D03*
X1345897D03*
X1342197D03*
X1338496D03*
X1334795D03*
X1347748Y925315D03*
X1344047D03*
X1340346D03*
X1336646D03*
X1349598Y928504D03*
X1345897D03*
X1342197D03*
X1338496D03*
X1334795D03*
X1347748Y931693D03*
X1344047D03*
X1340346D03*
X1336646D03*
X1349598Y934882D03*
X1345897D03*
X1342197D03*
X1338496D03*
X1334795D03*
X1347748Y938071D03*
X1344047D03*
X1340346D03*
X1336646D03*
X1349598Y941260D03*
X1345897D03*
X1342197D03*
X1338496D03*
X1334795D03*
X1347748Y944449D03*
X1344047D03*
X1340346D03*
X1336646D03*
X1349598Y947638D03*
X1345897D03*
X1342197D03*
X1338496D03*
X1334795D03*
X1347748Y950827D03*
X1344047D03*
X1340346D03*
X1336646D03*
X1349598Y954016D03*
X1345897D03*
X1342197D03*
X1338496D03*
X1334795D03*
X1347748Y957205D03*
X1344047D03*
X1340346D03*
X1336646D03*
X1349598Y960394D03*
X1345897D03*
X1342197D03*
X1338496D03*
X1334795D03*
X1347748Y963583D03*
X1344047D03*
X1340346D03*
X1336646D03*
X1349598Y966772D03*
X1345897D03*
X1342197D03*
X1338496D03*
X1334795D03*
X1347748Y969961D03*
X1344047D03*
X1340346D03*
X1336646D03*
X1349598Y973150D03*
X1345897D03*
X1342197D03*
X1338496D03*
X1334795D03*
X1347748Y976339D03*
X1344047D03*
X1340346D03*
X1336646D03*
X1349598Y979528D03*
X1345897D03*
X1342197D03*
X1338496D03*
X1334795D03*
X1347748Y982717D03*
X1344047D03*
X1340346D03*
X1336646D03*
X1349598Y985906D03*
X1345897D03*
X1342197D03*
X1338496D03*
X1334795D03*
X1347748Y989095D03*
X1344047D03*
X1340346D03*
X1336646D03*
X1349598Y992284D03*
X1345897D03*
X1342197D03*
X1338496D03*
X1334795D03*
X1347748Y995473D03*
X1344047D03*
X1340346D03*
X1336646D03*
X1349598Y998662D03*
X1345897D03*
X1342197D03*
X1338496D03*
X1334795D03*
X1347748Y1001851D03*
X1344047D03*
X1340346D03*
X1336646D03*
X1349598Y1005040D03*
X1345897D03*
X1342197D03*
X1338496D03*
X1334795D03*
X1347748Y1008229D03*
X1344047D03*
X1340346D03*
X1336646D03*
X1349598Y1011418D03*
X1345897D03*
X1342197D03*
X1338496D03*
X1334795D03*
X1347079Y1027008D03*
X1343378D03*
X1339677D03*
X1335976D03*
X1348929Y1030197D03*
X1345228D03*
X1341527D03*
X1337827D03*
X1347079Y1033386D03*
X1343378D03*
X1339677D03*
X1335976D03*
X1348929Y1036575D03*
X1345228D03*
X1341527D03*
X1337827D03*
X1347079Y1039764D03*
X1343378D03*
X1339677D03*
X1335976D03*
X1348929Y1042953D03*
X1345228D03*
X1341527D03*
X1337827D03*
X1347079Y1046142D03*
X1343378D03*
X1339677D03*
X1335976D03*
X1348929Y1049331D03*
X1345228D03*
X1341527D03*
X1337827D03*
X1347079Y1052520D03*
X1343378D03*
X1339677D03*
X1335976D03*
X1348929Y1055709D03*
X1345228D03*
X1341527D03*
X1337827D03*
X1347079Y1058898D03*
X1343378D03*
X1339677D03*
X1335976D03*
X1348929Y1062087D03*
X1345228D03*
X1341527D03*
X1337827D03*
X1347079Y1065276D03*
X1343378D03*
X1339677D03*
X1335976D03*
X1348929Y1068465D03*
X1345228D03*
X1341527D03*
X1337827D03*
X1347079Y1071654D03*
X1343378D03*
X1339677D03*
X1335976D03*
X1348929Y1074843D03*
X1345228D03*
X1341527D03*
X1337827D03*
X1347079Y1078032D03*
X1343378D03*
X1339677D03*
X1335976D03*
X1348929Y1081221D03*
X1345228D03*
X1341527D03*
X1337827D03*
X1347079Y1084410D03*
X1343378D03*
X1339677D03*
X1335976D03*
X1348929Y1087599D03*
X1345228D03*
X1341527D03*
X1337827D03*
X1347079Y1090788D03*
X1343378D03*
X1339677D03*
X1335976D03*
X1348929Y1093977D03*
X1345228D03*
X1341527D03*
X1337827D03*
X1347079Y1097166D03*
X1343378D03*
X1339677D03*
X1335976D03*
X1348929Y1100355D03*
X1345228D03*
X1341527D03*
X1337827D03*
X1347079Y1103544D03*
X1343378D03*
X1339677D03*
X1335976D03*
X1348929Y1106733D03*
X1345228D03*
X1341527D03*
X1337827D03*
X1347079Y1109922D03*
X1343378D03*
X1339677D03*
X1335976D03*
X1348929Y1113111D03*
X1345228D03*
X1341527D03*
X1337827D03*
X1347079Y1116300D03*
X1343378D03*
X1339677D03*
X1335976D03*
X1348929Y1119489D03*
X1345228D03*
X1341527D03*
X1337827D03*
X1347079Y1122678D03*
X1343378D03*
X1339677D03*
X1335976D03*
X1348929Y1125867D03*
X1345228D03*
X1341527D03*
X1337827D03*
X1347079Y1129056D03*
X1343378D03*
X1339677D03*
X1335976D03*
X1348929Y1132245D03*
X1345228D03*
X1341527D03*
X1337827D03*
X1347079Y1135433D03*
X1343378D03*
X1339677D03*
X1335976D03*
X1348929Y1138622D03*
X1345228D03*
X1341527D03*
X1337827D03*
X1347079Y1141811D03*
X1343378D03*
X1339677D03*
X1335976D03*
X1348929Y1145000D03*
X1345228D03*
X1341527D03*
X1337827D03*
X1347079Y1148189D03*
X1343378D03*
X1339677D03*
X1335976D03*
X1348929Y1151378D03*
X1345228D03*
X1341527D03*
X1337827D03*
X1347079Y1154567D03*
X1343378D03*
X1339677D03*
X1335976D03*
X1348929Y1157756D03*
X1345228D03*
X1341527D03*
X1337827D03*
X1347079Y1160945D03*
X1343378D03*
X1339677D03*
X1335976D03*
X1348929Y1164134D03*
X1341527D03*
X1337827D03*
X1362551Y874292D03*
X1358850D03*
X1355149D03*
X1351449D03*
X1364401Y877481D03*
X1360701D03*
X1357000D03*
X1353299D03*
X1362551Y880670D03*
X1358850D03*
X1355149D03*
X1351449D03*
X1364401Y883859D03*
X1360701D03*
X1357000D03*
X1353299D03*
X1362551Y887048D03*
X1358850D03*
X1355149D03*
X1351449D03*
X1364401Y890237D03*
X1360701D03*
X1357000D03*
X1353299D03*
X1362551Y893426D03*
X1358850D03*
X1355149D03*
X1351449D03*
X1364401Y896615D03*
X1360701D03*
X1357000D03*
X1353299D03*
X1362551Y899804D03*
X1358850D03*
X1355149D03*
X1351449D03*
X1364401Y902993D03*
X1360701D03*
X1357000D03*
X1353299D03*
X1362551Y906181D03*
X1358850D03*
X1355149D03*
X1351449D03*
X1364401Y909370D03*
X1360701D03*
X1357000D03*
X1353299D03*
X1362551Y912559D03*
X1358850D03*
X1355149D03*
X1351449D03*
X1364401Y915748D03*
X1360701D03*
X1357000D03*
X1353299D03*
X1362551Y918937D03*
X1358850D03*
X1355149D03*
X1351449D03*
X1364401Y922126D03*
X1360701D03*
X1357000D03*
X1353299D03*
X1362551Y925315D03*
X1358850D03*
X1355149D03*
X1351449D03*
X1364401Y928504D03*
X1360701D03*
X1357000D03*
X1353299D03*
X1362551Y931693D03*
X1358850D03*
X1355149D03*
X1351449D03*
X1364401Y934882D03*
X1360701D03*
X1357000D03*
X1353299D03*
X1362551Y938071D03*
X1358850D03*
X1355149D03*
X1351449D03*
X1364401Y941260D03*
X1360701D03*
X1357000D03*
X1353299D03*
X1362551Y944449D03*
X1358850D03*
X1355149D03*
X1351449D03*
X1364401Y947638D03*
X1360701D03*
X1357000D03*
X1353299D03*
X1362551Y950827D03*
X1358850D03*
X1355149D03*
X1351449D03*
X1364401Y954016D03*
X1360701D03*
X1357000D03*
X1353299D03*
X1362551Y957205D03*
X1358850D03*
X1355149D03*
X1351449D03*
X1364401Y960394D03*
X1360701D03*
X1357000D03*
X1353299D03*
X1362551Y963583D03*
X1358850D03*
X1355149D03*
X1351449D03*
X1364401Y966772D03*
X1360701D03*
X1357000D03*
X1353299D03*
X1362551Y969961D03*
X1358850D03*
X1355149D03*
X1351449D03*
X1364401Y973150D03*
X1360701D03*
X1357000D03*
X1353299D03*
X1362551Y976339D03*
X1358850D03*
X1355149D03*
X1351449D03*
X1364401Y979528D03*
X1360701D03*
X1357000D03*
X1353299D03*
X1362551Y982717D03*
X1358850D03*
X1355149D03*
X1351449D03*
X1364401Y985906D03*
X1360701D03*
X1357000D03*
X1353299D03*
X1362551Y989095D03*
X1358850D03*
X1355149D03*
X1351449D03*
X1364401Y992284D03*
X1360701D03*
X1357000D03*
X1353299D03*
X1362551Y995473D03*
X1358850D03*
X1355149D03*
X1351449D03*
X1364401Y998662D03*
X1360701D03*
X1357000D03*
X1353299D03*
X1362551Y1001851D03*
X1358850D03*
X1355149D03*
X1351449D03*
X1364401Y1005040D03*
X1360701D03*
X1357000D03*
X1353299D03*
X1362551Y1008229D03*
X1358850D03*
X1355149D03*
X1351449D03*
X1364401Y1011418D03*
X1360701D03*
X1357000D03*
X1353299D03*
X1361882Y1027008D03*
X1358181D03*
X1354480D03*
X1350779D03*
X1363732Y1030197D03*
X1360031D03*
X1356331D03*
X1352630D03*
X1361882Y1033386D03*
X1358181D03*
X1354480D03*
X1350779D03*
X1363732Y1036575D03*
X1360031D03*
X1356331D03*
X1352630D03*
X1361882Y1039764D03*
X1358181D03*
X1354480D03*
X1350779D03*
X1363732Y1042953D03*
X1360031D03*
X1356331D03*
X1352630D03*
X1361882Y1046142D03*
X1358181D03*
X1354480D03*
X1350779D03*
X1363732Y1049331D03*
X1360031D03*
X1356331D03*
X1352630D03*
X1361882Y1052520D03*
X1358181D03*
X1354480D03*
X1350779D03*
X1363732Y1055709D03*
X1360031D03*
X1356331D03*
X1352630D03*
X1361882Y1058898D03*
X1358181D03*
X1354480D03*
X1350779D03*
X1363732Y1062087D03*
X1360031D03*
X1356331D03*
X1352630D03*
X1361882Y1065276D03*
X1358181D03*
X1354480D03*
X1350779D03*
X1363732Y1068465D03*
X1360031D03*
X1356331D03*
X1352630D03*
X1361882Y1071654D03*
X1358181D03*
X1354480D03*
X1350779D03*
X1363732Y1074843D03*
X1360031D03*
X1356331D03*
X1352630D03*
X1361882Y1078032D03*
X1358181D03*
X1354480D03*
X1350779D03*
X1363732Y1081221D03*
X1360031D03*
X1356331D03*
X1352630D03*
X1361882Y1084410D03*
X1358181D03*
X1354480D03*
X1350779D03*
X1363732Y1087599D03*
X1360031D03*
X1356331D03*
X1352630D03*
X1361882Y1090788D03*
X1358181D03*
X1354480D03*
X1350779D03*
X1363732Y1093977D03*
X1360031D03*
X1356331D03*
X1352630D03*
X1361882Y1097166D03*
X1358181D03*
X1354480D03*
X1350779D03*
X1363732Y1100355D03*
X1360031D03*
X1356331D03*
X1352630D03*
X1361882Y1103544D03*
X1358181D03*
X1354480D03*
X1350779D03*
X1363732Y1106733D03*
X1360031D03*
X1356331D03*
X1352630D03*
X1361882Y1109922D03*
X1358181D03*
X1354480D03*
X1350779D03*
X1363732Y1113111D03*
X1360031D03*
X1356331D03*
X1352630D03*
X1361882Y1116300D03*
X1358181D03*
X1354480D03*
X1350779D03*
X1363732Y1119489D03*
X1360031D03*
X1356331D03*
X1352630D03*
X1361882Y1122678D03*
X1358181D03*
X1354480D03*
X1350779D03*
X1363732Y1125867D03*
X1360031D03*
X1356331D03*
X1352630D03*
X1361882Y1129056D03*
X1358181D03*
X1354480D03*
X1350779D03*
X1363732Y1132245D03*
X1360031D03*
X1356331D03*
X1352630D03*
X1361882Y1135433D03*
X1358181D03*
X1354480D03*
X1350779D03*
X1363732Y1138622D03*
X1360031D03*
X1356331D03*
X1352630D03*
X1361882Y1141811D03*
X1358181D03*
X1354480D03*
X1350779D03*
X1363732Y1145000D03*
X1360031D03*
X1356331D03*
X1352630D03*
X1361882Y1148189D03*
X1358181D03*
X1354480D03*
X1350779D03*
X1363732Y1151378D03*
X1360031D03*
X1356331D03*
X1352630D03*
X1361882Y1154567D03*
X1358181D03*
X1354480D03*
X1350779D03*
X1363732Y1157756D03*
X1360031D03*
X1356331D03*
X1352630D03*
X1361882Y1160945D03*
X1358181D03*
X1354480D03*
X1350779D03*
X1363732Y1164134D03*
X1360031D03*
X1356331D03*
X1352630D03*
X1377354Y874292D03*
X1373653D03*
X1369953D03*
X1379205Y877481D03*
X1375504D03*
X1371803D03*
X1368102D03*
X1377354Y880670D03*
X1373653D03*
X1369953D03*
X1366252D03*
X1379205Y883859D03*
X1375504D03*
X1371803D03*
X1368102D03*
X1377354Y887048D03*
X1373653D03*
X1369953D03*
X1366252D03*
X1379205Y890237D03*
X1375504D03*
X1371803D03*
X1368102D03*
X1377354Y893426D03*
X1373653D03*
X1369953D03*
X1366252D03*
X1379205Y896615D03*
X1375504D03*
X1371803D03*
X1368102D03*
X1377354Y899804D03*
X1373653D03*
X1369953D03*
X1366252D03*
X1379205Y902993D03*
X1375504D03*
X1371803D03*
X1368102D03*
X1377354Y906181D03*
X1373653D03*
X1369953D03*
X1366252D03*
X1379205Y909370D03*
X1375504D03*
X1371803D03*
X1368102D03*
X1377354Y912559D03*
X1373653D03*
X1369953D03*
X1366252D03*
X1379205Y915748D03*
X1375504D03*
X1371803D03*
X1368102D03*
X1377354Y918937D03*
X1373653D03*
X1369953D03*
X1366252D03*
X1379205Y922126D03*
X1375504D03*
X1371803D03*
X1368102D03*
X1377354Y925315D03*
X1373653D03*
X1369953D03*
X1366252D03*
X1379205Y928504D03*
X1375504D03*
X1371803D03*
X1368102D03*
X1377354Y931693D03*
X1373653D03*
X1369953D03*
X1366252D03*
X1379205Y934882D03*
X1375504D03*
X1371803D03*
X1368102D03*
X1377354Y938071D03*
X1373653D03*
X1369953D03*
X1366252D03*
X1379205Y941260D03*
X1375504D03*
X1371803D03*
X1368102D03*
X1377354Y944449D03*
X1373653D03*
X1369953D03*
X1366252D03*
X1379205Y947638D03*
X1375504D03*
X1371803D03*
X1368102D03*
X1377354Y950827D03*
X1373653D03*
X1369953D03*
X1366252D03*
X1379205Y954016D03*
X1375504D03*
X1371803D03*
X1368102D03*
X1377354Y957205D03*
X1373653D03*
X1369953D03*
X1366252D03*
X1379205Y960394D03*
X1375504D03*
X1371803D03*
X1368102D03*
X1377354Y963583D03*
X1373653D03*
X1369953D03*
X1366252D03*
X1379205Y966772D03*
X1375504D03*
X1371803D03*
X1368102D03*
X1377354Y969961D03*
X1373653D03*
X1369953D03*
X1366252D03*
X1379205Y973150D03*
X1375504D03*
X1371803D03*
X1368102D03*
X1377354Y976339D03*
X1373653D03*
X1369953D03*
X1366252D03*
X1379205Y979528D03*
X1375504D03*
X1371803D03*
X1368102D03*
X1377354Y982717D03*
X1373653D03*
X1369953D03*
X1366252D03*
X1379205Y985906D03*
X1375504D03*
X1371803D03*
X1368102D03*
X1377354Y989095D03*
X1373653D03*
X1369953D03*
X1366252D03*
X1379205Y992284D03*
X1375504D03*
X1371803D03*
X1368102D03*
X1377354Y995473D03*
X1373653D03*
X1369953D03*
X1366252D03*
X1379205Y998662D03*
X1375504D03*
X1371803D03*
X1368102D03*
X1377354Y1001851D03*
X1373653D03*
X1369953D03*
X1366252D03*
X1379205Y1005040D03*
X1375504D03*
X1371803D03*
X1368102D03*
X1377354Y1008229D03*
X1373653D03*
X1369953D03*
X1366252D03*
X1379205Y1011418D03*
X1375504D03*
X1371803D03*
X1368102D03*
X1376685Y1027008D03*
X1372984D03*
X1369283D03*
X1365583D03*
X1378535Y1030197D03*
X1374835D03*
X1371134D03*
X1367433D03*
X1376685Y1033386D03*
X1372984D03*
X1369283D03*
X1365583D03*
X1378535Y1036575D03*
X1374835D03*
X1371134D03*
X1367433D03*
X1376685Y1039764D03*
X1372984D03*
X1369283D03*
X1365583D03*
X1378535Y1042953D03*
X1374835D03*
X1371134D03*
X1367433D03*
X1376685Y1046142D03*
X1372984D03*
X1369283D03*
X1365583D03*
X1378535Y1049331D03*
X1374835D03*
X1371134D03*
X1367433D03*
X1376685Y1052520D03*
X1372984D03*
X1369283D03*
X1365583D03*
X1378535Y1055709D03*
X1374835D03*
X1371134D03*
X1367433D03*
X1376685Y1058898D03*
X1372984D03*
X1369283D03*
X1365583D03*
X1378535Y1062087D03*
X1374835D03*
X1371134D03*
X1367433D03*
X1376685Y1065276D03*
X1372984D03*
X1369283D03*
X1365583D03*
X1378535Y1068465D03*
X1374835D03*
X1371134D03*
X1367433D03*
X1376685Y1071654D03*
X1372984D03*
X1369283D03*
X1365583D03*
X1378535Y1074843D03*
X1374835D03*
X1371134D03*
X1367433D03*
X1376685Y1078032D03*
X1372984D03*
X1369283D03*
X1365583D03*
X1378535Y1081221D03*
X1374835D03*
X1371134D03*
X1367433D03*
X1376685Y1084410D03*
X1372984D03*
X1369283D03*
X1365583D03*
X1378535Y1087599D03*
X1374835D03*
X1371134D03*
X1367433D03*
X1376685Y1090788D03*
X1372984D03*
X1369283D03*
X1365583D03*
X1378535Y1093977D03*
X1374835D03*
X1371134D03*
X1367433D03*
X1376685Y1097166D03*
X1372984D03*
X1369283D03*
X1365583D03*
X1378535Y1100355D03*
X1374835D03*
X1371134D03*
X1367433D03*
X1376685Y1103544D03*
X1372984D03*
X1369283D03*
X1365583D03*
X1378535Y1106733D03*
X1374835D03*
X1371134D03*
X1367433D03*
X1376685Y1109922D03*
X1372984D03*
X1369283D03*
X1365583D03*
X1378535Y1113111D03*
X1374835D03*
X1371134D03*
X1367433D03*
X1376685Y1116300D03*
X1372984D03*
X1369283D03*
X1365583D03*
X1378535Y1119489D03*
X1374835D03*
X1371134D03*
X1367433D03*
X1376685Y1122678D03*
X1372984D03*
X1369283D03*
X1365583D03*
X1378535Y1125867D03*
X1374835D03*
X1371134D03*
X1367433D03*
X1376685Y1129056D03*
X1372984D03*
X1369283D03*
X1365583D03*
X1378535Y1132245D03*
X1374835D03*
X1371134D03*
X1367433D03*
X1376685Y1135433D03*
X1372984D03*
X1369283D03*
X1365583D03*
X1378535Y1138622D03*
X1374835D03*
X1371134D03*
X1367433D03*
X1376685Y1141811D03*
X1372984D03*
X1369283D03*
X1365583D03*
X1378535Y1145000D03*
X1374835D03*
X1371134D03*
X1367433D03*
X1376685Y1148189D03*
X1372984D03*
X1369283D03*
X1365583D03*
X1378535Y1151378D03*
X1374835D03*
X1371134D03*
X1367433D03*
X1376685Y1154567D03*
X1372984D03*
X1369283D03*
X1365583D03*
X1378535Y1157756D03*
X1374835D03*
X1371134D03*
X1367433D03*
X1376685Y1160945D03*
X1372984D03*
X1369283D03*
X1365583D03*
X1378535Y1164134D03*
X1374835D03*
X1371134D03*
X1392157Y874292D03*
X1384756D03*
X1381055D03*
X1394008Y877481D03*
X1390307D03*
X1386606D03*
X1382905D03*
X1392157Y880670D03*
X1388457D03*
X1384756D03*
X1381055D03*
X1394008Y883859D03*
X1390307D03*
X1386606D03*
X1382905D03*
X1392157Y887048D03*
X1388457D03*
X1384756D03*
X1381055D03*
X1394008Y890237D03*
X1390307D03*
X1386606D03*
X1382905D03*
X1392157Y893426D03*
X1388457D03*
X1384756D03*
X1381055D03*
X1394008Y896615D03*
X1390307D03*
X1386606D03*
X1382905D03*
X1392157Y899804D03*
X1388457D03*
X1384756D03*
X1381055D03*
X1394008Y902993D03*
X1390307D03*
X1386606D03*
X1382905D03*
X1392157Y906181D03*
X1388457D03*
X1384756D03*
X1381055D03*
X1394008Y909370D03*
X1390307D03*
X1386606D03*
X1382905D03*
X1392157Y912559D03*
X1388457D03*
X1384756D03*
X1381055D03*
X1394008Y915748D03*
X1390307D03*
X1386606D03*
X1382905D03*
X1392157Y918937D03*
X1388457D03*
X1384756D03*
X1381055D03*
X1394008Y922126D03*
X1390307D03*
X1386606D03*
X1382905D03*
X1392157Y925315D03*
X1388457D03*
X1384756D03*
X1381055D03*
X1394008Y928504D03*
X1390307D03*
X1386606D03*
X1382905D03*
X1392157Y931693D03*
X1388457D03*
X1384756D03*
X1381055D03*
X1394008Y934882D03*
X1390307D03*
X1386606D03*
X1382905D03*
X1392157Y938071D03*
X1388457D03*
X1384756D03*
X1381055D03*
X1394008Y941260D03*
X1390307D03*
X1386606D03*
X1382905D03*
X1392157Y944449D03*
X1388457D03*
X1384756D03*
X1381055D03*
X1394008Y947638D03*
X1390307D03*
X1386606D03*
X1382905D03*
X1392157Y950827D03*
X1388457D03*
X1384756D03*
X1381055D03*
X1394008Y954016D03*
X1390307D03*
X1386606D03*
X1382905D03*
X1392157Y957205D03*
X1388457D03*
X1384756D03*
X1381055D03*
X1394008Y960394D03*
X1390307D03*
X1386606D03*
X1382905D03*
X1392157Y963583D03*
X1388457D03*
X1384756D03*
X1381055D03*
X1394008Y966772D03*
X1390307D03*
X1386606D03*
X1382905D03*
X1392157Y969961D03*
X1388457D03*
X1384756D03*
X1381055D03*
X1394008Y973150D03*
X1390307D03*
X1386606D03*
X1382905D03*
X1392157Y976339D03*
X1388457D03*
X1384756D03*
X1381055D03*
X1394008Y979528D03*
X1390307D03*
X1386606D03*
X1382905D03*
X1392157Y982717D03*
X1388457D03*
X1384756D03*
X1381055D03*
X1394008Y985906D03*
X1390307D03*
X1386606D03*
X1382905D03*
X1392157Y989095D03*
X1388457D03*
X1384756D03*
X1381055D03*
X1394008Y992284D03*
X1390307D03*
X1386606D03*
X1382905D03*
X1381055Y995473D03*
Y1001851D03*
Y1008229D03*
X1380386Y1027008D03*
X1382236Y1030197D03*
X1380386Y1033386D03*
X1382236Y1036575D03*
X1380386Y1039764D03*
X1382236Y1042953D03*
X1391488Y1046142D03*
X1387787D03*
X1384086D03*
X1380386D03*
X1393338Y1049331D03*
X1389638D03*
X1385937D03*
X1382236D03*
X1391488Y1052520D03*
X1387787D03*
X1384086D03*
X1380386D03*
X1393338Y1055709D03*
X1389638D03*
X1385937D03*
X1382236D03*
X1391488Y1058898D03*
X1387787D03*
X1384086D03*
X1380386D03*
X1393338Y1062087D03*
X1389638D03*
X1385937D03*
X1382236D03*
X1391488Y1065276D03*
X1387787D03*
X1384086D03*
X1380386D03*
X1393338Y1068465D03*
X1389638D03*
X1385937D03*
X1382236D03*
X1391488Y1071654D03*
X1387787D03*
X1384086D03*
X1380386D03*
X1393338Y1074843D03*
X1389638D03*
X1385937D03*
X1382236D03*
X1391488Y1078032D03*
X1387787D03*
X1384086D03*
X1380386D03*
X1393338Y1081221D03*
X1389638D03*
X1385937D03*
X1382236D03*
X1391488Y1084410D03*
X1387787D03*
X1384086D03*
X1380386D03*
X1393338Y1087599D03*
X1389638D03*
X1385937D03*
X1382236D03*
X1391488Y1090788D03*
X1387787D03*
X1384086D03*
X1380386D03*
X1393338Y1093977D03*
X1389638D03*
X1385937D03*
X1382236D03*
X1391488Y1097166D03*
X1387787D03*
X1384086D03*
X1380386D03*
X1393338Y1100355D03*
X1389638D03*
X1385937D03*
X1382236D03*
X1391488Y1103544D03*
X1387787D03*
X1384086D03*
X1380386D03*
X1393338Y1106733D03*
X1389638D03*
X1385937D03*
X1382236D03*
X1391488Y1109922D03*
X1387787D03*
X1384086D03*
X1380386D03*
X1393338Y1113111D03*
X1389638D03*
X1385937D03*
X1382236D03*
X1391488Y1116300D03*
X1387787D03*
X1384086D03*
X1380386D03*
X1393338Y1119489D03*
X1389638D03*
X1385937D03*
X1382236D03*
X1391488Y1122678D03*
X1387787D03*
X1384086D03*
X1380386D03*
X1393338Y1125867D03*
X1389638D03*
X1385937D03*
X1382236D03*
X1391488Y1129056D03*
X1387787D03*
X1384086D03*
X1380386D03*
X1393338Y1132245D03*
X1389638D03*
X1385937D03*
X1382236D03*
X1391488Y1135433D03*
X1387787D03*
X1384086D03*
X1380386D03*
X1393338Y1138622D03*
X1389638D03*
X1385937D03*
X1382236D03*
X1391488Y1141811D03*
X1387787D03*
X1384086D03*
X1380386D03*
X1393338Y1145000D03*
X1389638D03*
X1385937D03*
X1382236D03*
X1391488Y1148189D03*
X1387787D03*
X1384086D03*
X1380386D03*
X1393338Y1151378D03*
X1389638D03*
X1385937D03*
X1382236D03*
X1391488Y1154567D03*
X1387787D03*
X1384086D03*
X1380386D03*
X1393338Y1157756D03*
X1389638D03*
X1385937D03*
X1382236D03*
X1391488Y1160945D03*
X1387787D03*
X1384086D03*
X1380386D03*
X1393338Y1164134D03*
X1385937D03*
X1382236D03*
X1406960Y874292D03*
X1403260D03*
X1399559D03*
X1395858D03*
X1408811Y877481D03*
X1405110D03*
X1401409D03*
X1397709D03*
X1406960Y880670D03*
X1403260D03*
X1399559D03*
X1395858D03*
X1408811Y883859D03*
X1405110D03*
X1401409D03*
X1397709D03*
X1406960Y887048D03*
X1403260D03*
X1399559D03*
X1395858D03*
X1408811Y890237D03*
X1405110D03*
X1401409D03*
X1397709D03*
X1406960Y893426D03*
X1403260D03*
X1399559D03*
X1395858D03*
X1408811Y896615D03*
X1405110D03*
X1401409D03*
X1397709D03*
X1406960Y899804D03*
X1403260D03*
X1399559D03*
X1395858D03*
X1408811Y902993D03*
X1405110D03*
X1401409D03*
X1397709D03*
X1406960Y906181D03*
X1403260D03*
X1399559D03*
X1395858D03*
X1408811Y909370D03*
X1405110D03*
X1401409D03*
X1397709D03*
X1406960Y912559D03*
X1403260D03*
X1399559D03*
X1395858D03*
X1408811Y915748D03*
X1405110D03*
X1401409D03*
X1397709D03*
X1406960Y918937D03*
X1403260D03*
X1399559D03*
X1395858D03*
X1408811Y922126D03*
X1405110D03*
X1401409D03*
X1397709D03*
X1406960Y925315D03*
X1403260D03*
X1399559D03*
X1395858D03*
X1408811Y928504D03*
X1405110D03*
X1401409D03*
X1397709D03*
X1406960Y931693D03*
X1403260D03*
X1399559D03*
X1395858D03*
X1408811Y934882D03*
X1405110D03*
X1401409D03*
X1397709D03*
X1406960Y938071D03*
X1403260D03*
X1399559D03*
X1395858D03*
X1408811Y941260D03*
X1405110D03*
X1401409D03*
X1397709D03*
X1406960Y944449D03*
X1403260D03*
X1399559D03*
X1395858D03*
X1408811Y947638D03*
X1405110D03*
X1401409D03*
X1397709D03*
X1406960Y950827D03*
X1403260D03*
X1399559D03*
X1395858D03*
X1408811Y954016D03*
X1405110D03*
X1401409D03*
X1397709D03*
X1406960Y957205D03*
X1403260D03*
X1399559D03*
X1395858D03*
X1408811Y960394D03*
X1405110D03*
X1401409D03*
X1397709D03*
X1406960Y963583D03*
X1403260D03*
X1399559D03*
X1395858D03*
X1408811Y966772D03*
X1405110D03*
X1401409D03*
X1397709D03*
X1406960Y969961D03*
X1403260D03*
X1399559D03*
X1395858D03*
X1408811Y973150D03*
X1405110D03*
X1401409D03*
X1397709D03*
X1406960Y976339D03*
X1403260D03*
X1399559D03*
X1395858D03*
X1408811Y979528D03*
X1405110D03*
X1401409D03*
X1397709D03*
X1406960Y982717D03*
X1403260D03*
X1399559D03*
X1395858D03*
X1408811Y985906D03*
X1405110D03*
X1401409D03*
X1397709D03*
X1406960Y989095D03*
X1403260D03*
X1399559D03*
X1395858D03*
X1408811Y992284D03*
X1405110D03*
X1401409D03*
X1397709D03*
X1406291Y1046142D03*
X1402590D03*
X1398890D03*
X1395189D03*
X1408142Y1049331D03*
X1404441D03*
X1400740D03*
X1397039D03*
X1406291Y1052520D03*
X1402590D03*
X1398890D03*
X1395189D03*
X1408142Y1055709D03*
X1404441D03*
X1400740D03*
X1397039D03*
X1406291Y1058898D03*
X1402590D03*
X1398890D03*
X1395189D03*
X1408142Y1062087D03*
X1404441D03*
X1400740D03*
X1397039D03*
X1406291Y1065276D03*
X1402590D03*
X1398890D03*
X1395189D03*
X1408142Y1068465D03*
X1404441D03*
X1400740D03*
X1397039D03*
X1406291Y1071654D03*
X1402590D03*
X1398890D03*
X1395189D03*
X1408142Y1074843D03*
X1404441D03*
X1400740D03*
X1397039D03*
X1406291Y1078032D03*
X1402590D03*
X1398890D03*
X1395189D03*
X1408142Y1081221D03*
X1404441D03*
X1400740D03*
X1397039D03*
X1406291Y1084410D03*
X1402590D03*
X1398890D03*
X1395189D03*
X1408142Y1087599D03*
X1404441D03*
X1400740D03*
X1397039D03*
X1406291Y1090788D03*
X1402590D03*
X1398890D03*
X1395189D03*
X1408142Y1093977D03*
X1404441D03*
X1400740D03*
X1397039D03*
X1406291Y1097166D03*
X1402590D03*
X1398890D03*
X1395189D03*
X1408142Y1100355D03*
X1404441D03*
X1400740D03*
X1397039D03*
X1406291Y1103544D03*
X1402590D03*
X1398890D03*
X1395189D03*
X1408142Y1106733D03*
X1404441D03*
X1400740D03*
X1397039D03*
X1406291Y1109922D03*
X1402590D03*
X1398890D03*
X1395189D03*
X1408142Y1113111D03*
X1404441D03*
X1400740D03*
X1397039D03*
X1406291Y1116300D03*
X1402590D03*
X1398890D03*
X1395189D03*
X1408142Y1119489D03*
X1404441D03*
X1400740D03*
X1397039D03*
X1406291Y1122678D03*
X1402590D03*
X1398890D03*
X1395189D03*
X1408142Y1125867D03*
X1404441D03*
X1400740D03*
X1397039D03*
X1406291Y1129056D03*
X1402590D03*
X1398890D03*
X1395189D03*
X1408142Y1132245D03*
X1404441D03*
X1400740D03*
X1397039D03*
X1406291Y1135433D03*
X1402590D03*
X1398890D03*
X1395189D03*
X1408142Y1138622D03*
X1404441D03*
X1400740D03*
X1397039D03*
X1406291Y1141811D03*
X1402590D03*
X1398890D03*
X1395189D03*
X1408142Y1145000D03*
X1404441D03*
X1400740D03*
X1397039D03*
X1406291Y1148189D03*
X1402590D03*
X1398890D03*
X1395189D03*
X1408142Y1151378D03*
X1404441D03*
X1400740D03*
X1397039D03*
X1406291Y1154567D03*
X1402590D03*
X1398890D03*
X1395189D03*
X1408142Y1157756D03*
X1404441D03*
X1400740D03*
X1397039D03*
X1406291Y1160945D03*
X1402590D03*
X1398890D03*
X1395189D03*
X1408142Y1164134D03*
X1404441D03*
X1400740D03*
X1397039D03*
X1423614Y877481D03*
X1419913D03*
X1412512D03*
X1421764Y880670D03*
X1410661D03*
X1423614Y883859D03*
X1419913D03*
X1412512D03*
X1421764Y887048D03*
X1410661D03*
X1423614Y890237D03*
X1419913D03*
X1412512D03*
X1421764Y893426D03*
X1410661D03*
X1423614Y896615D03*
X1419913D03*
X1412512D03*
X1421764Y899804D03*
X1410661D03*
X1423614Y902993D03*
X1419913D03*
X1412512D03*
X1421764Y906181D03*
X1410661D03*
X1423614Y909370D03*
X1419913D03*
X1412512D03*
X1421764Y912559D03*
X1410661D03*
X1423614Y915748D03*
X1419913D03*
X1412512D03*
X1421764Y918937D03*
X1410661D03*
X1423614Y922126D03*
X1419913D03*
X1412512D03*
X1421764Y925315D03*
X1410661D03*
X1423614Y928504D03*
X1419913D03*
X1412512D03*
X1421764Y931693D03*
X1410661D03*
X1423614Y934882D03*
X1419913D03*
X1412512D03*
X1421764Y938071D03*
X1410661D03*
X1423614Y941260D03*
X1419913D03*
X1412512D03*
X1421764Y944449D03*
X1410661D03*
X1423614Y947638D03*
X1419913D03*
X1412512D03*
X1421764Y950827D03*
X1410661D03*
X1423614Y954016D03*
X1419913D03*
X1412512D03*
X1421764Y957205D03*
X1410661D03*
X1423614Y960394D03*
X1419913D03*
X1412512D03*
X1421764Y963583D03*
X1410661D03*
X1423614Y966772D03*
X1419913D03*
X1412512D03*
X1421764Y969961D03*
X1410661D03*
X1423614Y973150D03*
X1419913D03*
X1412512D03*
X1421764Y976339D03*
X1410661D03*
X1423614Y979528D03*
X1419913D03*
X1412512D03*
X1421764Y982717D03*
X1410661D03*
X1423614Y985906D03*
X1419913D03*
X1412512D03*
X1421764Y989095D03*
X1410661D03*
X1423614Y992284D03*
X1419913D03*
X1412512D03*
X1421094Y1046142D03*
X1413693D03*
X1409992D03*
X1422945Y1049331D03*
X1411842D03*
X1421094Y1052520D03*
X1413693D03*
X1409992D03*
X1422945Y1055709D03*
X1411842D03*
X1421094Y1058898D03*
X1413693D03*
X1409992D03*
X1422945Y1062087D03*
X1411842D03*
X1421094Y1065276D03*
X1413693D03*
X1409992D03*
X1422945Y1068465D03*
X1411842D03*
X1421094Y1071654D03*
X1413693D03*
X1409992D03*
X1422945Y1074843D03*
X1411842D03*
X1421094Y1078032D03*
X1413693D03*
X1409992D03*
X1422945Y1081221D03*
X1411842D03*
X1421094Y1084410D03*
X1413693D03*
X1409992D03*
X1422945Y1087599D03*
X1411842D03*
X1421094Y1090788D03*
X1413693D03*
X1409992D03*
X1422945Y1093977D03*
X1411842D03*
X1421094Y1097166D03*
X1413693D03*
X1409992D03*
X1422945Y1100355D03*
X1411842D03*
X1421094Y1103544D03*
X1413693D03*
X1409992D03*
X1422945Y1106733D03*
X1411842D03*
X1421094Y1109922D03*
X1413693D03*
X1409992D03*
X1422945Y1113111D03*
X1411842D03*
X1421094Y1116300D03*
X1413693D03*
X1409992D03*
X1422945Y1119489D03*
X1411842D03*
X1421094Y1122678D03*
X1413693D03*
X1409992D03*
X1422945Y1125867D03*
X1411842D03*
X1421094Y1129056D03*
X1413693D03*
X1409992D03*
X1422945Y1132245D03*
X1411842D03*
X1421094Y1135433D03*
X1413693D03*
X1409992D03*
X1422945Y1138622D03*
X1411842D03*
X1421094Y1141811D03*
X1413693D03*
X1409992D03*
X1422945Y1145000D03*
X1411842D03*
X1421094Y1148189D03*
X1413693D03*
X1409992D03*
X1422945Y1151378D03*
X1411842D03*
X1421094Y1154567D03*
X1413693D03*
X1409992D03*
X1422945Y1157756D03*
X1411842D03*
X1421094Y1160945D03*
X1413693D03*
X1409992D03*
X1436567Y874292D03*
X1432866D03*
X1429165D03*
X1425464D03*
X1438417Y877481D03*
X1434716D03*
X1431016D03*
X1427315D03*
X1436567Y880670D03*
X1432866D03*
X1429165D03*
X1425464D03*
X1438417Y883859D03*
X1434716D03*
X1431016D03*
X1427315D03*
X1436567Y887048D03*
X1432866D03*
X1429165D03*
X1425464D03*
X1438417Y890237D03*
X1434716D03*
X1431016D03*
X1427315D03*
X1436567Y893426D03*
X1432866D03*
X1429165D03*
X1425464D03*
X1438417Y896615D03*
X1434716D03*
X1431016D03*
X1427315D03*
X1436567Y899804D03*
X1432866D03*
X1429165D03*
X1425464D03*
X1438417Y902993D03*
X1434716D03*
X1431016D03*
X1427315D03*
X1436567Y906181D03*
X1432866D03*
X1429165D03*
X1425464D03*
X1438417Y909370D03*
X1434716D03*
X1431016D03*
X1427315D03*
X1436567Y912559D03*
X1432866D03*
X1429165D03*
X1425464D03*
X1438417Y915748D03*
X1434716D03*
X1431016D03*
X1427315D03*
X1436567Y918937D03*
X1432866D03*
X1429165D03*
X1425464D03*
X1438417Y922126D03*
X1434716D03*
X1431016D03*
X1427315D03*
X1436567Y925315D03*
X1432866D03*
X1429165D03*
X1425464D03*
X1438417Y928504D03*
X1434716D03*
X1431016D03*
X1427315D03*
X1436567Y931693D03*
X1432866D03*
X1429165D03*
X1425464D03*
X1438417Y934882D03*
X1434716D03*
X1431016D03*
X1427315D03*
X1436567Y938071D03*
X1432866D03*
X1429165D03*
X1425464D03*
X1438417Y941260D03*
X1434716D03*
X1431016D03*
X1427315D03*
X1436567Y944449D03*
X1432866D03*
X1429165D03*
X1425464D03*
X1438417Y947638D03*
X1434716D03*
X1431016D03*
X1427315D03*
X1436567Y950827D03*
X1432866D03*
X1429165D03*
X1425464D03*
X1438417Y954016D03*
X1434716D03*
X1431016D03*
X1427315D03*
X1436567Y957205D03*
X1432866D03*
X1429165D03*
X1425464D03*
X1438417Y960394D03*
X1434716D03*
X1431016D03*
X1427315D03*
X1436567Y963583D03*
X1432866D03*
X1429165D03*
X1425464D03*
X1438417Y966772D03*
X1434716D03*
X1431016D03*
X1427315D03*
X1436567Y969961D03*
X1432866D03*
X1429165D03*
X1425464D03*
X1438417Y973150D03*
X1434716D03*
X1431016D03*
X1427315D03*
X1436567Y976339D03*
X1432866D03*
X1429165D03*
X1425464D03*
X1438417Y979528D03*
X1434716D03*
X1431016D03*
X1427315D03*
X1436567Y982717D03*
X1432866D03*
X1429165D03*
X1425464D03*
X1438417Y985906D03*
X1434716D03*
X1431016D03*
X1427315D03*
X1436567Y989095D03*
X1432866D03*
X1429165D03*
X1425464D03*
X1438417Y992284D03*
X1434716D03*
X1431016D03*
X1427315D03*
X1435897Y1046142D03*
X1432197D03*
X1428496D03*
X1424795D03*
X1437748Y1049331D03*
X1434047D03*
X1430346D03*
X1426646D03*
X1435897Y1052520D03*
X1432197D03*
X1428496D03*
X1424795D03*
X1437748Y1055709D03*
X1434047D03*
X1430346D03*
X1426646D03*
X1435897Y1058898D03*
X1432197D03*
X1428496D03*
X1424795D03*
X1437748Y1062087D03*
X1434047D03*
X1430346D03*
X1426646D03*
X1435897Y1065276D03*
X1432197D03*
X1428496D03*
X1424795D03*
X1437748Y1068465D03*
X1434047D03*
X1430346D03*
X1426646D03*
X1435897Y1071654D03*
X1432197D03*
X1428496D03*
X1424795D03*
X1437748Y1074843D03*
X1434047D03*
X1430346D03*
X1426646D03*
X1435897Y1078032D03*
X1432197D03*
X1428496D03*
X1424795D03*
X1437748Y1081221D03*
X1434047D03*
X1430346D03*
X1426646D03*
X1435897Y1084410D03*
X1432197D03*
X1428496D03*
X1424795D03*
X1437748Y1087599D03*
X1434047D03*
X1430346D03*
X1426646D03*
X1435897Y1090788D03*
X1432197D03*
X1428496D03*
X1424795D03*
X1437748Y1093977D03*
X1434047D03*
X1430346D03*
X1426646D03*
X1435897Y1097166D03*
X1432197D03*
X1428496D03*
X1424795D03*
X1437748Y1100355D03*
X1434047D03*
X1430346D03*
X1426646D03*
X1435897Y1103544D03*
X1432197D03*
X1428496D03*
X1424795D03*
X1437748Y1106733D03*
X1434047D03*
X1430346D03*
X1426646D03*
X1435897Y1109922D03*
X1432197D03*
X1428496D03*
X1424795D03*
X1437748Y1113111D03*
X1434047D03*
X1430346D03*
X1426646D03*
X1435897Y1116300D03*
X1432197D03*
X1428496D03*
X1424795D03*
X1437748Y1119489D03*
X1434047D03*
X1430346D03*
X1426646D03*
X1435897Y1122678D03*
X1432197D03*
X1428496D03*
X1424795D03*
X1437748Y1125867D03*
X1434047D03*
X1430346D03*
X1426646D03*
X1435897Y1129056D03*
X1432197D03*
X1428496D03*
X1424795D03*
X1437748Y1132245D03*
X1434047D03*
X1430346D03*
X1426646D03*
X1435897Y1135433D03*
X1432197D03*
X1428496D03*
X1424795D03*
X1437748Y1138622D03*
X1434047D03*
X1430346D03*
X1426646D03*
X1435897Y1141811D03*
X1432197D03*
X1428496D03*
X1424795D03*
X1437748Y1145000D03*
X1434047D03*
X1430346D03*
X1426646D03*
X1435897Y1148189D03*
X1432197D03*
X1428496D03*
X1424795D03*
X1437748Y1151378D03*
X1434047D03*
X1430346D03*
X1426646D03*
X1435897Y1154567D03*
X1432197D03*
X1428496D03*
X1424795D03*
X1437748Y1157756D03*
X1434047D03*
X1430346D03*
X1426646D03*
X1435897Y1160945D03*
X1432197D03*
X1428496D03*
X1424795D03*
X1437748Y1164134D03*
X1434047D03*
X1430346D03*
X1426646D03*
X1451370Y874292D03*
X1447669D03*
X1440268D03*
X1453220Y877481D03*
X1449520D03*
X1445819D03*
X1442118D03*
X1451370Y880670D03*
X1447669D03*
X1443968D03*
X1440268D03*
X1453220Y883859D03*
X1449520D03*
X1445819D03*
X1442118D03*
X1451370Y887048D03*
X1447669D03*
X1443968D03*
X1440268D03*
X1453220Y890237D03*
X1449520D03*
X1445819D03*
X1442118D03*
X1451370Y893426D03*
X1447669D03*
X1443968D03*
X1440268D03*
X1453220Y896615D03*
X1449520D03*
X1445819D03*
X1442118D03*
X1451370Y899804D03*
X1447669D03*
X1443968D03*
X1440268D03*
X1453220Y902993D03*
X1449520D03*
X1445819D03*
X1442118D03*
X1451370Y906181D03*
X1447669D03*
X1443968D03*
X1440268D03*
X1453220Y909370D03*
X1449520D03*
X1445819D03*
X1442118D03*
X1451370Y912559D03*
X1447669D03*
X1443968D03*
X1440268D03*
X1453220Y915748D03*
X1449520D03*
X1445819D03*
X1442118D03*
X1451370Y918937D03*
X1447669D03*
X1443968D03*
X1440268D03*
X1453220Y922126D03*
X1449520D03*
X1445819D03*
X1442118D03*
X1451370Y925315D03*
X1447669D03*
X1443968D03*
X1440268D03*
X1453220Y928504D03*
X1449520D03*
X1445819D03*
X1442118D03*
X1451370Y931693D03*
X1447669D03*
X1443968D03*
X1440268D03*
X1453220Y934882D03*
X1449520D03*
X1445819D03*
X1442118D03*
X1451370Y938071D03*
X1447669D03*
X1443968D03*
X1440268D03*
X1453220Y941260D03*
X1449520D03*
X1445819D03*
X1442118D03*
X1451370Y944449D03*
X1447669D03*
X1443968D03*
X1440268D03*
X1453220Y947638D03*
X1449520D03*
X1445819D03*
X1442118D03*
X1451370Y950827D03*
X1447669D03*
X1443968D03*
X1440268D03*
X1453220Y954016D03*
X1449520D03*
X1445819D03*
X1442118D03*
X1451370Y957205D03*
X1447669D03*
X1443968D03*
X1440268D03*
X1453220Y960394D03*
X1449520D03*
X1445819D03*
X1442118D03*
X1451370Y963583D03*
X1447669D03*
X1443968D03*
X1440268D03*
X1453220Y966772D03*
X1449520D03*
X1445819D03*
X1442118D03*
X1451370Y969961D03*
X1447669D03*
X1443968D03*
X1440268D03*
X1453220Y973150D03*
X1449520D03*
X1445819D03*
X1442118D03*
X1451370Y976339D03*
X1447669D03*
X1443968D03*
X1440268D03*
X1453220Y979528D03*
X1449520D03*
X1445819D03*
X1442118D03*
X1451370Y982717D03*
X1447669D03*
X1443968D03*
X1440268D03*
X1453220Y985906D03*
X1449520D03*
X1445819D03*
X1442118D03*
X1451370Y989095D03*
X1447669D03*
X1443968D03*
X1440268D03*
X1453220Y992284D03*
X1449520D03*
X1445819D03*
X1442118D03*
X1451370Y995473D03*
X1453220Y998662D03*
X1451370Y1001851D03*
X1453220Y1005040D03*
X1451370Y1008229D03*
X1453220Y1011418D03*
X1452551Y1030197D03*
Y1036575D03*
Y1042953D03*
X1450701Y1046142D03*
X1447000D03*
X1443299D03*
X1439598D03*
X1452551Y1049331D03*
X1448850D03*
X1445149D03*
X1441449D03*
X1450701Y1052520D03*
X1447000D03*
X1443299D03*
X1439598D03*
X1452551Y1055709D03*
X1448850D03*
X1445149D03*
X1441449D03*
X1450701Y1058898D03*
X1447000D03*
X1443299D03*
X1439598D03*
X1452551Y1062087D03*
X1448850D03*
X1445149D03*
X1441449D03*
X1450701Y1065276D03*
X1447000D03*
X1443299D03*
X1439598D03*
X1452551Y1068465D03*
X1448850D03*
X1445149D03*
X1441449D03*
X1450701Y1071654D03*
X1447000D03*
X1443299D03*
X1439598D03*
X1452551Y1074843D03*
X1448850D03*
X1445149D03*
X1441449D03*
X1450701Y1078032D03*
X1447000D03*
X1443299D03*
X1439598D03*
X1452551Y1081221D03*
X1448850D03*
X1445149D03*
X1441449D03*
X1450701Y1084410D03*
X1447000D03*
X1443299D03*
X1439598D03*
X1452551Y1087599D03*
X1448850D03*
X1445149D03*
X1441449D03*
X1450701Y1090788D03*
X1447000D03*
X1443299D03*
X1439598D03*
X1452551Y1093977D03*
X1448850D03*
X1445149D03*
X1441449D03*
X1450701Y1097166D03*
X1447000D03*
X1443299D03*
X1439598D03*
X1452551Y1100355D03*
X1448850D03*
X1445149D03*
X1441449D03*
X1450701Y1103544D03*
X1447000D03*
X1443299D03*
X1439598D03*
X1452551Y1106733D03*
X1448850D03*
X1445149D03*
X1441449D03*
X1450701Y1109922D03*
X1447000D03*
X1443299D03*
X1439598D03*
X1452551Y1113111D03*
X1448850D03*
X1445149D03*
X1441449D03*
X1450701Y1116300D03*
X1447000D03*
X1443299D03*
X1439598D03*
X1452551Y1119489D03*
X1448850D03*
X1445149D03*
X1441449D03*
X1450701Y1122678D03*
X1447000D03*
X1443299D03*
X1439598D03*
X1452551Y1125867D03*
X1448850D03*
X1445149D03*
X1441449D03*
X1450701Y1129056D03*
X1447000D03*
X1443299D03*
X1439598D03*
X1452551Y1132245D03*
X1448850D03*
X1445149D03*
X1441449D03*
X1450701Y1135433D03*
X1447000D03*
X1443299D03*
X1439598D03*
X1452551Y1138622D03*
X1448850D03*
X1445149D03*
X1441449D03*
X1450701Y1141811D03*
X1447000D03*
X1443299D03*
X1439598D03*
X1452551Y1145000D03*
X1448850D03*
X1445149D03*
X1441449D03*
X1450701Y1148189D03*
X1447000D03*
X1443299D03*
X1439598D03*
X1452551Y1151378D03*
X1448850D03*
X1445149D03*
X1441449D03*
X1450701Y1154567D03*
X1447000D03*
X1443299D03*
X1439598D03*
X1452551Y1157756D03*
X1448850D03*
X1445149D03*
X1441449D03*
X1450701Y1160945D03*
X1447000D03*
X1443299D03*
X1439598D03*
X1452551Y1164134D03*
X1448850D03*
X1441449D03*
X1462472Y874292D03*
X1458771D03*
X1455071D03*
X1468023Y877481D03*
X1464323D03*
X1460622D03*
X1456921D03*
X1466173Y880670D03*
X1462472D03*
X1458771D03*
X1455071D03*
X1468023Y883859D03*
X1464323D03*
X1460622D03*
X1456921D03*
X1466173Y887048D03*
X1462472D03*
X1458771D03*
X1455071D03*
X1468023Y890237D03*
X1464323D03*
X1460622D03*
X1456921D03*
X1466173Y893426D03*
X1462472D03*
X1458771D03*
X1455071D03*
X1468023Y896615D03*
X1464323D03*
X1460622D03*
X1456921D03*
X1466173Y899804D03*
X1462472D03*
X1458771D03*
X1455071D03*
X1468023Y902993D03*
X1464323D03*
X1460622D03*
X1456921D03*
X1466173Y906181D03*
X1462472D03*
X1458771D03*
X1455071D03*
X1468023Y909370D03*
X1464323D03*
X1460622D03*
X1456921D03*
X1466173Y912559D03*
X1462472D03*
X1458771D03*
X1455071D03*
X1468023Y915748D03*
X1464323D03*
X1460622D03*
X1456921D03*
X1466173Y918937D03*
X1462472D03*
X1458771D03*
X1455071D03*
X1468023Y922126D03*
X1464323D03*
X1460622D03*
X1456921D03*
X1466173Y925315D03*
X1462472D03*
X1458771D03*
X1455071D03*
X1468023Y928504D03*
X1464323D03*
X1460622D03*
X1456921D03*
X1466173Y931693D03*
X1462472D03*
X1458771D03*
X1455071D03*
X1468023Y934882D03*
X1464323D03*
X1460622D03*
X1456921D03*
X1466173Y938071D03*
X1462472D03*
X1458771D03*
X1455071D03*
X1468023Y941260D03*
X1464323D03*
X1460622D03*
X1456921D03*
X1466173Y944449D03*
X1462472D03*
X1458771D03*
X1455071D03*
X1468023Y947638D03*
X1464323D03*
X1460622D03*
X1456921D03*
X1466173Y950827D03*
X1462472D03*
X1458771D03*
X1455071D03*
X1468023Y954016D03*
X1464323D03*
X1460622D03*
X1456921D03*
X1466173Y957205D03*
X1462472D03*
X1458771D03*
X1455071D03*
X1468023Y960394D03*
X1464323D03*
X1460622D03*
X1456921D03*
X1466173Y963583D03*
X1462472D03*
X1458771D03*
X1455071D03*
X1468023Y966772D03*
X1464323D03*
X1460622D03*
X1456921D03*
X1466173Y969961D03*
X1462472D03*
X1458771D03*
X1455071D03*
X1468023Y973150D03*
X1464323D03*
X1460622D03*
X1456921D03*
X1466173Y976339D03*
X1462472D03*
X1458771D03*
X1455071D03*
X1468023Y979528D03*
X1464323D03*
X1460622D03*
X1456921D03*
X1466173Y982717D03*
X1462472D03*
X1458771D03*
X1455071D03*
X1468023Y985906D03*
X1464323D03*
X1460622D03*
X1456921D03*
X1466173Y989095D03*
X1462472D03*
X1458771D03*
X1455071D03*
X1468023Y992284D03*
X1464323D03*
X1460622D03*
X1456921D03*
X1466173Y995473D03*
X1462472D03*
X1458771D03*
X1455071D03*
X1468023Y998662D03*
X1464323D03*
X1460622D03*
X1456921D03*
X1466173Y1001851D03*
X1462472D03*
X1458771D03*
X1455071D03*
X1468023Y1005040D03*
X1464323D03*
X1460622D03*
X1456921D03*
X1466173Y1008229D03*
X1462472D03*
X1458771D03*
X1455071D03*
X1468023Y1011418D03*
X1464323D03*
X1460622D03*
X1456921D03*
X1465504Y1027008D03*
X1461803D03*
X1458102D03*
X1454401D03*
X1467354Y1030197D03*
X1463653D03*
X1459953D03*
X1456252D03*
X1465504Y1033386D03*
X1461803D03*
X1458102D03*
X1454401D03*
X1467354Y1036575D03*
X1463653D03*
X1459953D03*
X1456252D03*
X1465504Y1039764D03*
X1461803D03*
X1458102D03*
X1454401D03*
X1467354Y1042953D03*
X1463653D03*
X1459953D03*
X1456252D03*
X1465504Y1046142D03*
X1461803D03*
X1458102D03*
X1454401D03*
X1467354Y1049331D03*
X1463653D03*
X1459953D03*
X1456252D03*
X1465504Y1052520D03*
X1461803D03*
X1458102D03*
X1454401D03*
X1467354Y1055709D03*
X1463653D03*
X1459953D03*
X1456252D03*
X1465504Y1058898D03*
X1461803D03*
X1458102D03*
X1454401D03*
X1467354Y1062087D03*
X1463653D03*
X1459953D03*
X1456252D03*
X1465504Y1065276D03*
X1461803D03*
X1458102D03*
X1454401D03*
X1467354Y1068465D03*
X1463653D03*
X1459953D03*
X1456252D03*
X1465504Y1071654D03*
X1461803D03*
X1458102D03*
X1454401D03*
X1467354Y1074843D03*
X1463653D03*
X1459953D03*
X1456252D03*
X1465504Y1078032D03*
X1461803D03*
X1458102D03*
X1454401D03*
X1467354Y1081221D03*
X1463653D03*
X1459953D03*
X1456252D03*
X1465504Y1084410D03*
X1461803D03*
X1458102D03*
X1454401D03*
X1467354Y1087599D03*
X1463653D03*
X1459953D03*
X1456252D03*
X1465504Y1090788D03*
X1461803D03*
X1458102D03*
X1454401D03*
X1467354Y1093977D03*
X1463653D03*
X1459953D03*
X1456252D03*
X1465504Y1097166D03*
X1461803D03*
X1458102D03*
X1454401D03*
X1467354Y1100355D03*
X1463653D03*
X1459953D03*
X1456252D03*
X1465504Y1103544D03*
X1461803D03*
X1458102D03*
X1454401D03*
X1467354Y1106733D03*
X1463653D03*
X1459953D03*
X1456252D03*
X1465504Y1109922D03*
X1461803D03*
X1458102D03*
X1454401D03*
X1467354Y1113111D03*
X1463653D03*
X1459953D03*
X1456252D03*
X1465504Y1116300D03*
X1461803D03*
X1458102D03*
X1454401D03*
X1467354Y1119489D03*
X1463653D03*
X1459953D03*
X1456252D03*
X1465504Y1122678D03*
X1461803D03*
X1458102D03*
X1454401D03*
X1467354Y1125867D03*
X1463653D03*
X1459953D03*
X1456252D03*
X1465504Y1129056D03*
X1461803D03*
X1458102D03*
X1454401D03*
X1467354Y1132245D03*
X1463653D03*
X1459953D03*
X1456252D03*
X1465504Y1135433D03*
X1461803D03*
X1458102D03*
X1454401D03*
X1467354Y1138622D03*
X1463653D03*
X1459953D03*
X1456252D03*
X1465504Y1141811D03*
X1461803D03*
X1458102D03*
X1454401D03*
X1467354Y1145000D03*
X1463653D03*
X1459953D03*
X1456252D03*
X1465504Y1148189D03*
X1461803D03*
X1458102D03*
X1454401D03*
X1467354Y1151378D03*
X1463653D03*
X1459953D03*
X1456252D03*
X1465504Y1154567D03*
X1461803D03*
X1458102D03*
X1454401D03*
X1467354Y1157756D03*
X1463653D03*
X1459953D03*
X1456252D03*
X1465504Y1160945D03*
X1461803D03*
X1458102D03*
X1454401D03*
X1463653Y1164134D03*
X1459953D03*
X1456252D03*
X1480976Y874292D03*
X1477275D03*
X1473575D03*
X1469874D03*
X1482827Y877481D03*
X1479126D03*
X1475425D03*
X1471724D03*
X1480976Y880670D03*
X1477275D03*
X1473575D03*
X1469874D03*
X1482827Y883859D03*
X1479126D03*
X1475425D03*
X1471724D03*
X1480976Y887048D03*
X1477275D03*
X1473575D03*
X1469874D03*
X1482827Y890237D03*
X1479126D03*
X1475425D03*
X1471724D03*
X1480976Y893426D03*
X1477275D03*
X1473575D03*
X1469874D03*
X1482827Y896615D03*
X1479126D03*
X1475425D03*
X1471724D03*
X1480976Y899804D03*
X1477275D03*
X1473575D03*
X1469874D03*
X1482827Y902993D03*
X1479126D03*
X1475425D03*
X1471724D03*
X1480976Y906181D03*
X1477275D03*
X1473575D03*
X1469874D03*
X1482827Y909370D03*
X1479126D03*
X1475425D03*
X1471724D03*
X1480976Y912559D03*
X1477275D03*
X1473575D03*
X1469874D03*
X1482827Y915748D03*
X1479126D03*
X1475425D03*
X1471724D03*
X1480976Y918937D03*
X1477275D03*
X1473575D03*
X1469874D03*
X1482827Y922126D03*
X1479126D03*
X1475425D03*
X1471724D03*
X1480976Y925315D03*
X1477275D03*
X1473575D03*
X1469874D03*
X1482827Y928504D03*
X1479126D03*
X1475425D03*
X1471724D03*
X1480976Y931693D03*
X1477275D03*
X1473575D03*
X1469874D03*
X1482827Y934882D03*
X1479126D03*
X1475425D03*
X1471724D03*
X1480976Y938071D03*
X1477275D03*
X1473575D03*
X1469874D03*
X1482827Y941260D03*
X1479126D03*
X1475425D03*
X1471724D03*
X1480976Y944449D03*
X1477275D03*
X1473575D03*
X1469874D03*
X1482827Y947638D03*
X1479126D03*
X1475425D03*
X1471724D03*
X1480976Y950827D03*
X1477275D03*
X1473575D03*
X1469874D03*
X1482827Y954016D03*
X1479126D03*
X1475425D03*
X1471724D03*
X1480976Y957205D03*
X1477275D03*
X1473575D03*
X1469874D03*
X1482827Y960394D03*
X1479126D03*
X1475425D03*
X1471724D03*
X1480976Y963583D03*
X1477275D03*
X1473575D03*
X1469874D03*
X1482827Y966772D03*
X1479126D03*
X1475425D03*
X1471724D03*
X1480976Y969961D03*
X1477275D03*
X1473575D03*
X1469874D03*
X1482827Y973150D03*
X1479126D03*
X1475425D03*
X1471724D03*
X1480976Y976339D03*
X1477275D03*
X1473575D03*
X1469874D03*
X1482827Y979528D03*
X1479126D03*
X1475425D03*
X1471724D03*
X1480976Y982717D03*
X1477275D03*
X1473575D03*
X1469874D03*
X1482827Y985906D03*
X1479126D03*
X1475425D03*
X1471724D03*
X1480976Y989095D03*
X1477275D03*
X1473575D03*
X1469874D03*
X1482827Y992284D03*
X1479126D03*
X1475425D03*
X1471724D03*
X1480976Y995473D03*
X1477275D03*
X1473575D03*
X1469874D03*
X1482827Y998662D03*
X1479126D03*
X1475425D03*
X1471724D03*
X1480976Y1001851D03*
X1477275D03*
X1473575D03*
X1469874D03*
X1482827Y1005040D03*
X1479126D03*
X1475425D03*
X1471724D03*
X1480976Y1008229D03*
X1477275D03*
X1473575D03*
X1469874D03*
X1482827Y1011418D03*
X1479126D03*
X1475425D03*
X1471724D03*
X1480307Y1027008D03*
X1476606D03*
X1472905D03*
X1469205D03*
X1482157Y1030197D03*
X1478457D03*
X1474756D03*
X1471055D03*
X1480307Y1033386D03*
X1476606D03*
X1472905D03*
X1469205D03*
X1482157Y1036575D03*
X1478457D03*
X1474756D03*
X1471055D03*
X1480307Y1039764D03*
X1476606D03*
X1472905D03*
X1469205D03*
X1482157Y1042953D03*
X1478457D03*
X1474756D03*
X1471055D03*
X1480307Y1046142D03*
X1476606D03*
X1472905D03*
X1469205D03*
X1482157Y1049331D03*
X1478457D03*
X1474756D03*
X1471055D03*
X1480307Y1052520D03*
X1476606D03*
X1472905D03*
X1469205D03*
X1482157Y1055709D03*
X1478457D03*
X1474756D03*
X1471055D03*
X1480307Y1058898D03*
X1476606D03*
X1472905D03*
X1469205D03*
X1482157Y1062087D03*
X1478457D03*
X1474756D03*
X1471055D03*
X1480307Y1065276D03*
X1476606D03*
X1472905D03*
X1469205D03*
X1482157Y1068465D03*
X1478457D03*
X1474756D03*
X1471055D03*
X1480307Y1071654D03*
X1476606D03*
X1472905D03*
X1469205D03*
X1482157Y1074843D03*
X1478457D03*
X1474756D03*
X1471055D03*
X1480307Y1078032D03*
X1476606D03*
X1472905D03*
X1469205D03*
X1482157Y1081221D03*
X1478457D03*
X1474756D03*
X1471055D03*
X1480307Y1084410D03*
X1476606D03*
X1472905D03*
X1469205D03*
X1482157Y1087599D03*
X1478457D03*
X1474756D03*
X1471055D03*
X1480307Y1090788D03*
X1476606D03*
X1472905D03*
X1469205D03*
X1482157Y1093977D03*
X1478457D03*
X1474756D03*
X1471055D03*
X1480307Y1097166D03*
X1476606D03*
X1472905D03*
X1469205D03*
X1482157Y1100355D03*
X1478457D03*
X1474756D03*
X1471055D03*
X1480307Y1103544D03*
X1476606D03*
X1472905D03*
X1469205D03*
X1482157Y1106733D03*
X1478457D03*
X1474756D03*
X1471055D03*
X1480307Y1109922D03*
X1476606D03*
X1472905D03*
X1469205D03*
X1482157Y1113111D03*
X1478457D03*
X1474756D03*
X1471055D03*
X1480307Y1116300D03*
X1476606D03*
X1472905D03*
X1469205D03*
X1482157Y1119489D03*
X1478457D03*
X1474756D03*
X1471055D03*
X1480307Y1122678D03*
X1476606D03*
X1472905D03*
X1469205D03*
X1482157Y1125867D03*
X1478457D03*
X1474756D03*
X1471055D03*
X1480307Y1129056D03*
X1476606D03*
X1472905D03*
X1469205D03*
X1482157Y1132245D03*
X1478457D03*
X1474756D03*
X1471055D03*
X1480307Y1135433D03*
X1476606D03*
X1472905D03*
X1469205D03*
X1482157Y1138622D03*
X1478457D03*
X1474756D03*
X1471055D03*
X1480307Y1141811D03*
X1476606D03*
X1472905D03*
X1469205D03*
X1482157Y1145000D03*
X1478457D03*
X1474756D03*
X1471055D03*
X1480307Y1148189D03*
X1476606D03*
X1472905D03*
X1469205D03*
X1482157Y1151378D03*
X1478457D03*
X1474756D03*
X1471055D03*
X1480307Y1154567D03*
X1476606D03*
X1472905D03*
X1469205D03*
X1482157Y1157756D03*
X1478457D03*
X1474756D03*
X1471055D03*
X1480307Y1160945D03*
X1476606D03*
X1472905D03*
X1469205D03*
X1482157Y1164134D03*
X1478457D03*
X1474756D03*
X1471055D03*
X1495779Y874292D03*
X1492079D03*
X1484677D03*
X1497630Y877481D03*
X1493929D03*
X1490228D03*
X1486527D03*
X1495779Y880670D03*
X1492079D03*
X1488378D03*
X1484677D03*
X1497630Y883859D03*
X1493929D03*
X1490228D03*
X1486527D03*
X1495779Y887048D03*
X1492079D03*
X1488378D03*
X1484677D03*
X1497630Y890237D03*
X1493929D03*
X1490228D03*
X1486527D03*
X1495779Y893426D03*
X1492079D03*
X1488378D03*
X1484677D03*
X1497630Y896615D03*
X1493929D03*
X1490228D03*
X1486527D03*
X1495779Y899804D03*
X1492079D03*
X1488378D03*
X1484677D03*
X1497630Y902993D03*
X1493929D03*
X1490228D03*
X1486527D03*
X1495779Y906181D03*
X1492079D03*
X1488378D03*
X1484677D03*
X1497630Y909370D03*
X1493929D03*
X1490228D03*
X1486527D03*
X1495779Y912559D03*
X1492079D03*
X1488378D03*
X1484677D03*
X1497630Y915748D03*
X1493929D03*
X1490228D03*
X1486527D03*
X1495779Y918937D03*
X1492079D03*
X1488378D03*
X1484677D03*
X1497630Y922126D03*
X1493929D03*
X1490228D03*
X1486527D03*
X1495779Y925315D03*
X1492079D03*
X1488378D03*
X1484677D03*
X1497630Y928504D03*
X1493929D03*
X1490228D03*
X1486527D03*
X1495779Y931693D03*
X1492079D03*
X1488378D03*
X1484677D03*
X1497630Y934882D03*
X1493929D03*
X1490228D03*
X1486527D03*
X1495779Y938071D03*
X1492079D03*
X1488378D03*
X1484677D03*
X1497630Y941260D03*
X1493929D03*
X1490228D03*
X1486527D03*
X1495779Y944449D03*
X1492079D03*
X1488378D03*
X1484677D03*
X1497630Y947638D03*
X1493929D03*
X1490228D03*
X1486527D03*
X1495779Y950827D03*
X1492079D03*
X1488378D03*
X1484677D03*
X1497630Y954016D03*
X1493929D03*
X1490228D03*
X1486527D03*
X1495779Y957205D03*
X1492079D03*
X1488378D03*
X1484677D03*
X1497630Y960394D03*
X1493929D03*
X1490228D03*
X1486527D03*
X1495779Y963583D03*
X1492079D03*
X1488378D03*
X1484677D03*
X1497630Y966772D03*
X1493929D03*
X1490228D03*
X1486527D03*
X1495779Y969961D03*
X1492079D03*
X1488378D03*
X1484677D03*
X1497630Y973150D03*
X1493929D03*
X1490228D03*
X1486527D03*
X1495779Y976339D03*
X1492079D03*
X1488378D03*
X1484677D03*
X1497630Y979528D03*
X1493929D03*
X1490228D03*
X1486527D03*
X1495779Y982717D03*
X1492079D03*
X1488378D03*
X1484677D03*
X1497630Y985906D03*
X1493929D03*
X1490228D03*
X1486527D03*
X1495779Y989095D03*
X1492079D03*
X1488378D03*
X1484677D03*
X1497630Y992284D03*
X1493929D03*
X1490228D03*
X1486527D03*
X1495779Y995473D03*
X1492079D03*
X1488378D03*
X1484677D03*
X1497630Y998662D03*
X1493929D03*
X1490228D03*
X1486527D03*
X1495779Y1001851D03*
X1492079D03*
X1488378D03*
X1484677D03*
X1497630Y1005040D03*
X1493929D03*
X1490228D03*
X1486527D03*
X1495779Y1008229D03*
X1492079D03*
X1488378D03*
X1484677D03*
X1497630Y1011418D03*
X1493929D03*
X1490228D03*
X1486527D03*
X1495110Y1027008D03*
X1491409D03*
X1487709D03*
X1484008D03*
X1496960Y1030197D03*
X1493260D03*
X1489559D03*
X1485858D03*
X1495110Y1033386D03*
X1491409D03*
X1487709D03*
X1484008D03*
X1496960Y1036575D03*
X1493260D03*
X1489559D03*
X1485858D03*
X1495110Y1039764D03*
X1491409D03*
X1487709D03*
X1484008D03*
X1496960Y1042953D03*
X1493260D03*
X1489559D03*
X1485858D03*
X1495110Y1046142D03*
X1491409D03*
X1487709D03*
X1484008D03*
X1496960Y1049331D03*
X1493260D03*
X1489559D03*
X1485858D03*
X1495110Y1052520D03*
X1491409D03*
X1487709D03*
X1484008D03*
X1496960Y1055709D03*
X1493260D03*
X1489559D03*
X1485858D03*
X1495110Y1058898D03*
X1491409D03*
X1487709D03*
X1484008D03*
X1496960Y1062087D03*
X1493260D03*
X1489559D03*
X1485858D03*
X1495110Y1065276D03*
X1491409D03*
X1487709D03*
X1484008D03*
X1496960Y1068465D03*
X1493260D03*
X1489559D03*
X1485858D03*
X1495110Y1071654D03*
X1491409D03*
X1487709D03*
X1484008D03*
X1496960Y1074843D03*
X1493260D03*
X1489559D03*
X1485858D03*
X1495110Y1078032D03*
X1491409D03*
X1487709D03*
X1484008D03*
X1496960Y1081221D03*
X1493260D03*
X1489559D03*
X1485858D03*
X1495110Y1084410D03*
X1491409D03*
X1487709D03*
X1484008D03*
X1496960Y1087599D03*
X1493260D03*
X1489559D03*
X1485858D03*
X1495110Y1090788D03*
X1491409D03*
X1487709D03*
X1484008D03*
X1496960Y1093977D03*
X1493260D03*
X1489559D03*
X1485858D03*
X1495110Y1097166D03*
X1491409D03*
X1487709D03*
X1484008D03*
X1496960Y1100355D03*
X1493260D03*
X1489559D03*
X1485858D03*
X1495110Y1103544D03*
X1491409D03*
X1487709D03*
X1484008D03*
X1496960Y1106733D03*
X1493260D03*
X1489559D03*
X1485858D03*
X1495110Y1109922D03*
X1491409D03*
X1487709D03*
X1484008D03*
X1496960Y1113111D03*
X1493260D03*
X1489559D03*
X1485858D03*
X1495110Y1116300D03*
X1491409D03*
X1487709D03*
X1484008D03*
X1496960Y1119489D03*
X1493260D03*
X1489559D03*
X1485858D03*
X1495110Y1122678D03*
X1491409D03*
X1487709D03*
X1484008D03*
X1496960Y1125867D03*
X1493260D03*
X1489559D03*
X1485858D03*
X1495110Y1129056D03*
X1491409D03*
X1487709D03*
X1484008D03*
X1496960Y1132245D03*
X1493260D03*
X1489559D03*
X1485858D03*
X1495110Y1135433D03*
X1491409D03*
X1487709D03*
X1484008D03*
X1496960Y1138622D03*
X1493260D03*
X1489559D03*
X1485858D03*
X1495110Y1141811D03*
X1491409D03*
X1487709D03*
X1484008D03*
X1496960Y1145000D03*
X1493260D03*
X1489559D03*
X1485858D03*
X1495110Y1148189D03*
X1491409D03*
X1487709D03*
X1484008D03*
X1496960Y1151378D03*
X1493260D03*
X1489559D03*
X1485858D03*
X1495110Y1154567D03*
X1491409D03*
X1487709D03*
X1484008D03*
X1496960Y1157756D03*
X1493260D03*
X1489559D03*
X1485858D03*
X1495110Y1160945D03*
X1491409D03*
X1487709D03*
X1484008D03*
X1496960Y1164134D03*
X1493260D03*
X1485858D03*
X1506882Y874292D03*
X1503181D03*
X1499480D03*
X1512433Y877481D03*
X1508732D03*
X1505031D03*
X1501331D03*
X1510583Y880670D03*
X1506882D03*
X1503181D03*
X1499480D03*
X1512433Y883859D03*
X1508732D03*
X1505031D03*
X1501331D03*
X1510583Y887048D03*
X1506882D03*
X1503181D03*
X1499480D03*
X1512433Y890237D03*
X1508732D03*
X1505031D03*
X1501331D03*
X1510583Y893426D03*
X1506882D03*
X1503181D03*
X1499480D03*
X1512433Y896615D03*
X1508732D03*
X1505031D03*
X1501331D03*
X1510583Y899804D03*
X1506882D03*
X1503181D03*
X1499480D03*
X1512433Y902993D03*
X1508732D03*
X1505031D03*
X1501331D03*
X1510583Y906181D03*
X1506882D03*
X1503181D03*
X1499480D03*
X1512433Y909370D03*
X1508732D03*
X1505031D03*
X1501331D03*
X1510583Y912559D03*
X1506882D03*
X1503181D03*
X1499480D03*
X1512433Y915748D03*
X1508732D03*
X1505031D03*
X1501331D03*
X1510583Y918937D03*
X1506882D03*
X1503181D03*
X1499480D03*
X1512433Y922126D03*
X1508732D03*
X1505031D03*
X1501331D03*
X1510583Y925315D03*
X1506882D03*
X1503181D03*
X1499480D03*
X1512433Y928504D03*
X1508732D03*
X1505031D03*
X1501331D03*
X1510583Y931693D03*
X1506882D03*
X1503181D03*
X1499480D03*
X1512433Y934882D03*
X1508732D03*
X1505031D03*
X1501331D03*
X1510583Y938071D03*
X1506882D03*
X1503181D03*
X1499480D03*
X1512433Y941260D03*
X1508732D03*
X1505031D03*
X1501331D03*
X1510583Y944449D03*
X1506882D03*
X1503181D03*
X1499480D03*
X1512433Y947638D03*
X1508732D03*
X1505031D03*
X1501331D03*
X1510583Y950827D03*
X1506882D03*
X1503181D03*
X1499480D03*
X1512433Y954016D03*
X1508732D03*
X1505031D03*
X1501331D03*
X1510583Y957205D03*
X1506882D03*
X1503181D03*
X1499480D03*
X1512433Y960394D03*
X1508732D03*
X1505031D03*
X1501331D03*
X1510583Y963583D03*
X1506882D03*
X1503181D03*
X1499480D03*
X1512433Y966772D03*
X1508732D03*
X1505031D03*
X1501331D03*
X1510583Y969961D03*
X1506882D03*
X1503181D03*
X1499480D03*
X1512433Y973150D03*
X1508732D03*
X1505031D03*
X1501331D03*
X1510583Y976339D03*
X1506882D03*
X1503181D03*
X1499480D03*
X1512433Y979528D03*
X1508732D03*
X1505031D03*
X1501331D03*
X1510583Y982717D03*
X1506882D03*
X1503181D03*
X1499480D03*
X1512433Y985906D03*
X1508732D03*
X1505031D03*
X1501331D03*
X1510583Y989095D03*
X1506882D03*
X1503181D03*
X1499480D03*
X1512433Y992284D03*
X1508732D03*
X1505031D03*
X1501331D03*
X1510583Y995473D03*
X1506882D03*
X1503181D03*
X1499480D03*
X1512433Y998662D03*
X1508732D03*
X1505031D03*
X1501331D03*
X1510583Y1001851D03*
X1506882D03*
X1503181D03*
X1499480D03*
X1512433Y1005040D03*
X1508732D03*
X1505031D03*
X1501331D03*
X1510583Y1008229D03*
X1506882D03*
X1503181D03*
X1499480D03*
X1512433Y1011418D03*
X1508732D03*
X1505031D03*
X1501331D03*
X1513614Y1027008D03*
X1509913D03*
X1506212D03*
X1502512D03*
X1498811D03*
X1511764Y1030197D03*
X1508063D03*
X1504362D03*
X1500661D03*
X1513614Y1033386D03*
X1509913D03*
X1506212D03*
X1502512D03*
X1498811D03*
X1511764Y1036575D03*
X1508063D03*
X1504362D03*
X1500661D03*
X1513614Y1039764D03*
X1509913D03*
X1506212D03*
X1502512D03*
X1498811D03*
X1511764Y1042953D03*
X1508063D03*
X1504362D03*
X1500661D03*
X1513614Y1046142D03*
X1509913D03*
X1506212D03*
X1502512D03*
X1498811D03*
X1511764Y1049331D03*
X1508063D03*
X1504362D03*
X1500661D03*
X1513614Y1052520D03*
X1509913D03*
X1506212D03*
X1502512D03*
X1498811D03*
X1511764Y1055709D03*
X1508063D03*
X1504362D03*
X1500661D03*
X1513614Y1058898D03*
X1509913D03*
X1506212D03*
X1502512D03*
X1498811D03*
X1511764Y1062087D03*
X1508063D03*
X1504362D03*
X1500661D03*
X1513614Y1065276D03*
X1509913D03*
X1506212D03*
X1502512D03*
X1498811D03*
X1511764Y1068465D03*
X1508063D03*
X1504362D03*
X1500661D03*
X1513614Y1071654D03*
X1509913D03*
X1506212D03*
X1502512D03*
X1498811D03*
X1511764Y1074843D03*
X1508063D03*
X1504362D03*
X1500661D03*
X1513614Y1078032D03*
X1509913D03*
X1506212D03*
X1502512D03*
X1498811D03*
X1511764Y1081221D03*
X1508063D03*
X1504362D03*
X1500661D03*
X1513614Y1084410D03*
X1509913D03*
X1506212D03*
X1502512D03*
X1498811D03*
X1511764Y1087599D03*
X1508063D03*
X1504362D03*
X1500661D03*
X1513614Y1090788D03*
X1509913D03*
X1506212D03*
X1502512D03*
X1498811D03*
X1511764Y1093977D03*
X1508063D03*
X1504362D03*
X1500661D03*
X1513614Y1097166D03*
X1509913D03*
X1506212D03*
X1502512D03*
X1498811D03*
X1511764Y1100355D03*
X1508063D03*
X1504362D03*
X1500661D03*
X1513614Y1103544D03*
X1509913D03*
X1506212D03*
X1502512D03*
X1498811D03*
X1511764Y1106733D03*
X1508063D03*
X1504362D03*
X1500661D03*
X1513614Y1109922D03*
X1509913D03*
X1506212D03*
X1502512D03*
X1498811D03*
X1511764Y1113111D03*
X1508063D03*
X1504362D03*
X1500661D03*
X1513614Y1116300D03*
X1509913D03*
X1506212D03*
X1502512D03*
X1498811D03*
X1511764Y1119489D03*
X1508063D03*
X1504362D03*
X1500661D03*
X1513614Y1122678D03*
X1509913D03*
X1506212D03*
X1502512D03*
X1498811D03*
X1511764Y1125867D03*
X1508063D03*
X1504362D03*
X1500661D03*
X1513614Y1129056D03*
X1509913D03*
X1506212D03*
X1502512D03*
X1498811D03*
X1511764Y1132245D03*
X1508063D03*
X1504362D03*
X1500661D03*
X1513614Y1135433D03*
X1509913D03*
X1506212D03*
X1502512D03*
X1498811D03*
X1511764Y1138622D03*
X1508063D03*
X1504362D03*
X1500661D03*
X1513614Y1141811D03*
X1509913D03*
X1506212D03*
X1502512D03*
X1498811D03*
X1511764Y1145000D03*
X1508063D03*
X1504362D03*
X1500661D03*
X1513614Y1148189D03*
X1509913D03*
X1506212D03*
X1502512D03*
X1498811D03*
X1511764Y1151378D03*
X1508063D03*
X1504362D03*
X1500661D03*
X1513614Y1154567D03*
X1509913D03*
X1506212D03*
X1502512D03*
X1498811D03*
X1511764Y1157756D03*
X1508063D03*
X1504362D03*
X1500661D03*
X1513614Y1160945D03*
X1509913D03*
X1506212D03*
X1502512D03*
X1498811D03*
X1508063Y1164134D03*
X1504362D03*
X1500661D03*
X1525386Y874292D03*
X1521685D03*
X1517984D03*
X1514283D03*
X1527236Y877481D03*
X1523535D03*
X1519835D03*
X1516134D03*
X1525386Y880670D03*
X1521685D03*
X1517984D03*
X1514283D03*
X1527236Y883859D03*
X1523535D03*
X1519835D03*
X1516134D03*
X1525386Y887048D03*
X1521685D03*
X1517984D03*
X1514283D03*
X1527236Y890237D03*
X1523535D03*
X1519835D03*
X1516134D03*
X1525386Y893426D03*
X1521685D03*
X1517984D03*
X1514283D03*
X1527236Y896615D03*
X1523535D03*
X1519835D03*
X1516134D03*
X1525386Y899804D03*
X1521685D03*
X1517984D03*
X1514283D03*
X1527236Y902993D03*
X1523535D03*
X1519835D03*
X1516134D03*
X1525386Y906181D03*
X1521685D03*
X1517984D03*
X1514283D03*
X1527236Y909370D03*
X1523535D03*
X1519835D03*
X1516134D03*
X1525386Y912559D03*
X1521685D03*
X1517984D03*
X1514283D03*
X1527236Y915748D03*
X1523535D03*
X1519835D03*
X1516134D03*
X1525386Y918937D03*
X1521685D03*
X1517984D03*
X1514283D03*
X1527236Y922126D03*
X1523535D03*
X1519835D03*
X1516134D03*
X1525386Y925315D03*
X1521685D03*
X1517984D03*
X1514283D03*
X1527236Y928504D03*
X1523535D03*
X1519835D03*
X1516134D03*
X1525386Y931693D03*
X1521685D03*
X1517984D03*
X1514283D03*
X1527236Y934882D03*
X1523535D03*
X1519835D03*
X1516134D03*
X1525386Y938071D03*
X1521685D03*
X1517984D03*
X1514283D03*
X1527236Y941260D03*
X1523535D03*
X1519835D03*
X1516134D03*
X1525386Y944449D03*
X1521685D03*
X1517984D03*
X1514283D03*
X1527236Y947638D03*
X1523535D03*
X1519835D03*
X1516134D03*
X1525386Y950827D03*
X1521685D03*
X1517984D03*
X1514283D03*
X1527236Y954016D03*
X1523535D03*
X1519835D03*
X1516134D03*
X1525386Y957205D03*
X1521685D03*
X1517984D03*
X1514283D03*
X1527236Y960394D03*
X1523535D03*
X1519835D03*
X1516134D03*
X1525386Y963583D03*
X1521685D03*
X1517984D03*
X1514283D03*
X1527236Y966772D03*
X1523535D03*
X1519835D03*
X1516134D03*
X1525386Y969961D03*
X1521685D03*
X1517984D03*
X1514283D03*
X1527236Y973150D03*
X1523535D03*
X1519835D03*
X1516134D03*
X1525386Y976339D03*
X1521685D03*
X1517984D03*
X1514283D03*
X1527236Y979528D03*
X1523535D03*
X1519835D03*
X1516134D03*
X1525386Y982717D03*
X1521685D03*
X1517984D03*
X1514283D03*
X1527236Y985906D03*
X1523535D03*
X1519835D03*
X1516134D03*
X1525386Y989095D03*
X1521685D03*
X1517984D03*
X1514283D03*
X1527236Y992284D03*
X1523535D03*
X1519835D03*
X1516134D03*
X1525386Y995473D03*
X1521685D03*
X1517984D03*
X1514283D03*
X1527236Y998662D03*
X1523535D03*
X1519835D03*
X1516134D03*
X1525386Y1001851D03*
X1521685D03*
X1517984D03*
X1514283D03*
X1527236Y1005040D03*
X1523535D03*
X1519835D03*
X1516134D03*
X1525386Y1008229D03*
X1521685D03*
X1517984D03*
X1514283D03*
X1527236Y1011418D03*
X1523535D03*
X1519835D03*
X1516134D03*
X1528417Y1027008D03*
X1524716D03*
X1521016D03*
X1517315D03*
X1526567Y1030197D03*
X1522866D03*
X1519165D03*
X1515464D03*
X1528417Y1033386D03*
X1524716D03*
X1521016D03*
X1517315D03*
X1526567Y1036575D03*
X1522866D03*
X1519165D03*
X1515464D03*
X1528417Y1039764D03*
X1524716D03*
X1521016D03*
X1517315D03*
X1526567Y1042953D03*
X1522866D03*
X1519165D03*
X1515464D03*
X1528417Y1046142D03*
X1524716D03*
X1521016D03*
X1517315D03*
X1526567Y1049331D03*
X1522866D03*
X1519165D03*
X1515464D03*
X1528417Y1052520D03*
X1524716D03*
X1521016D03*
X1517315D03*
X1526567Y1055709D03*
X1522866D03*
X1519165D03*
X1515464D03*
X1528417Y1058898D03*
X1524716D03*
X1521016D03*
X1517315D03*
X1526567Y1062087D03*
X1522866D03*
X1519165D03*
X1515464D03*
X1528417Y1065276D03*
X1524716D03*
X1521016D03*
X1517315D03*
X1526567Y1068465D03*
X1522866D03*
X1519165D03*
X1515464D03*
X1528417Y1071654D03*
X1524716D03*
X1521016D03*
X1517315D03*
X1526567Y1074843D03*
X1522866D03*
X1519165D03*
X1515464D03*
X1528417Y1078032D03*
X1524716D03*
X1521016D03*
X1517315D03*
X1526567Y1081221D03*
X1522866D03*
X1519165D03*
X1515464D03*
X1528417Y1084410D03*
X1524716D03*
X1521016D03*
X1517315D03*
X1526567Y1087599D03*
X1522866D03*
X1519165D03*
X1515464D03*
X1528417Y1090788D03*
X1524716D03*
X1521016D03*
X1517315D03*
X1526567Y1093977D03*
X1522866D03*
X1519165D03*
X1515464D03*
X1528417Y1097166D03*
X1524716D03*
X1521016D03*
X1517315D03*
X1526567Y1100355D03*
X1522866D03*
X1519165D03*
X1515464D03*
X1528417Y1103544D03*
X1524716D03*
X1521016D03*
X1517315D03*
X1526567Y1106733D03*
X1522866D03*
X1519165D03*
X1515464D03*
X1528417Y1109922D03*
X1524716D03*
X1521016D03*
X1517315D03*
X1526567Y1113111D03*
X1522866D03*
X1519165D03*
X1515464D03*
X1528417Y1116300D03*
X1524716D03*
X1521016D03*
X1517315D03*
X1526567Y1119489D03*
X1522866D03*
X1519165D03*
X1515464D03*
X1528417Y1122678D03*
X1524716D03*
X1521016D03*
X1517315D03*
X1526567Y1125867D03*
X1522866D03*
X1519165D03*
X1515464D03*
X1528417Y1129056D03*
X1524716D03*
X1521016D03*
X1517315D03*
X1526567Y1132245D03*
X1522866D03*
X1519165D03*
X1515464D03*
X1528417Y1135433D03*
X1524716D03*
X1521016D03*
X1517315D03*
X1526567Y1138622D03*
X1522866D03*
X1519165D03*
X1515464D03*
X1528417Y1141811D03*
X1524716D03*
X1521016D03*
X1517315D03*
X1526567Y1145000D03*
X1522866D03*
X1519165D03*
X1515464D03*
X1528417Y1148189D03*
X1524716D03*
X1521016D03*
X1517315D03*
X1526567Y1151378D03*
X1522866D03*
X1519165D03*
X1515464D03*
X1528417Y1154567D03*
X1524716D03*
X1521016D03*
X1517315D03*
X1526567Y1157756D03*
X1522866D03*
X1519165D03*
X1515464D03*
X1528417Y1160945D03*
X1524716D03*
X1521016D03*
X1517315D03*
X1526567Y1164134D03*
X1522866D03*
X1519165D03*
X1515464D03*
X1540189Y874292D03*
X1536488D03*
X1529086D03*
X1542039Y877481D03*
X1538338D03*
X1534638D03*
X1530937D03*
X1540189Y880670D03*
X1536488D03*
X1532787D03*
X1529086D03*
X1542039Y883859D03*
X1538338D03*
X1534638D03*
X1530937D03*
X1540189Y887048D03*
X1536488D03*
X1532787D03*
X1529086D03*
X1542039Y890237D03*
X1538338D03*
X1534638D03*
X1530937D03*
X1540189Y893426D03*
X1536488D03*
X1532787D03*
X1529086D03*
X1542039Y896615D03*
X1538338D03*
X1534638D03*
X1530937D03*
X1540189Y899804D03*
X1536488D03*
X1532787D03*
X1529086D03*
X1542039Y902993D03*
X1538338D03*
X1534638D03*
X1530937D03*
X1540189Y906181D03*
X1536488D03*
X1532787D03*
X1529086D03*
X1542039Y909370D03*
X1538338D03*
X1534638D03*
X1530937D03*
X1540189Y912559D03*
X1536488D03*
X1532787D03*
X1529086D03*
X1542039Y915748D03*
X1538338D03*
X1534638D03*
X1530937D03*
X1540189Y918937D03*
X1536488D03*
X1532787D03*
X1529086D03*
X1542039Y922126D03*
X1538338D03*
X1534638D03*
X1530937D03*
X1540189Y925315D03*
X1536488D03*
X1532787D03*
X1529086D03*
X1542039Y928504D03*
X1538338D03*
X1534638D03*
X1530937D03*
X1540189Y931693D03*
X1536488D03*
X1532787D03*
X1529086D03*
X1542039Y934882D03*
X1538338D03*
X1534638D03*
X1530937D03*
X1540189Y938071D03*
X1536488D03*
X1532787D03*
X1529086D03*
X1542039Y941260D03*
X1538338D03*
X1534638D03*
X1530937D03*
X1540189Y944449D03*
X1536488D03*
X1532787D03*
X1529086D03*
X1542039Y947638D03*
X1538338D03*
X1534638D03*
X1530937D03*
X1540189Y950827D03*
X1536488D03*
X1532787D03*
X1529086D03*
X1542039Y954016D03*
X1538338D03*
X1534638D03*
X1530937D03*
X1540189Y957205D03*
X1536488D03*
X1532787D03*
X1529086D03*
X1542039Y960394D03*
X1538338D03*
X1534638D03*
X1530937D03*
X1540189Y963583D03*
X1536488D03*
X1532787D03*
X1529086D03*
X1542039Y966772D03*
X1538338D03*
X1534638D03*
X1530937D03*
X1540189Y969961D03*
X1536488D03*
X1532787D03*
X1529086D03*
X1542039Y973150D03*
X1538338D03*
X1534638D03*
X1530937D03*
X1540189Y976339D03*
X1536488D03*
X1532787D03*
X1529086D03*
X1542039Y979528D03*
X1538338D03*
X1534638D03*
X1530937D03*
X1540189Y982717D03*
X1536488D03*
X1532787D03*
X1529086D03*
X1542039Y985906D03*
X1538338D03*
X1534638D03*
X1530937D03*
X1540189Y989095D03*
X1536488D03*
X1532787D03*
X1529086D03*
X1542039Y992284D03*
X1538338D03*
X1534638D03*
X1530937D03*
X1540189Y995473D03*
X1536488D03*
X1532787D03*
X1529086D03*
X1542039Y998662D03*
X1538338D03*
X1534638D03*
X1530937D03*
X1540189Y1001851D03*
X1536488D03*
X1532787D03*
X1529086D03*
X1542039Y1005040D03*
X1538338D03*
X1534638D03*
X1530937D03*
X1540189Y1008229D03*
X1536488D03*
X1532787D03*
X1529086D03*
X1542039Y1011418D03*
X1538338D03*
X1534638D03*
X1530937D03*
X1543220Y1027008D03*
X1539520D03*
X1535819D03*
X1532118D03*
X1541370Y1030197D03*
X1537669D03*
X1533968D03*
X1530268D03*
X1543220Y1033386D03*
X1539520D03*
X1535819D03*
X1532118D03*
X1541370Y1036575D03*
X1537669D03*
X1533968D03*
X1530268D03*
X1543220Y1039764D03*
X1539520D03*
X1535819D03*
X1532118D03*
X1541370Y1042953D03*
X1537669D03*
X1533968D03*
X1530268D03*
X1543220Y1046142D03*
X1539520D03*
X1535819D03*
X1532118D03*
X1541370Y1049331D03*
X1537669D03*
X1533968D03*
X1530268D03*
X1543220Y1052520D03*
X1539520D03*
X1535819D03*
X1532118D03*
X1541370Y1055709D03*
X1537669D03*
X1533968D03*
X1530268D03*
X1543220Y1058898D03*
X1539520D03*
X1535819D03*
X1532118D03*
X1541370Y1062087D03*
X1537669D03*
X1533968D03*
X1530268D03*
X1543220Y1065276D03*
X1539520D03*
X1535819D03*
X1532118D03*
X1541370Y1068465D03*
X1537669D03*
X1533968D03*
X1530268D03*
X1543220Y1071654D03*
X1539520D03*
X1535819D03*
X1532118D03*
X1541370Y1074843D03*
X1537669D03*
X1533968D03*
X1530268D03*
X1543220Y1078032D03*
X1539520D03*
X1535819D03*
X1532118D03*
X1541370Y1081221D03*
X1537669D03*
X1533968D03*
X1530268D03*
X1543220Y1084410D03*
X1539520D03*
X1535819D03*
X1532118D03*
X1541370Y1087599D03*
X1537669D03*
X1533968D03*
X1530268D03*
X1543220Y1090788D03*
X1539520D03*
X1535819D03*
X1532118D03*
X1541370Y1093977D03*
X1537669D03*
X1533968D03*
X1530268D03*
X1543220Y1097166D03*
X1539520D03*
X1535819D03*
X1532118D03*
X1541370Y1100355D03*
X1537669D03*
X1533968D03*
X1530268D03*
X1543220Y1103544D03*
X1539520D03*
X1535819D03*
X1532118D03*
X1541370Y1106733D03*
X1537669D03*
X1533968D03*
X1530268D03*
X1543220Y1109922D03*
X1539520D03*
X1535819D03*
X1532118D03*
X1541370Y1113111D03*
X1537669D03*
X1533968D03*
X1530268D03*
X1543220Y1116300D03*
X1539520D03*
X1535819D03*
X1532118D03*
X1541370Y1119489D03*
X1537669D03*
X1533968D03*
X1530268D03*
X1543220Y1122678D03*
X1539520D03*
X1535819D03*
X1532118D03*
X1541370Y1125867D03*
X1537669D03*
X1533968D03*
X1530268D03*
X1543220Y1129056D03*
X1539520D03*
X1535819D03*
X1532118D03*
X1541370Y1132245D03*
X1537669D03*
X1533968D03*
X1530268D03*
X1543220Y1135433D03*
X1539520D03*
X1535819D03*
X1532118D03*
X1541370Y1138622D03*
X1537669D03*
X1533968D03*
X1530268D03*
X1543220Y1141811D03*
X1539520D03*
X1535819D03*
X1532118D03*
X1541370Y1145000D03*
X1537669D03*
X1533968D03*
X1530268D03*
X1543220Y1148189D03*
X1539520D03*
X1535819D03*
X1532118D03*
X1541370Y1151378D03*
X1537669D03*
X1533968D03*
X1530268D03*
X1543220Y1154567D03*
X1539520D03*
X1535819D03*
X1532118D03*
X1541370Y1157756D03*
X1537669D03*
X1533968D03*
X1530268D03*
X1543220Y1160945D03*
X1539520D03*
X1535819D03*
X1532118D03*
X1541370Y1164134D03*
X1537669D03*
X1530268D03*
X1543890Y874292D03*
X1545740Y877481D03*
X1551291Y880670D03*
X1547590D03*
X1543890D03*
X1549441Y883859D03*
X1545740D03*
X1551291Y887048D03*
X1547590D03*
X1543890D03*
X1549441Y890237D03*
X1545740D03*
X1551291Y893426D03*
X1547590D03*
X1543890D03*
X1549441Y896615D03*
X1545740D03*
X1551291Y899804D03*
X1547590D03*
X1543890D03*
X1549441Y902993D03*
X1545740D03*
X1551291Y906181D03*
X1547590D03*
X1543890D03*
X1549441Y909370D03*
X1545740D03*
X1551291Y912559D03*
X1547590D03*
X1543890D03*
X1549441Y915748D03*
X1545740D03*
X1551291Y918937D03*
X1547590D03*
X1543890D03*
X1549441Y922126D03*
X1545740D03*
X1551291Y925315D03*
X1547590D03*
X1543890D03*
X1549441Y928504D03*
X1545740D03*
X1551291Y931693D03*
X1547590D03*
X1543890D03*
X1549441Y934882D03*
X1545740D03*
X1551291Y938071D03*
X1547590D03*
X1543890D03*
X1549441Y941260D03*
X1545740D03*
X1551291Y944449D03*
X1547590D03*
X1543890D03*
X1549441Y947638D03*
X1545740D03*
X1551291Y950827D03*
X1547590D03*
X1543890D03*
X1549441Y954016D03*
X1545740D03*
X1551291Y957205D03*
X1547590D03*
X1543890D03*
X1549441Y960394D03*
X1545740D03*
X1551291Y963583D03*
X1547590D03*
X1543890D03*
X1549441Y966772D03*
X1545740D03*
X1551291Y969961D03*
X1547590D03*
X1543890D03*
X1549441Y973150D03*
X1545740D03*
X1551291Y976339D03*
X1547590D03*
X1543890D03*
X1549441Y979528D03*
X1545740D03*
X1551291Y982717D03*
X1547590D03*
X1543890D03*
X1549441Y985906D03*
X1545740D03*
X1551291Y989095D03*
X1547590D03*
X1543890D03*
X1549441Y992284D03*
X1545740D03*
X1551291Y995473D03*
X1547590D03*
X1543890D03*
X1549441Y998662D03*
X1545740D03*
X1551291Y1001851D03*
X1547590D03*
X1543890D03*
X1549441Y1005040D03*
X1545740D03*
X1551291Y1008229D03*
X1547590D03*
X1543890D03*
X1549441Y1011418D03*
X1545740D03*
X1550622Y1027008D03*
X1546921D03*
X1552472Y1030197D03*
X1548771D03*
X1545071D03*
X1550622Y1033386D03*
X1546921D03*
X1552472Y1036575D03*
X1548771D03*
X1545071D03*
X1550622Y1039764D03*
X1546921D03*
X1552472Y1042953D03*
X1548771D03*
X1545071D03*
X1550622Y1046142D03*
X1546921D03*
X1552472Y1049331D03*
X1548771D03*
X1545071D03*
X1550622Y1052520D03*
X1546921D03*
X1552472Y1055709D03*
X1548771D03*
X1545071D03*
X1550622Y1058898D03*
X1546921D03*
X1552472Y1062087D03*
X1548771D03*
X1545071D03*
X1550622Y1065276D03*
X1546921D03*
X1552472Y1068465D03*
X1548771D03*
X1545071D03*
X1550622Y1071654D03*
X1546921D03*
X1552472Y1074843D03*
X1548771D03*
X1545071D03*
X1550622Y1078032D03*
X1546921D03*
X1552472Y1081221D03*
X1548771D03*
X1545071D03*
X1550622Y1084410D03*
X1546921D03*
X1552472Y1087599D03*
X1548771D03*
X1545071D03*
X1550622Y1090788D03*
X1546921D03*
X1552472Y1093977D03*
X1548771D03*
X1545071D03*
X1550622Y1097166D03*
X1546921D03*
X1552472Y1100355D03*
X1548771D03*
X1545071D03*
X1550622Y1103544D03*
X1546921D03*
X1552472Y1106733D03*
X1548771D03*
X1545071D03*
X1550622Y1109922D03*
X1546921D03*
X1552472Y1113111D03*
X1548771D03*
X1545071D03*
X1550622Y1116300D03*
X1546921D03*
X1552472Y1119489D03*
X1548771D03*
X1545071D03*
X1550622Y1122678D03*
X1546921D03*
X1552472Y1125867D03*
X1548771D03*
X1545071D03*
X1550622Y1129056D03*
X1546921D03*
X1552472Y1132245D03*
X1548771D03*
X1545071D03*
X1550622Y1135433D03*
X1546921D03*
X1552472Y1138622D03*
X1548771D03*
X1545071D03*
X1550622Y1141811D03*
X1546921D03*
X1552472Y1145000D03*
X1548771D03*
X1545071D03*
X1550622Y1148189D03*
X1546921D03*
X1552472Y1151378D03*
X1548771D03*
X1545071D03*
X1550622Y1154567D03*
X1546921D03*
X1552472Y1157756D03*
X1548771D03*
X1545071D03*
X1546921Y1160945D03*
X1545071Y1164134D03*
G54D71*
X99729Y289822D03*
Y310256D03*
X757184Y1722772D03*
X1072863Y1429176D03*
X1080970Y1660958D03*
X1299439Y92812D03*
X1550377Y581353D03*
G54D290*
X1024961Y543499D03*
Y545074D03*
Y546649D03*
Y548224D03*
Y549799D03*
X1030079D03*
Y548224D03*
Y546649D03*
Y545074D03*
Y543499D03*
G54D155*
X326731Y663237D03*
X363731D03*
X443467Y594259D03*
X754645Y1436735D03*
X1077638Y133866D03*
X1166535Y1422322D03*
X1291146Y1385558D03*
X1320516D03*
X1425533Y601230D03*
X1487677Y649988D03*
X1524437Y650208D03*
X1701285Y208455D03*
X1700840Y1434362D03*
X1731660Y208455D03*
X1770442Y294777D03*
X1800002D03*
G54D119*
X215312Y1577778D03*
X240508D03*
X252717Y1577830D03*
X277913D03*
X516830D03*
X542026D03*
X1222952Y1610648D03*
X1248148D03*
X1260530Y1610830D03*
X1285726D03*
X1524704D03*
X1549900D03*
G54D272*
X922441Y154311D03*
Y243799D03*
G54D218*
X628988Y1415094D03*
X637447Y1421755D03*
X1307050Y546690D03*
G54D182*
X481161Y214077D03*
X579478Y227071D03*
G54D345*
G01X55756Y1534564D02*
X53017D01*
X51699Y1533246D01*
X50631D01*
G01X55756Y1536335D02*
X52802D01*
X52041Y1537096D01*
X50631D01*
G01X41208Y1622896D02*
X42333D01*
X43633Y1621596D01*
G01X52196Y1528369D02*
X53596Y1529769D01*
Y1532141D01*
X54247Y1532792D01*
X55756D01*
G01X68768Y1547221D02*
X68000Y1546453D01*
Y1542339D01*
G01X72768Y1547221D02*
X69772Y1544725D01*
Y1542339D01*
G01X91499Y1532792D02*
X89990D01*
X88245Y1531047D01*
G01X86374Y1540746D02*
X87150D01*
X89789Y1538107D01*
X91499D01*
G01X86271Y1544869D02*
X87696D01*
X89096Y1543469D01*
Y1541269D01*
X90486Y1539879D01*
X91499D01*
G01X103152Y1374001D02*
Y1375130D01*
X101874Y1376408D01*
G01X104511Y1546921D02*
X103743Y1546153D01*
Y1542339D01*
G01X108511Y1546921D02*
X105515Y1544425D01*
Y1542339D01*
G01X115590Y1381783D02*
X115396Y1381589D01*
Y1376461D01*
G01X119632Y1384933D02*
X115590D01*
G01X119632Y1381783D02*
X117168Y1379319D01*
Y1376461D01*
G01X135752Y1374001D02*
Y1375130D01*
X134474Y1376408D01*
G01X148190Y1381783D02*
X147996Y1381589D01*
Y1376461D01*
G01X152232Y1384933D02*
X148190D01*
G01X152232Y1381783D02*
X149768Y1379319D01*
Y1376461D01*
G01X168452Y1374001D02*
Y1375130D01*
X167174Y1376408D01*
G01X180890Y1381783D02*
X180696Y1381589D01*
Y1376461D01*
G01X184932Y1384933D02*
X180890D01*
G01X184932Y1381783D02*
X182468Y1379319D01*
Y1376461D01*
G01X201352Y1374001D02*
Y1375130D01*
X200074Y1376408D01*
G01X213790Y1381783D02*
X213596Y1381589D01*
Y1376461D01*
G01X217832Y1384933D02*
X213790D01*
G01X217832Y1381783D02*
X215368Y1379319D01*
Y1376461D01*
G01X206764Y1509459D02*
Y1507683D01*
X207152Y1507295D01*
G01X202039Y1509459D02*
Y1507683D01*
X202427Y1507295D01*
G01X206764Y1509459D02*
Y1510324D01*
X207945Y1511505D01*
G01X202039Y1509459D02*
Y1510323D01*
X203221Y1511505D01*
G01X234152Y1374001D02*
Y1375130D01*
X232874Y1376408D01*
G01X255466Y648334D02*
X255660Y648528D01*
Y653656D01*
G01X251424Y645184D02*
X255466D01*
G01X253888Y653656D02*
Y650798D01*
X251424Y648334D01*
G01X246590Y1381783D02*
X246396Y1381589D01*
Y1376461D01*
G01X250632Y1384933D02*
X246590D01*
G01X250632Y1381783D02*
X248168Y1379319D01*
Y1376461D01*
G01X267904Y656116D02*
X268101Y655919D01*
Y654790D01*
X269182Y653709D01*
G01X267752Y1327855D02*
Y1328984D01*
X266474Y1330262D01*
G01X276801Y581653D02*
X276826Y581678D01*
Y585178D01*
G01X288196Y682575D02*
X288390Y682769D01*
Y687897D01*
G01X284154Y679425D02*
X288196D01*
G01X286618Y687897D02*
Y685039D01*
X284154Y682575D01*
G01X280190Y1335637D02*
X279996Y1335443D01*
Y1330315D01*
G01X284232Y1338787D02*
X280190D01*
G01X284232Y1335637D02*
X281768Y1333173D01*
Y1330315D01*
G01X300634Y690357D02*
X300831Y690160D01*
Y689031D01*
X301912Y687950D01*
G01X300648Y1327827D02*
Y1328956D01*
X299370Y1330234D01*
G01X316924Y699575D02*
X320966D01*
G01X319388Y708047D02*
Y705189D01*
X316924Y702725D01*
G01X313086Y1335609D02*
X312892Y1335415D01*
Y1330287D01*
G01X317128Y1338759D02*
X313086D01*
G01X317128Y1335609D02*
X314664Y1333145D01*
Y1330287D01*
G01X334682Y708100D02*
X333404Y709378D01*
Y710507D01*
G01X320966Y702725D02*
X321160Y702919D01*
Y708047D01*
G01X333552Y1327770D02*
Y1328899D01*
X332274Y1330177D01*
G01X330101Y1509459D02*
Y1507683D01*
X330489Y1507295D01*
G01X334826Y1509459D02*
Y1507683D01*
X335214Y1507295D01*
G01X334826Y1509459D02*
Y1510324D01*
X336007Y1511505D01*
G01X330101Y1509459D02*
Y1510323D01*
X331283Y1511505D01*
G01X349984Y699307D02*
X354026D01*
G01X352448Y707779D02*
Y704921D01*
X349984Y702457D01*
G01X345990Y1335552D02*
X345796Y1335358D01*
Y1330230D01*
G01X350032Y1338702D02*
X345990D01*
G01X350032Y1335552D02*
X347568Y1333088D01*
Y1330230D01*
G01X354026Y702457D02*
Y704281D01*
X354220Y704475D01*
Y707779D01*
G01X365074Y1330377D02*
X366352Y1329099D01*
Y1327970D01*
G01X366464Y710239D02*
X366661Y710042D01*
Y708913D01*
X367742Y707832D01*
G01X378790Y1335752D02*
X378596Y1335558D01*
Y1330430D01*
G01X382832Y1338902D02*
X378790D01*
G01X383024Y699375D02*
X387066D01*
G01Y702525D02*
X387260Y702719D01*
Y707847D01*
G01X385488D02*
Y704989D01*
X383024Y702525D01*
G01X382832Y1335752D02*
X380368Y1333288D01*
Y1330430D01*
G01X400782Y707900D02*
X399504Y709178D01*
Y710307D01*
G01X398934Y1347301D02*
Y1348430D01*
X397656Y1349708D01*
G01X422031Y690047D02*
Y685698D01*
G01X420066Y684725D02*
X420260Y684919D01*
Y690047D01*
G01X420066Y681575D02*
X416024D01*
G01X418488Y690047D02*
Y687189D01*
X416024Y684725D01*
G01X411372Y1355083D02*
X411178Y1354889D01*
Y1349761D01*
G01X415414Y1355083D02*
X412950Y1352619D01*
Y1349761D01*
G01X411372Y1358233D02*
X415414D01*
G01X433782Y690100D02*
X432504Y691378D01*
Y692507D01*
G01X452466Y656975D02*
X448424D01*
G01X452466Y660125D02*
X452660Y660319D01*
Y665447D01*
G01X450888D02*
Y662589D01*
X448424Y660125D01*
G01X466182Y665500D02*
X464904Y666778D01*
Y667907D01*
G01X466212Y1509459D02*
Y1507683D01*
X466600Y1507295D01*
G01X466212Y1509459D02*
Y1510323D01*
X467394Y1511505D01*
G01X485066Y630475D02*
X481024D01*
G01X483488Y638947D02*
Y636089D01*
X481024Y633625D01*
G01X470937Y1509459D02*
Y1507683D01*
X471325Y1507295D01*
G01X470937Y1509459D02*
Y1510324D01*
X472118Y1511505D01*
G01X498782Y639000D02*
X497504Y640278D01*
Y641407D01*
G01X485066Y633625D02*
X485260Y633819D01*
Y638947D01*
G01X514324Y596375D02*
X518366D01*
G01Y599525D02*
X518560Y599719D01*
Y604847D01*
G01X516788D02*
Y601989D01*
X514324Y599525D01*
G01X530804Y607307D02*
Y606178D01*
X532082Y604900D01*
G01X598999Y1509459D02*
Y1507683D01*
X599387Y1507295D01*
G01X594274Y1509459D02*
Y1507683D01*
X594662Y1507295D01*
G01X598999Y1509459D02*
Y1510324D01*
X600180Y1511505D01*
G01X594274Y1509459D02*
Y1510323D01*
X595456Y1511505D01*
G01X709430Y1394417D02*
X710708Y1393139D01*
Y1392010D01*
G01X723146Y1399602D02*
X722952Y1399408D01*
Y1394470D01*
G01X713096Y1583509D02*
X715716D01*
X715978Y1583247D01*
X716697D01*
G01X727188Y1399602D02*
X724724Y1397138D01*
Y1394470D01*
G01X742212Y1394517D02*
X743490Y1393239D01*
Y1392110D01*
G01X755928Y1399702D02*
X755734Y1399508D01*
Y1394570D01*
G01X757506D02*
Y1397238D01*
X759970Y1399702D01*
G01X801614Y1339062D02*
X801089Y1339587D01*
G01X947305Y1150769D02*
X947830Y1150244D01*
G01X1073612Y1376389D02*
X1074890Y1375111D01*
Y1373982D01*
G01X1087328Y1381764D02*
X1087134Y1381570D01*
Y1376442D01*
G01X1091370Y1384914D02*
X1087328D01*
G01X1091370Y1381764D02*
X1088906Y1379300D01*
Y1376442D01*
G01X1106212Y1376389D02*
X1107490Y1375111D01*
Y1373982D01*
G01X1119928Y1381764D02*
X1119734Y1381570D01*
Y1376442D01*
G01X1123970Y1384914D02*
X1119928D01*
G01X1123970Y1381764D02*
X1121506Y1379300D01*
Y1376442D01*
G01X1138912Y1376389D02*
X1140190Y1375111D01*
Y1373982D01*
G01X1152628Y1381764D02*
X1152434Y1381570D01*
Y1376442D01*
G01X1156670Y1384914D02*
X1152628D01*
G01X1156670Y1381764D02*
X1154206Y1379300D01*
Y1376442D01*
G01X1171812Y1376389D02*
X1173090Y1375111D01*
Y1373982D01*
G01X1185528Y1381764D02*
X1185334Y1381570D01*
Y1376442D01*
G01X1189570Y1384914D02*
X1185528D01*
G01X1189570Y1381764D02*
X1187106Y1379300D01*
Y1376442D01*
G01X1205890Y1373982D02*
Y1375111D01*
X1204612Y1376389D01*
G01X1214637Y1542459D02*
Y1540683D01*
X1215025Y1540295D01*
G01X1214637Y1542459D02*
Y1543324D01*
X1215818Y1544505D01*
G01X1209912Y1542459D02*
Y1540683D01*
X1210300Y1540295D01*
G01X1209912Y1542459D02*
Y1543323D01*
X1211094Y1544505D01*
G01X1218328Y1381764D02*
X1218134Y1381570D01*
Y1376442D01*
G01X1222370Y1384914D02*
X1218328D01*
G01X1222370Y1381764D02*
X1219906Y1379300D01*
Y1376442D01*
G01X1243881Y1327836D02*
Y1328965D01*
X1242603Y1330243D01*
G01X1256319Y1335618D02*
X1256125Y1335424D01*
Y1330296D01*
G01X1260361Y1338768D02*
X1256319D01*
G01X1260361Y1335618D02*
X1257897Y1333154D01*
Y1330296D01*
G01X1276777Y1327808D02*
Y1328937D01*
X1275499Y1330215D01*
G01X1289215Y1335590D02*
X1289021Y1335396D01*
Y1330268D01*
G01X1293257Y1338740D02*
X1289215D01*
G01X1307366Y552788D02*
X1307341Y552813D01*
X1303841D01*
G01X1293257Y1335590D02*
X1290793Y1333126D01*
Y1330268D01*
G01X1309681Y1327751D02*
Y1328880D01*
X1308403Y1330158D01*
G01X1322119Y1335533D02*
X1321925Y1335339D01*
Y1330211D01*
G01X1326161Y1338683D02*
X1322119D01*
G01X1326161Y1335533D02*
X1323697Y1333069D01*
Y1330211D01*
G01X1342481Y1327951D02*
Y1329080D01*
X1341203Y1330358D01*
G01X1342699Y1542459D02*
Y1540683D01*
X1343087Y1540295D01*
G01X1342699Y1542459D02*
Y1543324D01*
X1343880Y1544505D01*
G01X1337974Y1542459D02*
Y1540683D01*
X1338362Y1540295D01*
G01X1337974Y1542459D02*
Y1543323D01*
X1339156Y1544505D01*
G01X1366018Y614518D02*
X1361976D01*
G01Y617668D02*
X1364440Y620132D01*
Y622990D01*
G01X1354919Y1335733D02*
X1354725Y1335539D01*
Y1330411D01*
G01X1358961Y1338883D02*
X1354919D01*
G01X1358961Y1335733D02*
X1356497Y1333269D01*
Y1330411D01*
G01X1378456Y625450D02*
Y624321D01*
X1379734Y623043D01*
G01X1366018Y617668D02*
Y618928D01*
X1366212Y619122D01*
Y622990D01*
G01X1375063Y1347282D02*
Y1348411D01*
X1373785Y1349689D01*
G01X1387501Y1355064D02*
X1387307Y1354870D01*
Y1349742D01*
G01X1387501Y1358214D02*
X1391543D01*
G01Y1355064D02*
X1389079Y1352600D01*
Y1349742D01*
G01X1398718Y650568D02*
X1398912Y650762D01*
Y655890D01*
G01X1398718Y647418D02*
X1394676D01*
G01X1397140Y655890D02*
Y653032D01*
X1394676Y650568D01*
G01X1411156Y658350D02*
X1411353Y658153D01*
Y657024D01*
X1412434Y655943D01*
G01X1431318Y683148D02*
X1431512Y683342D01*
Y688470D01*
G01X1427276Y679998D02*
X1431318D01*
G01X1429740Y688470D02*
Y685612D01*
X1427276Y683148D01*
G01X1443756Y690930D02*
X1443953Y690733D01*
Y689604D01*
X1445034Y688523D01*
G01X1460194Y699575D02*
X1464236D01*
G01Y702725D02*
X1464430Y702919D01*
Y708047D01*
G01X1462658D02*
Y705189D01*
X1460194Y702725D01*
G01X1476674Y710507D02*
X1476871Y710310D01*
Y709181D01*
X1477952Y708100D01*
G01X1478811Y1542459D02*
Y1540683D01*
X1479199Y1540295D01*
G01X1478811Y1542459D02*
Y1543324D01*
X1479992Y1544505D01*
G01X1474086Y1542459D02*
Y1540683D01*
X1474474Y1540295D01*
G01X1474086Y1542459D02*
Y1543323D01*
X1475268Y1544505D01*
G01X1493276Y699575D02*
X1497318D01*
G01X1497512Y708215D02*
Y702919D01*
X1497318Y702725D01*
G01X1495740Y708215D02*
Y705189D01*
X1493276Y702725D01*
G01X1511034Y708100D02*
X1509953Y709181D01*
Y710478D01*
X1509756Y710675D01*
G01X1526076Y699575D02*
X1530118D01*
G01X1528540Y708047D02*
Y705189D01*
X1526076Y702725D01*
G01X1542556Y710507D02*
X1542753Y710310D01*
Y709181D01*
X1543834Y708100D01*
G01X1530118Y702725D02*
X1530312Y702919D01*
Y708047D01*
G01X1563248Y680785D02*
Y682559D01*
X1563442Y682753D01*
Y686107D01*
G01X1559206Y677635D02*
X1563248D01*
G01X1561670Y686107D02*
Y683249D01*
X1559206Y680785D01*
G01X1576964Y686160D02*
X1575686Y687438D01*
Y688567D01*
G01X1596018Y647016D02*
X1596212Y647210D01*
Y652338D01*
G01X1591976Y643866D02*
X1596018D01*
G01X1594440Y652338D02*
Y649480D01*
X1591976Y647016D01*
G01X1602148Y1542459D02*
Y1540683D01*
X1602536Y1540295D01*
G01X1602148Y1542459D02*
Y1543323D01*
X1603330Y1544505D01*
G01X1619798Y557414D02*
X1619399D01*
X1615349Y559092D01*
X1613586D01*
G01X1618673Y555839D02*
X1616723D01*
X1616198Y556364D01*
G01X1606873Y1542459D02*
Y1540683D01*
X1607261Y1540295D01*
G01X1606873Y1542459D02*
Y1543324D01*
X1608054Y1544505D01*
G01X1624976Y624866D02*
X1629018D01*
G01Y628016D02*
X1629212Y628210D01*
Y633338D01*
G01X1627440D02*
Y630480D01*
X1624976Y628016D01*
G01X1641456Y635798D02*
X1641653Y635601D01*
Y634472D01*
X1642734Y633391D01*
G01X1657163Y1393706D02*
X1658441Y1392428D01*
Y1391299D01*
G01X1670879Y1398891D02*
X1670685Y1398697D01*
Y1393759D01*
G01X1674921Y1398891D02*
X1672457Y1396427D01*
Y1393759D01*
G01X1689945Y1393806D02*
X1691223Y1392528D01*
Y1391399D01*
G01X1703661Y1398991D02*
X1703467Y1398797D01*
Y1393859D01*
G01X1707703Y1398991D02*
X1705239Y1396527D01*
Y1393859D01*
G01X1739479Y1561405D02*
X1740879Y1562805D01*
Y1565177D01*
X1741530Y1565828D01*
X1743039D01*
G01X1737914Y1566282D02*
X1738982D01*
X1740300Y1567600D01*
X1743039D01*
G01X1737914Y1570132D02*
X1739324D01*
X1740085Y1569371D01*
X1743039D01*
G01X1756051Y1580257D02*
X1755283Y1579489D01*
Y1575375D01*
G01X1760051Y1580257D02*
X1757055Y1577261D01*
Y1575375D01*
G01X1767888Y1661465D02*
X1766763D01*
X1765463Y1662765D01*
G01X1778782Y1565828D02*
X1777273D01*
X1775528Y1564083D01*
G01X1773657Y1573782D02*
X1774433D01*
X1777072Y1571143D01*
X1778782D01*
G01X1773554Y1577905D02*
X1774979D01*
X1776379Y1576505D01*
Y1574305D01*
X1777769Y1572915D01*
X1778782D01*
G01X1791794Y1579957D02*
X1791026Y1579189D01*
Y1575375D01*
G01X1795794Y1579957D02*
X1792798Y1577461D01*
Y1575375D01*
G54D336*
G01X169251Y1469695D02*
X170626Y1471070D01*
Y1473552D01*
G02X171641Y1476003I3467J0D01*
G01X171830Y1476192D01*
G02X173487Y1477300I3615J-3613D01*
G01X177089Y1478792D01*
G03X177291Y1478927I-238J575D01*
G01X180439Y1482075D01*
G03X181059Y1483002I-2018J2021D01*
G01X183901Y1489864D01*
X184462Y1490798D01*
G02X185556Y1492351I11110J-6664D01*
G01X194242Y1502924D01*
G03X194916Y1504805I-2289J1881D01*
G01Y1507648D01*
X193764Y1508800D01*
Y1509865D01*
X194123Y1510224D01*
X194652D01*
X194953Y1509923D01*
Y1509459D01*
G01X170213Y1483690D02*
X171674Y1482229D01*
X172005D01*
G03X175300Y1483594I0J4659D01*
G01X176584Y1484878D01*
G03X176952Y1485429I-1200J1200D01*
G01X178724Y1489711D01*
X178486Y1490285D01*
X178945Y1491395D01*
X179521Y1491633D01*
X180085Y1492997D01*
X180751Y1493994D01*
X180630Y1494605D01*
X181297Y1495603D01*
X181908Y1495725D01*
X182356Y1496395D01*
G02X182937Y1497103I3888J-2598D01*
G01X185312Y1499478D01*
X189296Y1504334D01*
X189794Y1505164D01*
X190191Y1506121D01*
Y1507648D01*
X189039Y1508800D01*
Y1509865D01*
X189398Y1510224D01*
X189927D01*
X190228Y1509923D01*
Y1509459D01*
G01X170213Y1480090D02*
X171502Y1481379D01*
X172005D01*
G03X175902Y1482992I2J5510D01*
G01X177186Y1484276D01*
G03X177738Y1485104I-1803J1800D01*
G01X180839Y1492594D01*
X181458Y1493522D01*
X181459D01*
X182615Y1495252D01*
Y1495253D01*
X183063Y1495923D01*
G02X183539Y1496501I3177J-2131D01*
G01X185943Y1498906D01*
X189993Y1503843D01*
X190556Y1504780D01*
X191041Y1505952D01*
Y1508415D01*
X191409Y1508783D01*
Y1511505D01*
G01X170213Y1501890D02*
X171581Y1503258D01*
X180129D01*
G03X181232Y1503477I0J2889D01*
G01X183614Y1504461D01*
G03X184726Y1505205I-1295J3139D01*
G01X186317Y1506802D01*
Y1508415D01*
X186685Y1508783D01*
Y1511505D01*
G01X170213Y1505490D02*
X171595Y1504108D01*
X172795D01*
X173235Y1504548D01*
X174435D01*
X174875Y1504108D01*
X176075D01*
X176515Y1504548D01*
X177715D01*
X178155Y1504108D01*
X180128D01*
G03X180907Y1504263I-1J2039D01*
G01X183290Y1505247D01*
G03X184123Y1505805I-973J2353D01*
G01X185467Y1507156D01*
Y1507648D01*
X184315Y1508800D01*
Y1509865D01*
X184674Y1510224D01*
X185203D01*
X185504Y1509923D01*
Y1509459D01*
G01X179551Y1459995D02*
X178176Y1461370D01*
Y1462880D01*
G02X178903Y1464635I2482J0D01*
G01X181859Y1467591D01*
X182481D01*
X183331Y1468441D01*
Y1469063D01*
X184359Y1470091D01*
G03X184907Y1471413I-1321J1322D01*
G01Y1477179D01*
G02X185101Y1478158I2559J2D01*
G01X188463Y1486277D01*
X189465Y1487950D01*
X199831Y1500581D01*
G03X200490Y1502419I-2235J1838D01*
G01Y1508415D01*
X200858Y1508783D01*
Y1511505D01*
G01X175951Y1459995D02*
X177326Y1461370D01*
Y1462880D01*
G02X178301Y1465237I3332J2D01*
G01X182729Y1469664D01*
Y1469665D01*
X183757Y1470693D01*
G03X184057Y1471413I-718J722D01*
G01Y1477179D01*
G02X184315Y1478483I3409J3D01*
G01X187701Y1486660D01*
X188768Y1488441D01*
X199174Y1501121D01*
G03X199640Y1502420I-1578J1299D01*
G01Y1507648D01*
X198488Y1508800D01*
Y1509865D01*
X198847Y1510224D01*
X199376D01*
X199677Y1509923D01*
Y1509459D01*
G01X172851Y1469695D02*
X171476Y1471070D01*
Y1473552D01*
G02X172243Y1475401I2616J-2D01*
G01X172432Y1475590D01*
G02X173813Y1476514I3014J-3011D01*
G01X177415Y1478006D01*
G03X177893Y1478325I-563J1362D01*
G01X179053Y1479485D01*
X179675D01*
X180525Y1480335D01*
Y1480957D01*
X181041Y1481473D01*
G03X181845Y1482676I-2621J2622D01*
G01X184662Y1489480D01*
X185191Y1490360D01*
G02X186214Y1491811I10378J-6231D01*
G01X194899Y1502384D01*
G03X195766Y1504804I-2946J2421D01*
G01Y1508415D01*
X196134Y1508783D01*
Y1511505D01*
G01X177969Y1525565D02*
X178117Y1525713D01*
X181503D01*
G01X178044Y1526835D02*
X178316Y1526563D01*
X179126D01*
X179457Y1526894D01*
G01X185504Y1540477D02*
X185837Y1540810D01*
Y1541294D01*
X185400Y1541731D01*
Y1546069D01*
X186485Y1547154D01*
X187708D01*
X188254Y1547700D01*
Y1548397D01*
G01X199651Y1469695D02*
X198276Y1471070D01*
Y1474524D01*
X198716Y1474964D01*
Y1476164D01*
X198276Y1476604D01*
Y1477804D01*
G02X199566Y1482055I7649J0D01*
G01X207164Y1493421D01*
G03X209939Y1502566I-13681J9145D01*
G01Y1508415D01*
X210307Y1508783D01*
Y1511505D01*
G01X196051Y1469695D02*
X197426Y1471070D01*
Y1477804D01*
G02X198859Y1482527I8499J0D01*
G01X206457Y1493893D01*
G03X209089Y1502566I-12974J8673D01*
G01Y1507648D01*
X207937Y1508800D01*
Y1509865D01*
X208296Y1510224D01*
X208825D01*
X209126Y1509923D01*
Y1509459D01*
G01X192951Y1479395D02*
X191576Y1480770D01*
Y1481455D01*
X192425Y1483502D01*
X194559Y1486102D01*
X195178Y1486163D01*
X195940Y1487091D01*
X195880Y1487711D01*
X203746Y1497295D01*
G03X205215Y1502250I-7643J4961D01*
G03Y1502253I-9112J1D01*
G03Y1502257I-9112J2D01*
G01Y1508415D01*
X205583Y1508783D01*
Y1511505D01*
G01X189351Y1479395D02*
X190726Y1480770D01*
Y1481625D01*
X191688Y1483944D01*
X203058Y1497797D01*
G03X204365Y1502252I-6955J4460D01*
G01Y1507648D01*
X203213Y1508800D01*
Y1509865D01*
X203572Y1510224D01*
X204101D01*
X204402Y1509923D01*
Y1509459D01*
G01X186685Y1538431D02*
X186687Y1538433D01*
Y1541647D01*
X186250Y1542084D01*
Y1545716D01*
X186838Y1546304D01*
X187700D01*
X188254Y1545750D01*
Y1544997D01*
G01X191409Y1538431D02*
X191411Y1538433D01*
Y1541647D01*
X191062Y1541996D01*
Y1545804D01*
X191562Y1546304D01*
X192424D01*
X192978Y1545750D01*
Y1544997D01*
G01X196134Y1538431D02*
X196136Y1538433D01*
Y1541647D01*
X195787Y1541996D01*
Y1545804D01*
X196287Y1546304D01*
X197149D01*
X197703Y1545750D01*
Y1544997D01*
G01X200858Y1538431D02*
X200860Y1538433D01*
Y1541647D01*
X200563Y1541944D01*
Y1545804D01*
X201063Y1546304D01*
X201873D01*
X202427Y1545750D01*
Y1544997D01*
G01X190228Y1540477D02*
X190561Y1540810D01*
Y1541294D01*
X190212Y1541643D01*
Y1546157D01*
X191209Y1547154D01*
X192432D01*
X192978Y1547700D01*
Y1548397D01*
G01X194953Y1540477D02*
X195286Y1540810D01*
Y1541294D01*
X194937Y1541643D01*
Y1546157D01*
X195934Y1547154D01*
X197157D01*
X197703Y1547700D01*
Y1548397D01*
G01X199677Y1540477D02*
X200010Y1540810D01*
Y1541294D01*
X199713Y1541591D01*
Y1546157D01*
X200710Y1547154D01*
X201881D01*
X202427Y1547700D01*
Y1548397D01*
G01X206351Y1459995D02*
X204976Y1461370D01*
Y1462519D01*
G02X206013Y1465019I3536J-2D01*
G01X210865Y1469871D01*
G03X211745Y1471995I-2126J2125D01*
G01Y1475784D01*
X212185Y1476224D01*
Y1477424D01*
X211745Y1477864D01*
Y1488214D01*
G02X212242Y1490757I6761J-1D01*
G01X212386Y1491111D01*
G03X214663Y1502733I-28531J11624D01*
G01Y1508415D01*
X215032Y1508784D01*
Y1511505D01*
G01X202751Y1459995D02*
X204126Y1461370D01*
Y1462520D01*
G02X205411Y1465621I4387J-1D01*
G01X210263Y1470473D01*
G03X210895Y1471996I-1523J1525D01*
G01Y1488213D01*
G02X211454Y1491077I7611J1D01*
G01X211598Y1491431D01*
G03X213813Y1502734I-27743J11305D01*
G01Y1507648D01*
X212661Y1508800D01*
Y1509865D01*
X213020Y1510224D01*
X213549D01*
X213850Y1509923D01*
Y1509459D01*
G01X205583Y1538431D02*
X205585Y1538433D01*
Y1541647D01*
X205236Y1541996D01*
Y1545804D01*
X205736Y1546304D01*
X206598D01*
X207152Y1545750D01*
Y1544997D01*
G01X210307Y1538431D02*
X210309Y1538433D01*
Y1541647D01*
X209960Y1541996D01*
Y1545804D01*
X210460Y1546304D01*
X211322D01*
X211876Y1545750D01*
Y1544997D01*
G01X215032Y1538431D02*
X215034Y1538433D01*
Y1540809D01*
X215033Y1540810D01*
Y1541647D01*
X214719Y1541961D01*
Y1545804D01*
X215219Y1546304D01*
X216047D01*
X216601Y1545750D01*
Y1544997D01*
G01X204402Y1540477D02*
X204735Y1540810D01*
Y1541294D01*
X204386Y1541643D01*
Y1546157D01*
X205383Y1547154D01*
X206606D01*
X207152Y1547700D01*
Y1548397D01*
G01X209126Y1540477D02*
X209459Y1540810D01*
Y1541294D01*
X209110Y1541643D01*
Y1546157D01*
X210107Y1547154D01*
X211330D01*
X211876Y1547700D01*
Y1548397D01*
G01X213850Y1540477D02*
X214183Y1540810D01*
Y1541294D01*
X213869Y1541608D01*
Y1546157D01*
X214866Y1547154D01*
X216054D01*
X216601Y1547701D01*
Y1548397D01*
G01X229551Y1459995D02*
X230926Y1461370D01*
Y1462707D01*
G02X232168Y1465705I4242J-1D01*
G01X236747Y1470284D01*
G03X237534Y1472179I-1894J1898D01*
G01Y1476358D01*
G03X237253Y1477033I-955J-2D01*
G01X228553Y1485733D01*
G02X227987Y1487102I1369J1367D01*
G01Y1507648D01*
X226835Y1508800D01*
Y1509865D01*
X227194Y1510224D01*
X227723D01*
X228024Y1509923D01*
Y1509459D01*
G01X226451Y1469695D02*
X225263Y1470883D01*
G02X225076Y1471335I453J452D01*
G01Y1475760D01*
X225516Y1476200D01*
Y1477400D01*
X225076Y1477840D01*
Y1482744D01*
G03X224524Y1484339I-2578J1D01*
G02X224267Y1484767I1562J1229D01*
G02X224112Y1485504I1672J737D01*
G01Y1508415D01*
X224480Y1508783D01*
Y1511505D01*
G01X222851Y1469695D02*
X224039Y1470883D01*
G03X224226Y1471335I-453J452D01*
G01Y1482745D01*
G03X223856Y1483813I-1728J-1D01*
G02X223489Y1484424I2230J1755D01*
G02X223262Y1485505I2450J1079D01*
G01Y1507648D01*
X222110Y1508800D01*
Y1509865D01*
X222469Y1510224D01*
X222998D01*
X223299Y1509923D01*
Y1509459D01*
G01X219751Y1479395D02*
X218562Y1480584D01*
G02X218376Y1481034I451J450D01*
G01Y1484545D01*
X218816Y1484985D01*
Y1486185D01*
X218376Y1486625D01*
Y1487825D01*
G02X218846Y1489317I2604J0D01*
G03X219318Y1490800I-2135J1496D01*
G01X219388Y1507645D01*
Y1508415D01*
X219756Y1508783D01*
Y1511505D01*
G01X233151Y1459995D02*
X231776Y1461370D01*
Y1462706D01*
G02X232770Y1465103I3391J-2D01*
G01X237349Y1469682D01*
G03X238384Y1472179I-2497J2498D01*
G01Y1476358D01*
G03X237855Y1477635I-1806J0D01*
G01X234466Y1481024D01*
Y1481646D01*
X233616Y1482496D01*
X232994D01*
X229155Y1486335D01*
G02X228837Y1487102I766J767D01*
G01Y1508415D01*
X229205Y1508783D01*
Y1511505D01*
G01X216151Y1479395D02*
X217339Y1480583D01*
G03X217526Y1481035I-453J452D01*
G01Y1487826D01*
G02X218151Y1489807I3454J-1D01*
G03X218468Y1490804I-1440J1007D01*
G01X218538Y1507648D01*
X217386Y1508800D01*
Y1509865D01*
X217745Y1510224D01*
X218274D01*
X218575Y1509923D01*
Y1509459D01*
G01X219756Y1538431D02*
X219758Y1538433D01*
Y1541647D01*
X219409Y1541996D01*
Y1545804D01*
X219909Y1546304D01*
X220771D01*
X221325Y1545750D01*
Y1544997D01*
G01X226050D02*
Y1545749D01*
X225495Y1546304D01*
X224633D01*
X224133Y1545804D01*
Y1541996D01*
X224482Y1541647D01*
Y1538433D01*
X224480Y1538431D01*
G01X229205D02*
X229207Y1538433D01*
Y1541647D01*
X228927Y1541927D01*
Y1545804D01*
X229427Y1546304D01*
X230220D01*
X230774Y1545750D01*
Y1544997D01*
G01X218575Y1540477D02*
X218908Y1540810D01*
Y1541294D01*
X218559Y1541643D01*
Y1546157D01*
X219556Y1547154D01*
X220779D01*
X221325Y1547700D01*
Y1548397D01*
G01X223299Y1540477D02*
X223632Y1540810D01*
Y1541294D01*
X223283Y1541643D01*
Y1546157D01*
X224280Y1547154D01*
X225503D01*
X226050Y1547701D01*
Y1548397D01*
G01X228024Y1540477D02*
X228357Y1540810D01*
Y1541294D01*
X228077Y1541574D01*
Y1546157D01*
X229074Y1547154D01*
X230228D01*
X230774Y1547700D01*
Y1548397D01*
G01X246551Y1479395D02*
X245172Y1480774D01*
Y1481113D01*
G03X244777Y1482070I-1353J2D01*
G01X240912Y1485934D01*
G03X239860Y1486368I-1050J-1053D01*
G01X238985D01*
G02X238559Y1486545I0J601D01*
G01X235883Y1489222D01*
Y1489843D01*
X235034Y1490692D01*
X234412D01*
X233708Y1491396D01*
G02X233561Y1491751I355J355D01*
G01Y1508415D01*
X233929Y1508783D01*
Y1511505D01*
G01X253251Y1469695D02*
X251876Y1471070D01*
Y1476464D01*
X252316Y1476904D01*
Y1478104D01*
X251876Y1478544D01*
Y1481246D01*
G03X251481Y1482203I-1353J2D01*
G01X238432Y1495252D01*
G02X238285Y1495607I355J355D01*
G01Y1508415D01*
X238654Y1508784D01*
Y1511505D01*
G01X242951Y1479395D02*
X244322Y1480766D01*
Y1481113D01*
G03X244175Y1481468I-502J0D01*
G01X240311Y1485332D01*
G03X239861Y1485518I-450J-451D01*
G01X238984D01*
G02X237958Y1485943I0J1451D01*
G01X233811Y1490090D01*
X233810D01*
X233106Y1490794D01*
G02X232711Y1491751I958J955D01*
G01Y1507648D01*
X231559Y1508800D01*
Y1509865D01*
X231918Y1510224D01*
X232447D01*
X232748Y1509923D01*
Y1509459D01*
G01X249651Y1469695D02*
X251026Y1471070D01*
Y1481246D01*
G03X250879Y1481601I-502J0D01*
G01X237826Y1494654D01*
G02X237435Y1495607I962J951D01*
G01Y1507648D01*
X236283Y1508800D01*
Y1509865D01*
X236642Y1510224D01*
X237171D01*
X237472Y1509923D01*
Y1509459D01*
G01X259951Y1459995D02*
X258576Y1461370D01*
Y1462750D01*
G02X259321Y1464545I2539J-2D01*
G01X262987Y1468211D01*
X263609D01*
X264459Y1469061D01*
Y1469683D01*
X264912Y1470136D01*
G03X265307Y1471092I-957J955D01*
G01Y1474658D01*
G03X264772Y1475946I-1822J-2D01*
G01X243892Y1496827D01*
G02X243010Y1498953I2125J2128D01*
G01Y1508415D01*
X243378Y1508783D01*
Y1511505D01*
G01X256351Y1459995D02*
X257726Y1461370D01*
Y1462750D01*
G02X258719Y1465147I3390J0D01*
G01X264310Y1470737D01*
G03X264457Y1471092I-355J355D01*
G01Y1474657D01*
G03X264171Y1475344I-972J-2D01*
G01X243290Y1496225D01*
G02X242160Y1498953I2728J2728D01*
G01Y1507648D01*
X241008Y1508800D01*
Y1509865D01*
X241367Y1510224D01*
X241896D01*
X242197Y1509923D01*
Y1509459D01*
G01X235499Y1544997D02*
Y1545749D01*
X234944Y1546304D01*
X234082D01*
X233582Y1545804D01*
Y1541996D01*
X233929Y1541649D01*
Y1538431D01*
G01X240223Y1544997D02*
Y1545749D01*
X239668Y1546304D01*
X238806D01*
X238306Y1545804D01*
Y1541996D01*
X238655Y1541647D01*
Y1538432D01*
X238654Y1538431D01*
G01X244947Y1544997D02*
Y1545653D01*
X244296Y1546304D01*
X243531D01*
X243031Y1545804D01*
Y1541996D01*
X243380Y1541647D01*
Y1538433D01*
X243378Y1538431D01*
G01X235499Y1548397D02*
Y1547701D01*
X234952Y1547154D01*
X233729D01*
X232732Y1546157D01*
Y1541643D01*
X233079Y1541296D01*
Y1540808D01*
X232748Y1540477D01*
G01X237472D02*
X237805Y1540810D01*
Y1541294D01*
X237456Y1541643D01*
Y1546157D01*
X238453Y1547154D01*
X239676D01*
X240223Y1547701D01*
Y1548397D01*
G01X242197Y1540477D02*
X242530Y1540810D01*
Y1541294D01*
X242181Y1541643D01*
Y1546157D01*
X243178Y1547154D01*
X244388D01*
X244947Y1547713D01*
Y1548397D01*
G01X269751Y1459995D02*
X271126Y1461370D01*
Y1462707D01*
G02X272366Y1465704I4238J2D01*
G01X277109Y1470447D01*
G03X277717Y1471914I-1466J1467D01*
G01Y1472979D01*
G03X277037Y1474620I-2320J0D01*
G01X275362Y1476295D01*
G03X274240Y1476760I-1122J-1121D01*
G01X270772D01*
G02X268526Y1477689I-2J3176D01*
G01X247279Y1498936D01*
G02X246884Y1499893I958J955D01*
G01Y1507648D01*
X245732Y1508800D01*
Y1509865D01*
X246091Y1510224D01*
X246620D01*
X246921Y1509923D01*
Y1509459D01*
G01X273351Y1459995D02*
X271976Y1461370D01*
Y1462708D01*
X271977Y1462707D01*
G02X272968Y1465102I3387J1D01*
G01X275391Y1467525D01*
X276013D01*
X276863Y1468375D01*
Y1468997D01*
X277711Y1469845D01*
G03X278567Y1471914I-2068J2067D01*
G01Y1472979D01*
G03X277639Y1475222I-3171J2D01*
G01X275964Y1476897D01*
G03X274240Y1477610I-1722J-1724D01*
G01X270772D01*
G02X269128Y1478291I0J2325D01*
G01X247881Y1499538D01*
G02X247734Y1499893I355J355D01*
G01Y1508415D01*
X248102Y1508783D01*
Y1511505D01*
G01X273521Y1484182D02*
X272712Y1483373D01*
X272162Y1483145D01*
X270924D01*
X253238Y1500831D01*
G02X252460Y1502713I1883J1880D01*
G01X252459Y1502712D01*
Y1507585D01*
X252829Y1507955D01*
Y1511503D01*
X252827Y1511505D01*
G01X273521Y1497582D02*
X272146Y1496207D01*
X265434D01*
G02X265036Y1496372I0J563D01*
G01X257552Y1503856D01*
G02X257183Y1504746I889J890D01*
G01Y1507585D01*
X257553Y1507955D01*
Y1511503D01*
X257551Y1511505D01*
G01X273521Y1480582D02*
X271808Y1482295D01*
X270571D01*
X252636Y1500230D01*
G02X251609Y1502713I2484J2481D01*
G01Y1507938D01*
X251979Y1508308D01*
Y1509126D01*
X251646Y1509459D01*
G01X273521Y1493982D02*
X272146Y1495357D01*
X270328D01*
X269888Y1494917D01*
X268688D01*
X268248Y1495357D01*
X265434D01*
G02X264434Y1495770I-2J1413D01*
G01X256950Y1503254D01*
G02X256333Y1504746I1491J1490D01*
G01Y1507938D01*
X256703Y1508308D01*
Y1509126D01*
X256370Y1509459D01*
G01X248102Y1538431D02*
X248104Y1538433D01*
Y1541647D01*
X247789Y1541962D01*
Y1545804D01*
X248289Y1546304D01*
X249117D01*
X249671Y1545750D01*
Y1544997D01*
G01X254396D02*
Y1545645D01*
X253737Y1546304D01*
X252980D01*
X252480Y1545804D01*
Y1541996D01*
X252829Y1541647D01*
Y1538433D01*
X252827Y1538431D01*
G01X259120Y1544997D02*
Y1545669D01*
X258485Y1546304D01*
X257704D01*
X257204Y1545804D01*
Y1541996D01*
X257553Y1541647D01*
Y1538433D01*
X257551Y1538431D01*
G01X246921Y1540477D02*
X247254Y1540810D01*
Y1541294D01*
X246939Y1541609D01*
Y1546157D01*
X247936Y1547154D01*
X249125D01*
X249671Y1547700D01*
Y1548397D01*
G01X251646Y1540477D02*
X251979Y1540810D01*
Y1541294D01*
X251630Y1541643D01*
Y1546157D01*
X252627Y1547154D01*
X253779D01*
X254396Y1547771D01*
Y1548397D01*
G01X256370Y1540477D02*
X256703Y1540810D01*
Y1541294D01*
X256354Y1541643D01*
Y1546157D01*
X257351Y1547154D01*
X258509D01*
X259120Y1547765D01*
Y1548397D01*
G01X304013Y1459995D02*
X305388Y1461370D01*
Y1462880D01*
G02X306363Y1465237I3332J2D01*
G01X310791Y1469664D01*
Y1469665D01*
X311819Y1470693D01*
G03X312119Y1471413I-718J722D01*
G01Y1477179D01*
G02X312377Y1478483I3409J3D01*
G01X315763Y1486660D01*
X316830Y1488441D01*
X327236Y1501121D01*
G03X327702Y1502420I-1578J1299D01*
G01Y1507648D01*
X326550Y1508800D01*
Y1509865D01*
X326909Y1510224D01*
X327438D01*
X327739Y1509923D01*
Y1509459D01*
G01X300913Y1469695D02*
X299538Y1471070D01*
Y1473552D01*
G02X300305Y1475401I2616J-2D01*
G01X300494Y1475590D01*
G02X301875Y1476514I3014J-3011D01*
G01X305477Y1478006D01*
G03X305955Y1478325I-563J1362D01*
G01X307115Y1479485D01*
X307737D01*
X308587Y1480335D01*
Y1480957D01*
X309103Y1481473D01*
G03X309907Y1482676I-2621J2622D01*
G01X312724Y1489480D01*
X313253Y1490360D01*
G02X314276Y1491811I10378J-6231D01*
G01X322961Y1502384D01*
G03X323828Y1504804I-2946J2421D01*
G01Y1508415D01*
X324196Y1508783D01*
Y1511505D01*
G01X297313Y1469695D02*
X298688Y1471070D01*
Y1473552D01*
G02X299703Y1476003I3467J0D01*
G01X299892Y1476192D01*
G02X301549Y1477300I3615J-3613D01*
G01X305151Y1478792D01*
G03X305353Y1478927I-238J575D01*
G01X308501Y1482075D01*
G03X309121Y1483002I-2018J2021D01*
G01X311963Y1489864D01*
X312524Y1490798D01*
G02X313618Y1492351I11110J-6664D01*
G01X322304Y1502924D01*
G03X322978Y1504805I-2289J1881D01*
G01Y1507648D01*
X321826Y1508800D01*
Y1509865D01*
X322185Y1510224D01*
X322714D01*
X323015Y1509923D01*
Y1509459D01*
G01X298275Y1483690D02*
X299736Y1482229D01*
X300067D01*
G03X303362Y1483594I0J4659D01*
G01X304646Y1484878D01*
G03X305014Y1485429I-1200J1200D01*
G01X306786Y1489711D01*
X306548Y1490285D01*
X307007Y1491395D01*
X307583Y1491633D01*
X308147Y1492997D01*
X308813Y1493994D01*
X308692Y1494605D01*
X309359Y1495603D01*
X309970Y1495725D01*
X310418Y1496395D01*
G02X310999Y1497103I3888J-2598D01*
G01X313374Y1499478D01*
X317358Y1504334D01*
X317856Y1505164D01*
X318253Y1506121D01*
Y1507648D01*
X317101Y1508800D01*
Y1509865D01*
X317460Y1510224D01*
X317989D01*
X318290Y1509923D01*
Y1509459D01*
G01X298275Y1480090D02*
X299564Y1481379D01*
X300067D01*
G03X303964Y1482992I2J5510D01*
G01X305248Y1484276D01*
G03X305800Y1485104I-1803J1800D01*
G01X308901Y1492594D01*
X309520Y1493522D01*
X309521D01*
X310677Y1495252D01*
Y1495253D01*
X311125Y1495923D01*
G02X311601Y1496501I3177J-2131D01*
G01X314005Y1498906D01*
X318055Y1503843D01*
X318618Y1504780D01*
X319103Y1505952D01*
Y1508415D01*
X319471Y1508783D01*
Y1511505D01*
G01X298275Y1501890D02*
X299643Y1503258D01*
X308191D01*
G03X309294Y1503477I0J2889D01*
G01X311676Y1504461D01*
G03X312788Y1505205I-1295J3139D01*
G01X314379Y1506802D01*
Y1508415D01*
X314747Y1508783D01*
Y1511505D01*
G01X298275Y1505490D02*
X299657Y1504108D01*
X300857D01*
X301297Y1504548D01*
X302497D01*
X302937Y1504108D01*
X304137D01*
X304577Y1504548D01*
X305777D01*
X306217Y1504108D01*
X308190D01*
G03X308969Y1504263I-1J2039D01*
G01X311352Y1505247D01*
G03X312185Y1505805I-973J2353D01*
G01X313529Y1507156D01*
Y1507648D01*
X312377Y1508800D01*
Y1509865D01*
X312736Y1510224D01*
X313265D01*
X313566Y1509923D01*
Y1509459D01*
G01X306031Y1525565D02*
X306179Y1525713D01*
X309565D01*
G01X306106Y1526835D02*
X306378Y1526563D01*
X307188D01*
X307519Y1526894D01*
G01X307613Y1459995D02*
X306238Y1461370D01*
Y1462880D01*
G02X306965Y1464635I2482J0D01*
G01X309921Y1467591D01*
X310543D01*
X311393Y1468441D01*
Y1469063D01*
X312421Y1470091D01*
G03X312969Y1471413I-1321J1322D01*
G01Y1477179D01*
G02X313163Y1478158I2559J2D01*
G01X316525Y1486277D01*
X317527Y1487950D01*
X327893Y1500581D01*
G03X328552Y1502419I-2235J1838D01*
G01Y1508415D01*
X328920Y1508783D01*
Y1511505D01*
G01X321013Y1479395D02*
X319638Y1480770D01*
Y1481455D01*
X320487Y1483502D01*
X322621Y1486102D01*
X323240Y1486163D01*
X324002Y1487091D01*
X323942Y1487711D01*
X331808Y1497295D01*
G03X333277Y1502250I-7643J4961D01*
G03Y1502253I-9112J1D01*
G03Y1502257I-9112J2D01*
G01Y1508415D01*
X333645Y1508783D01*
Y1511505D01*
G01X317413Y1479395D02*
X318788Y1480770D01*
Y1481625D01*
X319750Y1483944D01*
X331120Y1497797D01*
G03X332427Y1502252I-6955J4460D01*
G01Y1507648D01*
X331275Y1508800D01*
Y1509865D01*
X331634Y1510224D01*
X332163D01*
X332464Y1509923D01*
Y1509459D01*
G01X314747Y1538431D02*
X314749Y1538433D01*
Y1541647D01*
X314312Y1542084D01*
Y1545716D01*
X314900Y1546304D01*
X315762D01*
X316316Y1545750D01*
Y1544997D01*
G01X319471Y1538431D02*
X319473Y1538433D01*
Y1541647D01*
X319124Y1541996D01*
Y1545804D01*
X319624Y1546304D01*
X320486D01*
X321040Y1545750D01*
Y1544997D01*
G01X313566Y1540477D02*
X313899Y1540810D01*
Y1541294D01*
X313462Y1541731D01*
Y1546069D01*
X314547Y1547154D01*
X315770D01*
X316316Y1547700D01*
Y1548397D01*
G01X318290Y1540477D02*
X318623Y1540810D01*
Y1541294D01*
X318274Y1541643D01*
Y1546157D01*
X319271Y1547154D01*
X320494D01*
X321040Y1547700D01*
Y1548397D01*
G01X334413Y1459995D02*
X333038Y1461370D01*
Y1462519D01*
G02X334075Y1465019I3536J-2D01*
G01X338927Y1469871D01*
G03X339807Y1471995I-2126J2125D01*
G01Y1475784D01*
X340247Y1476224D01*
Y1477424D01*
X339807Y1477864D01*
Y1488214D01*
G02X340304Y1490757I6761J-1D01*
G01X340448Y1491111D01*
G03X342725Y1502733I-28531J11624D01*
G01Y1508415D01*
X343094Y1508784D01*
Y1511505D01*
G01X330813Y1459995D02*
X332188Y1461370D01*
Y1462520D01*
G02X333473Y1465621I4387J-1D01*
G01X338325Y1470473D01*
G03X338957Y1471996I-1523J1525D01*
G01Y1488213D01*
G02X339516Y1491077I7611J1D01*
G01X339660Y1491431D01*
G03X341875Y1502734I-27743J11305D01*
G01Y1507648D01*
X340723Y1508800D01*
Y1509865D01*
X341082Y1510224D01*
X341611D01*
X341912Y1509923D01*
Y1509459D01*
G01X327713Y1469695D02*
X326338Y1471070D01*
Y1474524D01*
X326778Y1474964D01*
Y1476164D01*
X326338Y1476604D01*
Y1477804D01*
G02X327628Y1482055I7649J0D01*
G01X335226Y1493421D01*
G03X338001Y1502566I-13681J9145D01*
G01Y1508415D01*
X338369Y1508783D01*
Y1511505D01*
G01X324113Y1469695D02*
X325488Y1471070D01*
Y1477804D01*
G02X326921Y1482527I8499J0D01*
G01X334519Y1493893D01*
G03X337151Y1502566I-12974J8673D01*
G01Y1507648D01*
X335999Y1508800D01*
Y1509865D01*
X336358Y1510224D01*
X336887D01*
X337188Y1509923D01*
Y1509459D01*
G01X324196Y1538431D02*
X324198Y1538433D01*
Y1541647D01*
X323849Y1541996D01*
Y1545804D01*
X324349Y1546304D01*
X325211D01*
X325765Y1545750D01*
Y1544997D01*
G01X328920Y1538431D02*
X328922Y1538433D01*
Y1541647D01*
X328625Y1541944D01*
Y1545804D01*
X329125Y1546304D01*
X329935D01*
X330489Y1545750D01*
Y1544997D01*
G01X333645Y1538431D02*
X333647Y1538433D01*
Y1541647D01*
X333298Y1541996D01*
Y1545804D01*
X333798Y1546304D01*
X334660D01*
X335214Y1545750D01*
Y1544997D01*
G01X323015Y1540477D02*
X323348Y1540810D01*
Y1541294D01*
X322999Y1541643D01*
Y1546157D01*
X323996Y1547154D01*
X325219D01*
X325765Y1547700D01*
Y1548397D01*
G01X327739Y1540477D02*
X328072Y1540810D01*
Y1541294D01*
X327775Y1541591D01*
Y1546157D01*
X328772Y1547154D01*
X329943D01*
X330489Y1547700D01*
Y1548397D01*
G01X332464Y1540477D02*
X332797Y1540810D01*
Y1541294D01*
X332448Y1541643D01*
Y1546157D01*
X333445Y1547154D01*
X334668D01*
X335214Y1547700D01*
Y1548397D01*
G01X347813Y1479395D02*
X346624Y1480584D01*
G02X346438Y1481034I451J450D01*
G01Y1484545D01*
X346878Y1484985D01*
Y1486185D01*
X346438Y1486625D01*
Y1487825D01*
G02X346908Y1489317I2604J0D01*
G03X347380Y1490800I-2135J1496D01*
G01X347450Y1507645D01*
Y1508415D01*
X347818Y1508783D01*
Y1511505D01*
G01X344213Y1479395D02*
X345401Y1480583D01*
G03X345588Y1481035I-453J452D01*
G01Y1487826D01*
G02X346213Y1489807I3454J-1D01*
G03X346530Y1490804I-1440J1007D01*
G01X346600Y1507648D01*
X345448Y1508800D01*
Y1509865D01*
X345807Y1510224D01*
X346336D01*
X346637Y1509923D01*
Y1509459D01*
G01X338369Y1538431D02*
X338371Y1538433D01*
Y1541647D01*
X338022Y1541996D01*
Y1545804D01*
X338522Y1546304D01*
X339384D01*
X339938Y1545750D01*
Y1544997D01*
G01X343094Y1538431D02*
X343096Y1538433D01*
Y1540809D01*
X343095Y1540810D01*
Y1541647D01*
X342781Y1541961D01*
Y1545804D01*
X343281Y1546304D01*
X344109D01*
X344663Y1545750D01*
Y1544997D01*
G01X347818Y1538431D02*
X347820Y1538433D01*
Y1541647D01*
X347471Y1541996D01*
Y1545804D01*
X347971Y1546304D01*
X348833D01*
X349387Y1545750D01*
Y1544997D01*
G01X337188Y1540477D02*
X337521Y1540810D01*
Y1541294D01*
X337172Y1541643D01*
Y1546157D01*
X338169Y1547154D01*
X339392D01*
X339938Y1547700D01*
Y1548397D01*
G01X341912Y1540477D02*
X342245Y1540810D01*
Y1541294D01*
X341931Y1541608D01*
Y1546157D01*
X342928Y1547154D01*
X344116D01*
X344663Y1547701D01*
Y1548397D01*
G01X346637Y1540477D02*
X346970Y1540810D01*
Y1541294D01*
X346621Y1541643D01*
Y1546157D01*
X347618Y1547154D01*
X348841D01*
X349387Y1547700D01*
Y1548397D01*
G01X361213Y1459995D02*
X359838Y1461370D01*
Y1462706D01*
G02X360832Y1465103I3391J-2D01*
G01X365411Y1469682D01*
G03X366446Y1472179I-2497J2498D01*
G01Y1476358D01*
G03X365917Y1477635I-1806J0D01*
G01X362528Y1481024D01*
Y1481646D01*
X361678Y1482496D01*
X361056D01*
X357217Y1486335D01*
G02X356899Y1487102I766J767D01*
G01Y1508415D01*
X357267Y1508783D01*
Y1511505D01*
G01X357613Y1459995D02*
X358988Y1461370D01*
Y1462707D01*
G02X360230Y1465705I4242J-1D01*
G01X364809Y1470284D01*
G03X365596Y1472179I-1894J1898D01*
G01Y1476358D01*
G03X365315Y1477033I-955J-2D01*
G01X356615Y1485733D01*
G02X356049Y1487102I1369J1367D01*
G01Y1507648D01*
X354897Y1508800D01*
Y1509865D01*
X355256Y1510224D01*
X355785D01*
X356086Y1509923D01*
Y1509459D01*
G01X354513Y1469695D02*
X353325Y1470883D01*
G02X353138Y1471335I453J452D01*
G01Y1475760D01*
X353578Y1476200D01*
Y1477400D01*
X353138Y1477840D01*
Y1482744D01*
G03X352586Y1484339I-2578J1D01*
G02X352329Y1484767I1562J1229D01*
G02X352174Y1485504I1672J737D01*
G01Y1508415D01*
X352542Y1508783D01*
Y1511505D01*
G01X350913Y1469695D02*
X352101Y1470883D01*
G03X352288Y1471335I-453J452D01*
G01Y1482745D01*
G03X351918Y1483813I-1728J-1D01*
G02X351551Y1484424I2230J1755D01*
G02X351324Y1485505I2450J1079D01*
G01Y1507648D01*
X350172Y1508800D01*
Y1509865D01*
X350531Y1510224D01*
X351060D01*
X351361Y1509923D01*
Y1509459D01*
G01X374613Y1479395D02*
X373234Y1480774D01*
Y1481113D01*
G03X372839Y1482070I-1353J2D01*
G01X368974Y1485934D01*
G03X367922Y1486368I-1050J-1053D01*
G01X367047D01*
G02X366621Y1486545I0J601D01*
G01X363945Y1489222D01*
Y1489843D01*
X363096Y1490692D01*
X362474D01*
X361770Y1491396D01*
G02X361623Y1491751I355J355D01*
G01Y1508415D01*
X361991Y1508783D01*
Y1511505D01*
G01X371013Y1479395D02*
X372384Y1480766D01*
Y1481113D01*
G03X372237Y1481468I-502J0D01*
G01X368373Y1485332D01*
G03X367923Y1485518I-450J-451D01*
G01X367046D01*
G02X366020Y1485943I0J1451D01*
G01X361873Y1490090D01*
X361872D01*
X361168Y1490794D01*
G02X360773Y1491751I958J955D01*
G01Y1507648D01*
X359621Y1508800D01*
Y1509865D01*
X359980Y1510224D01*
X360509D01*
X360810Y1509923D01*
Y1509459D01*
G01X377713Y1469695D02*
X379088Y1471070D01*
Y1481246D01*
G03X378941Y1481601I-502J0D01*
G01X365888Y1494654D01*
G02X365497Y1495607I962J951D01*
G01Y1507648D01*
X364345Y1508800D01*
Y1509865D01*
X364704Y1510224D01*
X365233D01*
X365534Y1509923D01*
Y1509459D01*
G01X363561Y1544997D02*
Y1545749D01*
X363006Y1546304D01*
X362144D01*
X361644Y1545804D01*
Y1541996D01*
X361991Y1541649D01*
Y1538431D01*
G01X354112Y1544997D02*
Y1545749D01*
X353557Y1546304D01*
X352695D01*
X352195Y1545804D01*
Y1541996D01*
X352544Y1541647D01*
Y1538433D01*
X352542Y1538431D01*
G01X357267D02*
X357269Y1538433D01*
Y1541647D01*
X356989Y1541927D01*
Y1545804D01*
X357489Y1546304D01*
X358282D01*
X358836Y1545750D01*
Y1544997D01*
G01X363561Y1548397D02*
Y1547701D01*
X363014Y1547154D01*
X361791D01*
X360794Y1546157D01*
Y1541643D01*
X361141Y1541296D01*
Y1540808D01*
X360810Y1540477D01*
G01X351361D02*
X351694Y1540810D01*
Y1541294D01*
X351345Y1541643D01*
Y1546157D01*
X352342Y1547154D01*
X353565D01*
X354112Y1547701D01*
Y1548397D01*
G01X356086Y1540477D02*
X356419Y1540810D01*
Y1541294D01*
X356139Y1541574D01*
Y1546157D01*
X357136Y1547154D01*
X358290D01*
X358836Y1547700D01*
Y1548397D01*
G01X381313Y1469695D02*
X379938Y1471070D01*
Y1476464D01*
X380378Y1476904D01*
Y1478104D01*
X379938Y1478544D01*
Y1481246D01*
G03X379543Y1482203I-1353J2D01*
G01X366494Y1495252D01*
G02X366347Y1495607I355J355D01*
G01Y1508415D01*
X366716Y1508784D01*
Y1511505D01*
G01X388013Y1459995D02*
X386638Y1461370D01*
Y1462750D01*
G02X387383Y1464545I2539J-2D01*
G01X391049Y1468211D01*
X391671D01*
X392521Y1469061D01*
Y1469683D01*
X392974Y1470136D01*
G03X393369Y1471092I-957J955D01*
G01Y1474658D01*
G03X392834Y1475946I-1822J-2D01*
G01X371954Y1496827D01*
G02X371072Y1498953I2125J2128D01*
G01Y1508415D01*
X371440Y1508783D01*
Y1511505D01*
G01X384413Y1459995D02*
X385788Y1461370D01*
Y1462750D01*
G02X386781Y1465147I3390J0D01*
G01X392372Y1470737D01*
G03X392519Y1471092I-355J355D01*
G01Y1474657D01*
G03X392233Y1475344I-972J-2D01*
G01X371352Y1496225D01*
G02X370222Y1498953I2728J2728D01*
G01Y1507648D01*
X369070Y1508800D01*
Y1509865D01*
X369429Y1510224D01*
X369958D01*
X370259Y1509923D01*
Y1509459D01*
G01X401413Y1459995D02*
X400038Y1461370D01*
Y1462708D01*
X400039Y1462707D01*
G02X401030Y1465102I3387J1D01*
G01X403453Y1467525D01*
X404075D01*
X404925Y1468375D01*
Y1468997D01*
X405773Y1469845D01*
G03X406629Y1471914I-2068J2067D01*
G01Y1472979D01*
G03X405701Y1475222I-3171J2D01*
G01X404026Y1476897D01*
G03X402302Y1477610I-1722J-1724D01*
G01X398834D01*
G02X397190Y1478291I0J2325D01*
G01X375943Y1499538D01*
G02X375796Y1499893I355J355D01*
G01Y1508415D01*
X376164Y1508783D01*
Y1511505D01*
G01X401583Y1480582D02*
X399870Y1482295D01*
X398633D01*
X380698Y1500230D01*
G02X379671Y1502713I2484J2481D01*
G01Y1507938D01*
X380041Y1508308D01*
Y1509126D01*
X379708Y1509459D01*
G01X397813Y1459995D02*
X399188Y1461370D01*
Y1462707D01*
G02X400428Y1465704I4238J2D01*
G01X405171Y1470447D01*
G03X405779Y1471914I-1466J1467D01*
G01Y1472979D01*
G03X405099Y1474620I-2320J0D01*
G01X403424Y1476295D01*
G03X402302Y1476760I-1122J-1121D01*
G01X398834D01*
G02X396588Y1477689I-2J3176D01*
G01X375341Y1498936D01*
G02X374946Y1499893I958J955D01*
G01Y1507648D01*
X373794Y1508800D01*
Y1509865D01*
X374153Y1510224D01*
X374682D01*
X374983Y1509923D01*
Y1509459D01*
G01X368285Y1544997D02*
Y1545749D01*
X367730Y1546304D01*
X366868D01*
X366368Y1545804D01*
Y1541996D01*
X366717Y1541647D01*
Y1538432D01*
X366716Y1538431D01*
G01X373009Y1544997D02*
Y1545653D01*
X372358Y1546304D01*
X371593D01*
X371093Y1545804D01*
Y1541996D01*
X371442Y1541647D01*
Y1538433D01*
X371440Y1538431D01*
G01X376164D02*
X376166Y1538433D01*
Y1541647D01*
X375851Y1541962D01*
Y1545804D01*
X376351Y1546304D01*
X377179D01*
X377733Y1545750D01*
Y1544997D01*
G01X365534Y1540477D02*
X365867Y1540810D01*
Y1541294D01*
X365518Y1541643D01*
Y1546157D01*
X366515Y1547154D01*
X367738D01*
X368285Y1547701D01*
Y1548397D01*
G01X370259Y1540477D02*
X370592Y1540810D01*
Y1541294D01*
X370243Y1541643D01*
Y1546157D01*
X371240Y1547154D01*
X372450D01*
X373009Y1547713D01*
Y1548397D01*
G01X374983Y1540477D02*
X375316Y1540810D01*
Y1541294D01*
X375001Y1541609D01*
Y1546157D01*
X375998Y1547154D01*
X377187D01*
X377733Y1547700D01*
Y1548397D01*
G01X379708Y1540477D02*
X380041Y1540810D01*
Y1541294D01*
X379692Y1541643D01*
Y1546157D01*
X380689Y1547154D01*
X381841D01*
X382458Y1547771D01*
Y1548397D01*
G01X401583Y1484182D02*
X400774Y1483373D01*
X400224Y1483145D01*
X398986D01*
X381300Y1500831D01*
G02X380522Y1502713I1883J1880D01*
G01X380521Y1502712D01*
Y1507585D01*
X380891Y1507955D01*
Y1511503D01*
X380889Y1511505D01*
G01X401583Y1497582D02*
X400208Y1496207D01*
X393496D01*
G02X393098Y1496372I0J563D01*
G01X385614Y1503856D01*
G02X385245Y1504746I889J890D01*
G01Y1507585D01*
X385615Y1507955D01*
Y1511503D01*
X385613Y1511505D01*
G01X401583Y1493982D02*
X400208Y1495357D01*
X398390D01*
X397950Y1494917D01*
X396750D01*
X396310Y1495357D01*
X393496D01*
G02X392496Y1495770I-2J1413D01*
G01X385012Y1503254D01*
G02X384395Y1504746I1491J1490D01*
G01Y1507938D01*
X384765Y1508308D01*
Y1509126D01*
X384432Y1509459D01*
G01X382458Y1544997D02*
Y1545645D01*
X381799Y1546304D01*
X381042D01*
X380542Y1545804D01*
Y1541996D01*
X380891Y1541647D01*
Y1538433D01*
X380889Y1538431D01*
G01X387182Y1544997D02*
Y1545669D01*
X386547Y1546304D01*
X385766D01*
X385266Y1545804D01*
Y1541996D01*
X385615Y1541647D01*
Y1538433D01*
X385613Y1538431D01*
G01X384432Y1540477D02*
X384765Y1540810D01*
Y1541294D01*
X384416Y1541643D01*
Y1546157D01*
X385413Y1547154D01*
X386571D01*
X387182Y1547765D01*
Y1548397D01*
G01X437024Y1469695D02*
X435649Y1471070D01*
Y1473552D01*
G02X436416Y1475401I2616J-2D01*
G01X436605Y1475590D01*
G02X437986Y1476514I3014J-3011D01*
G01X441588Y1478006D01*
G03X442066Y1478325I-563J1362D01*
G01X443226Y1479485D01*
X443848D01*
X444698Y1480335D01*
Y1480957D01*
X445214Y1481473D01*
G03X446018Y1482676I-2621J2622D01*
G01X448835Y1489480D01*
X449364Y1490360D01*
G02X450387Y1491811I10378J-6231D01*
G01X459072Y1502384D01*
G03X459939Y1504804I-2946J2421D01*
G01Y1508415D01*
X460307Y1508783D01*
Y1511505D01*
G01X433424Y1469695D02*
X434799Y1471070D01*
Y1473552D01*
G02X435814Y1476003I3467J0D01*
G01X436003Y1476192D01*
G02X437660Y1477300I3615J-3613D01*
G01X441262Y1478792D01*
G03X441464Y1478927I-238J575D01*
G01X444612Y1482075D01*
G03X445232Y1483002I-2018J2021D01*
G01X448074Y1489864D01*
X448635Y1490798D01*
G02X449729Y1492351I11110J-6664D01*
G01X458415Y1502924D01*
G03X459089Y1504805I-2289J1881D01*
G01Y1507648D01*
X457937Y1508800D01*
Y1509865D01*
X458296Y1510224D01*
X458825D01*
X459126Y1509923D01*
Y1509459D01*
G01X434386Y1483690D02*
X435847Y1482229D01*
X436178D01*
G03X439473Y1483594I0J4659D01*
G01X440757Y1484878D01*
G03X441125Y1485429I-1200J1200D01*
G01X442897Y1489711D01*
X442659Y1490285D01*
X443118Y1491395D01*
X443694Y1491633D01*
X444258Y1492997D01*
X444924Y1493994D01*
X444803Y1494605D01*
X445470Y1495603D01*
X446081Y1495725D01*
X446529Y1496395D01*
G02X447110Y1497103I3888J-2598D01*
G01X449485Y1499478D01*
X453469Y1504334D01*
X453967Y1505164D01*
X454364Y1506121D01*
Y1507648D01*
X453212Y1508800D01*
Y1509865D01*
X453571Y1510224D01*
X454100D01*
X454401Y1509923D01*
Y1509459D01*
G01X434386Y1480090D02*
X435675Y1481379D01*
X436178D01*
G03X440075Y1482992I2J5510D01*
G01X441359Y1484276D01*
G03X441911Y1485104I-1803J1800D01*
G01X445012Y1492594D01*
X445631Y1493522D01*
X445632D01*
X446788Y1495252D01*
Y1495253D01*
X447236Y1495923D01*
G02X447712Y1496501I3177J-2131D01*
G01X450116Y1498906D01*
X454166Y1503843D01*
X454729Y1504780D01*
X455214Y1505952D01*
Y1508415D01*
X455582Y1508783D01*
Y1511505D01*
G01X434386Y1501890D02*
X435754Y1503258D01*
X444302D01*
G03X445405Y1503477I0J2889D01*
G01X447787Y1504461D01*
G03X448899Y1505205I-1295J3139D01*
G01X450490Y1506802D01*
Y1508415D01*
X450858Y1508783D01*
Y1511505D01*
G01X434386Y1505490D02*
X435768Y1504108D01*
X436968D01*
X437408Y1504548D01*
X438608D01*
X439048Y1504108D01*
X440248D01*
X440688Y1504548D01*
X441888D01*
X442328Y1504108D01*
X444301D01*
G03X445080Y1504263I-1J2039D01*
G01X447463Y1505247D01*
G03X448296Y1505805I-973J2353D01*
G01X449640Y1507156D01*
Y1507648D01*
X448488Y1508800D01*
Y1509865D01*
X448847Y1510224D01*
X449376D01*
X449677Y1509923D01*
Y1509459D01*
G01X442142Y1525565D02*
X442290Y1525713D01*
X445676D01*
G01X442217Y1526835D02*
X442489Y1526563D01*
X443299D01*
X443630Y1526894D01*
G01X443724Y1459995D02*
X442349Y1461370D01*
Y1462880D01*
G02X443076Y1464635I2482J0D01*
G01X446032Y1467591D01*
X446654D01*
X447504Y1468441D01*
Y1469063D01*
X448532Y1470091D01*
G03X449080Y1471413I-1321J1322D01*
G01Y1477179D01*
G02X449274Y1478158I2559J2D01*
G01X452636Y1486277D01*
X453638Y1487950D01*
X464004Y1500581D01*
G03X464663Y1502419I-2235J1838D01*
G01Y1508415D01*
X465031Y1508783D01*
Y1511505D01*
G01X440124Y1459995D02*
X441499Y1461370D01*
Y1462880D01*
G02X442474Y1465237I3332J2D01*
G01X446902Y1469664D01*
Y1469665D01*
X447930Y1470693D01*
G03X448230Y1471413I-718J722D01*
G01Y1477179D01*
G02X448488Y1478483I3409J3D01*
G01X451874Y1486660D01*
X452941Y1488441D01*
X463347Y1501121D01*
G03X463813Y1502420I-1578J1299D01*
G01Y1507648D01*
X462661Y1508800D01*
Y1509865D01*
X463020Y1510224D01*
X463549D01*
X463850Y1509923D01*
Y1509459D01*
G01X453524Y1479395D02*
X454899Y1480770D01*
Y1481625D01*
X455861Y1483944D01*
X467231Y1497797D01*
G03X468538Y1502252I-6955J4460D01*
G01Y1507648D01*
X467386Y1508800D01*
Y1509865D01*
X467745Y1510224D01*
X468274D01*
X468575Y1509923D01*
Y1509459D01*
G01X450858Y1538431D02*
X450860Y1538433D01*
Y1541647D01*
X450423Y1542084D01*
Y1545716D01*
X451011Y1546304D01*
X451873D01*
X452427Y1545750D01*
Y1544997D01*
G01X449677Y1540477D02*
X450010Y1540810D01*
Y1541294D01*
X449573Y1541731D01*
Y1546069D01*
X450658Y1547154D01*
X451881D01*
X452427Y1547700D01*
Y1548397D01*
G01X454401Y1540477D02*
X454734Y1540810D01*
Y1541294D01*
X454385Y1541643D01*
Y1546157D01*
X455382Y1547154D01*
X456605D01*
X457151Y1547700D01*
Y1548397D01*
G01X470524Y1459995D02*
X469149Y1461370D01*
Y1462519D01*
G02X470186Y1465019I3536J-2D01*
G01X475038Y1469871D01*
G03X475918Y1471995I-2126J2125D01*
G01Y1475784D01*
X476358Y1476224D01*
Y1477424D01*
X475918Y1477864D01*
Y1488214D01*
G02X476415Y1490757I6761J-1D01*
G01X476559Y1491111D01*
G03X478836Y1502733I-28531J11624D01*
G01Y1508415D01*
X479205Y1508784D01*
Y1511505D01*
G01X466924Y1459995D02*
X468299Y1461370D01*
Y1462520D01*
G02X469584Y1465621I4387J-1D01*
G01X474436Y1470473D01*
G03X475068Y1471996I-1523J1525D01*
G01Y1488213D01*
G02X475627Y1491077I7611J1D01*
G01X475771Y1491431D01*
G03X477986Y1502734I-27743J11305D01*
G01Y1507648D01*
X476834Y1508800D01*
Y1509865D01*
X477193Y1510224D01*
X477722D01*
X478023Y1509923D01*
Y1509459D01*
G01X463824Y1469695D02*
X462449Y1471070D01*
Y1474524D01*
X462889Y1474964D01*
Y1476164D01*
X462449Y1476604D01*
Y1477804D01*
G02X463739Y1482055I7649J0D01*
G01X471337Y1493421D01*
G03X474112Y1502566I-13681J9145D01*
G01Y1508415D01*
X474480Y1508783D01*
Y1511505D01*
G01X460224Y1469695D02*
X461599Y1471070D01*
Y1477804D01*
G02X463032Y1482527I8499J0D01*
G01X470630Y1493893D01*
G03X473262Y1502566I-12974J8673D01*
G01Y1507648D01*
X472110Y1508800D01*
Y1509865D01*
X472469Y1510224D01*
X472998D01*
X473299Y1509923D01*
Y1509459D01*
G01X457124Y1479395D02*
X455749Y1480770D01*
Y1481455D01*
X456598Y1483502D01*
X458732Y1486102D01*
X459351Y1486163D01*
X460113Y1487091D01*
X460053Y1487711D01*
X467919Y1497295D01*
G03X469388Y1502250I-7643J4961D01*
G03Y1502253I-9112J1D01*
G03Y1502257I-9112J2D01*
G01Y1508415D01*
X469756Y1508783D01*
Y1511505D01*
G01X455582Y1538431D02*
X455584Y1538433D01*
Y1541647D01*
X455235Y1541996D01*
Y1545804D01*
X455735Y1546304D01*
X456597D01*
X457151Y1545750D01*
Y1544997D01*
G01X460307Y1538431D02*
X460309Y1538433D01*
Y1541647D01*
X459960Y1541996D01*
Y1545804D01*
X460460Y1546304D01*
X461322D01*
X461876Y1545750D01*
Y1544997D01*
G01X465031Y1538431D02*
X465033Y1538433D01*
Y1541647D01*
X464736Y1541944D01*
Y1545804D01*
X465236Y1546304D01*
X466046D01*
X466600Y1545750D01*
Y1544997D01*
G01X459126Y1540477D02*
X459459Y1540810D01*
Y1541294D01*
X459110Y1541643D01*
Y1546157D01*
X460107Y1547154D01*
X461330D01*
X461876Y1547700D01*
Y1548397D01*
G01X463850Y1540477D02*
X464183Y1540810D01*
Y1541294D01*
X463886Y1541591D01*
Y1546157D01*
X464883Y1547154D01*
X466054D01*
X466600Y1547700D01*
Y1548397D01*
G01X468575Y1540477D02*
X468908Y1540810D01*
Y1541294D01*
X468559Y1541643D01*
Y1546157D01*
X469556Y1547154D01*
X470779D01*
X471325Y1547700D01*
Y1548397D01*
G01X483924Y1479395D02*
X482735Y1480584D01*
G02X482549Y1481034I451J450D01*
G01Y1484545D01*
X482989Y1484985D01*
Y1486185D01*
X482549Y1486625D01*
Y1487825D01*
G02X483019Y1489317I2604J0D01*
G03X483491Y1490800I-2135J1496D01*
G01X483561Y1507645D01*
Y1508415D01*
X483929Y1508783D01*
Y1511505D01*
G01X480324Y1479395D02*
X481512Y1480583D01*
G03X481699Y1481035I-453J452D01*
G01Y1487826D01*
G02X482324Y1489807I3454J-1D01*
G03X482641Y1490804I-1440J1007D01*
G01X482711Y1507648D01*
X481559Y1508800D01*
Y1509865D01*
X481918Y1510224D01*
X482447D01*
X482748Y1509923D01*
Y1509459D01*
G01X469756Y1538431D02*
X469758Y1538433D01*
Y1541647D01*
X469409Y1541996D01*
Y1545804D01*
X469909Y1546304D01*
X470771D01*
X471325Y1545750D01*
Y1544997D01*
G01X474480Y1538431D02*
X474482Y1538433D01*
Y1541647D01*
X474133Y1541996D01*
Y1545804D01*
X474633Y1546304D01*
X475495D01*
X476049Y1545750D01*
Y1544997D01*
G01X479205Y1538431D02*
X479207Y1538433D01*
Y1540809D01*
X479206Y1540810D01*
Y1541647D01*
X478892Y1541961D01*
Y1545804D01*
X479392Y1546304D01*
X480220D01*
X480774Y1545750D01*
Y1544997D01*
G01X483929Y1538431D02*
X483931Y1538433D01*
Y1541647D01*
X483582Y1541996D01*
Y1545804D01*
X484082Y1546304D01*
X484944D01*
X485498Y1545750D01*
Y1544997D01*
G01X473299Y1540477D02*
X473632Y1540810D01*
Y1541294D01*
X473283Y1541643D01*
Y1546157D01*
X474280Y1547154D01*
X475503D01*
X476049Y1547700D01*
Y1548397D01*
G01X478023Y1540477D02*
X478356Y1540810D01*
Y1541294D01*
X478042Y1541608D01*
Y1546157D01*
X479039Y1547154D01*
X480227D01*
X480774Y1547701D01*
Y1548397D01*
G01X482748Y1540477D02*
X483081Y1540810D01*
Y1541294D01*
X482732Y1541643D01*
Y1546157D01*
X483729Y1547154D01*
X484952D01*
X485498Y1547700D01*
Y1548397D01*
G01X497324Y1459995D02*
X495949Y1461370D01*
Y1462706D01*
G02X496943Y1465103I3391J-2D01*
G01X501522Y1469682D01*
G03X502557Y1472179I-2497J2498D01*
G01Y1476358D01*
G03X502028Y1477635I-1806J0D01*
G01X498639Y1481024D01*
Y1481646D01*
X497789Y1482496D01*
X497167D01*
X493328Y1486335D01*
G02X493010Y1487102I766J767D01*
G01Y1508415D01*
X493378Y1508783D01*
Y1511505D01*
G01X493724Y1459995D02*
X495099Y1461370D01*
Y1462707D01*
G02X496341Y1465705I4242J-1D01*
G01X500920Y1470284D01*
G03X501707Y1472179I-1894J1898D01*
G01Y1476358D01*
G03X501426Y1477033I-955J-2D01*
G01X492726Y1485733D01*
G02X492160Y1487102I1369J1367D01*
G01Y1507648D01*
X491008Y1508800D01*
Y1509865D01*
X491367Y1510224D01*
X491896D01*
X492197Y1509923D01*
Y1509459D01*
G01X490624Y1469695D02*
X489436Y1470883D01*
G02X489249Y1471335I453J452D01*
G01Y1475760D01*
X489689Y1476200D01*
Y1477400D01*
X489249Y1477840D01*
Y1482744D01*
G03X488697Y1484339I-2578J1D01*
G02X488440Y1484767I1562J1229D01*
G02X488285Y1485504I1672J737D01*
G01Y1508415D01*
X488653Y1508783D01*
Y1511505D01*
G01X487024Y1469695D02*
X488212Y1470883D01*
G03X488399Y1471335I-453J452D01*
G01Y1482745D01*
G03X488029Y1483813I-1728J-1D01*
G02X487662Y1484424I2230J1755D01*
G02X487435Y1485505I2450J1079D01*
G01Y1507648D01*
X486283Y1508800D01*
Y1509865D01*
X486642Y1510224D01*
X487171D01*
X487472Y1509923D01*
Y1509459D01*
G01X510724Y1479395D02*
X509345Y1480774D01*
Y1481113D01*
G03X508950Y1482070I-1353J2D01*
G01X505085Y1485934D01*
G03X504033Y1486368I-1050J-1053D01*
G01X503158D01*
G02X502732Y1486545I0J601D01*
G01X500056Y1489222D01*
Y1489843D01*
X499207Y1490692D01*
X498585D01*
X497881Y1491396D01*
G02X497734Y1491751I355J355D01*
G01Y1508415D01*
X498102Y1508783D01*
Y1511505D01*
G01X507124Y1479395D02*
X508495Y1480766D01*
Y1481113D01*
G03X508348Y1481468I-502J0D01*
G01X504484Y1485332D01*
G03X504034Y1485518I-450J-451D01*
G01X503157D01*
G02X502131Y1485943I0J1451D01*
G01X497984Y1490090D01*
X497983D01*
X497279Y1490794D01*
G02X496884Y1491751I958J955D01*
G01Y1507648D01*
X495732Y1508800D01*
Y1509865D01*
X496091Y1510224D01*
X496620D01*
X496921Y1509923D01*
Y1509459D01*
G01X499672Y1544997D02*
Y1545749D01*
X499117Y1546304D01*
X498255D01*
X497755Y1545804D01*
Y1541996D01*
X498102Y1541649D01*
Y1538431D01*
G01X490223Y1544997D02*
Y1545749D01*
X489668Y1546304D01*
X488806D01*
X488306Y1545804D01*
Y1541996D01*
X488655Y1541647D01*
Y1538433D01*
X488653Y1538431D01*
G01X493378D02*
X493380Y1538433D01*
Y1541647D01*
X493100Y1541927D01*
Y1545804D01*
X493600Y1546304D01*
X494393D01*
X494947Y1545750D01*
Y1544997D01*
G01X499672Y1548397D02*
Y1547701D01*
X499125Y1547154D01*
X497902D01*
X496905Y1546157D01*
Y1541643D01*
X497252Y1541296D01*
Y1540808D01*
X496921Y1540477D01*
G01X487472D02*
X487805Y1540810D01*
Y1541294D01*
X487456Y1541643D01*
Y1546157D01*
X488453Y1547154D01*
X489676D01*
X490223Y1547701D01*
Y1548397D01*
G01X492197Y1540477D02*
X492530Y1540810D01*
Y1541294D01*
X492250Y1541574D01*
Y1546157D01*
X493247Y1547154D01*
X494401D01*
X494947Y1547700D01*
Y1548397D01*
G01X513824Y1469695D02*
X515199Y1471070D01*
Y1481246D01*
G03X515052Y1481601I-502J0D01*
G01X501999Y1494654D01*
G02X501608Y1495607I962J951D01*
G01Y1507648D01*
X500456Y1508800D01*
Y1509865D01*
X500815Y1510224D01*
X501344D01*
X501645Y1509923D01*
Y1509459D01*
G01X517424Y1469695D02*
X516049Y1471070D01*
Y1476464D01*
X516489Y1476904D01*
Y1478104D01*
X516049Y1478544D01*
Y1481246D01*
G03X515654Y1482203I-1353J2D01*
G01X502605Y1495252D01*
G02X502458Y1495607I355J355D01*
G01Y1508415D01*
X502827Y1508784D01*
Y1511505D01*
G01X524124Y1459995D02*
X522749Y1461370D01*
Y1462750D01*
G02X523494Y1464545I2539J-2D01*
G01X527160Y1468211D01*
X527782D01*
X528632Y1469061D01*
Y1469683D01*
X529085Y1470136D01*
G03X529480Y1471092I-957J955D01*
G01Y1474658D01*
G03X528945Y1475946I-1822J-2D01*
G01X508065Y1496827D01*
G02X507183Y1498953I2125J2128D01*
G01Y1508415D01*
X507551Y1508783D01*
Y1511505D01*
G01X520524Y1459995D02*
X521899Y1461370D01*
Y1462750D01*
G02X522892Y1465147I3390J0D01*
G01X528483Y1470737D01*
G03X528630Y1471092I-355J355D01*
G01Y1474657D01*
G03X528344Y1475344I-972J-2D01*
G01X507463Y1496225D01*
G02X506333Y1498953I2728J2728D01*
G01Y1507648D01*
X505181Y1508800D01*
Y1509865D01*
X505540Y1510224D01*
X506069D01*
X506370Y1509923D01*
Y1509459D01*
G01X537524Y1459995D02*
X536149Y1461370D01*
Y1462708D01*
X536150Y1462707D01*
G02X537141Y1465102I3387J1D01*
G01X539564Y1467525D01*
X540186D01*
X541036Y1468375D01*
Y1468997D01*
X541884Y1469845D01*
G03X542740Y1471914I-2068J2067D01*
G01Y1472979D01*
G03X541812Y1475222I-3171J2D01*
G01X540137Y1476897D01*
G03X538413Y1477610I-1722J-1724D01*
G01X534945D01*
G02X533301Y1478291I0J2325D01*
G01X512054Y1499538D01*
G02X511907Y1499893I355J355D01*
G01Y1508415D01*
X512275Y1508783D01*
Y1511505D01*
G01X533924Y1459995D02*
X535299Y1461370D01*
Y1462707D01*
G02X536539Y1465704I4238J2D01*
G01X541282Y1470447D01*
G03X541890Y1471914I-1466J1467D01*
G01Y1472979D01*
G03X541210Y1474620I-2320J0D01*
G01X539535Y1476295D01*
G03X538413Y1476760I-1122J-1121D01*
G01X534945D01*
G02X532699Y1477689I-2J3176D01*
G01X511452Y1498936D01*
G02X511057Y1499893I958J955D01*
G01Y1507648D01*
X509905Y1508800D01*
Y1509865D01*
X510264Y1510224D01*
X510793D01*
X511094Y1509923D01*
Y1509459D01*
G01X504396Y1544997D02*
Y1545749D01*
X503841Y1546304D01*
X502979D01*
X502479Y1545804D01*
Y1541996D01*
X502828Y1541647D01*
Y1538432D01*
X502827Y1538431D01*
G01X509120Y1544997D02*
Y1545653D01*
X508469Y1546304D01*
X507704D01*
X507204Y1545804D01*
Y1541996D01*
X507553Y1541647D01*
Y1538433D01*
X507551Y1538431D01*
G01X512275D02*
X512277Y1538433D01*
Y1541647D01*
X511962Y1541962D01*
Y1545804D01*
X512462Y1546304D01*
X513290D01*
X513844Y1545750D01*
Y1544997D01*
G01X501645Y1540477D02*
X501978Y1540810D01*
Y1541294D01*
X501629Y1541643D01*
Y1546157D01*
X502626Y1547154D01*
X503849D01*
X504396Y1547701D01*
Y1548397D01*
G01X506370Y1540477D02*
X506703Y1540810D01*
Y1541294D01*
X506354Y1541643D01*
Y1546157D01*
X507351Y1547154D01*
X508561D01*
X509120Y1547713D01*
Y1548397D01*
G01X511094Y1540477D02*
X511427Y1540810D01*
Y1541294D01*
X511112Y1541609D01*
Y1546157D01*
X512109Y1547154D01*
X513298D01*
X513844Y1547700D01*
Y1548397D01*
G01X537694Y1480582D02*
X535981Y1482295D01*
X534744D01*
X516809Y1500230D01*
G02X515782Y1502713I2484J2481D01*
G01Y1507938D01*
X516152Y1508308D01*
Y1509126D01*
X515819Y1509459D01*
G01X537694Y1484182D02*
X536885Y1483373D01*
X536335Y1483145D01*
X535097D01*
X517411Y1500831D01*
G02X516633Y1502713I1883J1880D01*
G01X516632Y1502712D01*
Y1507585D01*
X517002Y1507955D01*
Y1511503D01*
X517000Y1511505D01*
G01X537694Y1497582D02*
X536319Y1496207D01*
X529607D01*
G02X529209Y1496372I0J563D01*
G01X521725Y1503856D01*
G02X521356Y1504746I889J890D01*
G01Y1507585D01*
X521726Y1507955D01*
Y1511503D01*
X521724Y1511505D01*
G01X537694Y1493982D02*
X536319Y1495357D01*
X534501D01*
X534061Y1494917D01*
X532861D01*
X532421Y1495357D01*
X529607D01*
G02X528607Y1495770I-2J1413D01*
G01X521123Y1503254D01*
G02X520506Y1504746I1491J1490D01*
G01Y1507938D01*
X520876Y1508308D01*
Y1509126D01*
X520543Y1509459D01*
G01X518569Y1544997D02*
Y1545645D01*
X517910Y1546304D01*
X517153D01*
X516653Y1545804D01*
Y1541996D01*
X517002Y1541647D01*
Y1538433D01*
X517000Y1538431D01*
G01X523293Y1544997D02*
Y1545669D01*
X522658Y1546304D01*
X521877D01*
X521377Y1545804D01*
Y1541996D01*
X521726Y1541647D01*
Y1538433D01*
X521724Y1538431D01*
G01X515819Y1540477D02*
X516152Y1540810D01*
Y1541294D01*
X515803Y1541643D01*
Y1546157D01*
X516800Y1547154D01*
X517952D01*
X518569Y1547771D01*
Y1548397D01*
G01X520543Y1540477D02*
X520876Y1540810D01*
Y1541294D01*
X520527Y1541643D01*
Y1546157D01*
X521524Y1547154D01*
X522682D01*
X523293Y1547765D01*
Y1548397D01*
G01X571786Y1459995D02*
X570411Y1461370D01*
Y1462880D01*
G02X571138Y1464635I2482J0D01*
G01X574094Y1467591D01*
X574716D01*
X575566Y1468441D01*
Y1469063D01*
X576594Y1470091D01*
G03X577142Y1471413I-1321J1322D01*
G01Y1477179D01*
G02X577336Y1478158I2559J2D01*
G01X580698Y1486277D01*
X581700Y1487950D01*
X592066Y1500581D01*
G03X592725Y1502419I-2235J1838D01*
G01Y1508415D01*
X593093Y1508783D01*
Y1511505D01*
G01X568186Y1459995D02*
X569561Y1461370D01*
Y1462880D01*
G02X570536Y1465237I3332J2D01*
G01X574964Y1469664D01*
Y1469665D01*
X575992Y1470693D01*
G03X576292Y1471413I-718J722D01*
G01Y1477179D01*
G02X576550Y1478483I3409J3D01*
G01X579936Y1486660D01*
X581003Y1488441D01*
X591409Y1501121D01*
G03X591875Y1502420I-1578J1299D01*
G01Y1507648D01*
X590723Y1508800D01*
Y1509865D01*
X591082Y1510224D01*
X591611D01*
X591912Y1509923D01*
Y1509459D01*
G01X565086Y1469695D02*
X563711Y1471070D01*
Y1473552D01*
G02X564478Y1475401I2616J-2D01*
G01X564667Y1475590D01*
G02X566048Y1476514I3014J-3011D01*
G01X569650Y1478006D01*
G03X570128Y1478325I-563J1362D01*
G01X571288Y1479485D01*
X571910D01*
X572760Y1480335D01*
Y1480957D01*
X573276Y1481473D01*
G03X574080Y1482676I-2621J2622D01*
G01X576897Y1489480D01*
X577426Y1490360D01*
G02X578449Y1491811I10378J-6231D01*
G01X587134Y1502384D01*
G03X588001Y1504804I-2946J2421D01*
G01Y1508415D01*
X588369Y1508783D01*
Y1511505D01*
G01X561486Y1469695D02*
X562861Y1471070D01*
Y1473552D01*
G02X563876Y1476003I3467J0D01*
G01X564065Y1476192D01*
G02X565722Y1477300I3615J-3613D01*
G01X569324Y1478792D01*
G03X569526Y1478927I-238J575D01*
G01X572674Y1482075D01*
G03X573294Y1483002I-2018J2021D01*
G01X576136Y1489864D01*
X576697Y1490798D01*
G02X577791Y1492351I11110J-6664D01*
G01X586477Y1502924D01*
G03X587151Y1504805I-2289J1881D01*
G01Y1507648D01*
X585999Y1508800D01*
Y1509865D01*
X586358Y1510224D01*
X586887D01*
X587188Y1509923D01*
Y1509459D01*
G01X562448Y1483690D02*
X563909Y1482229D01*
X564240D01*
G03X567535Y1483594I0J4659D01*
G01X568819Y1484878D01*
G03X569187Y1485429I-1200J1200D01*
G01X570959Y1489711D01*
X570721Y1490285D01*
X571180Y1491395D01*
X571756Y1491633D01*
X572320Y1492997D01*
X572986Y1493994D01*
X572865Y1494605D01*
X573532Y1495603D01*
X574143Y1495725D01*
X574591Y1496395D01*
G02X575172Y1497103I3888J-2598D01*
G01X577547Y1499478D01*
X581531Y1504334D01*
X582029Y1505164D01*
X582426Y1506121D01*
Y1507648D01*
X581274Y1508800D01*
Y1509865D01*
X581633Y1510224D01*
X582162D01*
X582463Y1509923D01*
Y1509459D01*
G01X562448Y1480090D02*
X563737Y1481379D01*
X564240D01*
G03X568137Y1482992I2J5510D01*
G01X569421Y1484276D01*
G03X569973Y1485104I-1803J1800D01*
G01X573074Y1492594D01*
X573693Y1493522D01*
X573694D01*
X574850Y1495252D01*
Y1495253D01*
X575298Y1495923D01*
G02X575774Y1496501I3177J-2131D01*
G01X578178Y1498906D01*
X582228Y1503843D01*
X582791Y1504780D01*
X583276Y1505952D01*
Y1508415D01*
X583644Y1508783D01*
Y1511505D01*
G01X562448Y1501890D02*
X563816Y1503258D01*
X572364D01*
G03X573467Y1503477I0J2889D01*
G01X575849Y1504461D01*
G03X576961Y1505205I-1295J3139D01*
G01X578552Y1506802D01*
Y1508415D01*
X578920Y1508783D01*
Y1511505D01*
G01X562448Y1505490D02*
X563830Y1504108D01*
X565030D01*
X565470Y1504548D01*
X566670D01*
X567110Y1504108D01*
X568310D01*
X568750Y1504548D01*
X569950D01*
X570390Y1504108D01*
X572363D01*
G03X573142Y1504263I-1J2039D01*
G01X575525Y1505247D01*
G03X576358Y1505805I-973J2353D01*
G01X577702Y1507156D01*
Y1507648D01*
X576550Y1508800D01*
Y1509865D01*
X576909Y1510224D01*
X577438D01*
X577739Y1509923D01*
Y1509459D01*
G01X570204Y1525565D02*
X570352Y1525713D01*
X573738D01*
G01X570279Y1526835D02*
X570551Y1526563D01*
X571361D01*
X571692Y1526894D01*
G01X588286Y1469695D02*
X589661Y1471070D01*
Y1477804D01*
G02X591094Y1482527I8499J0D01*
G01X598692Y1493893D01*
G03X601324Y1502566I-12974J8673D01*
G01Y1507648D01*
X600172Y1508800D01*
Y1509865D01*
X600531Y1510224D01*
X601060D01*
X601361Y1509923D01*
Y1509459D01*
G01X585186Y1479395D02*
X583811Y1480770D01*
Y1481455D01*
X584660Y1483502D01*
X586794Y1486102D01*
X587413Y1486163D01*
X588175Y1487091D01*
X588115Y1487711D01*
X595981Y1497295D01*
G03X597450Y1502250I-7643J4961D01*
G03Y1502253I-9112J1D01*
G03Y1502257I-9112J2D01*
G01Y1508415D01*
X597818Y1508783D01*
Y1511505D01*
G01X581586Y1479395D02*
X582961Y1480770D01*
Y1481625D01*
X583923Y1483944D01*
X595293Y1497797D01*
G03X596600Y1502252I-6955J4460D01*
G01Y1507648D01*
X595448Y1508800D01*
Y1509865D01*
X595807Y1510224D01*
X596336D01*
X596637Y1509923D01*
Y1509459D01*
G01X578920Y1538431D02*
X578922Y1538433D01*
Y1541647D01*
X578485Y1542084D01*
Y1545716D01*
X579073Y1546304D01*
X579935D01*
X580489Y1545750D01*
Y1544997D01*
G01X583644Y1538431D02*
X583646Y1538433D01*
Y1541647D01*
X583297Y1541996D01*
Y1545804D01*
X583797Y1546304D01*
X584659D01*
X585213Y1545750D01*
Y1544997D01*
G01X588369Y1538431D02*
X588371Y1538433D01*
Y1541647D01*
X588022Y1541996D01*
Y1545804D01*
X588522Y1546304D01*
X589384D01*
X589938Y1545750D01*
Y1544997D01*
G01X577739Y1540477D02*
X578072Y1540810D01*
Y1541294D01*
X577635Y1541731D01*
Y1546069D01*
X578720Y1547154D01*
X579943D01*
X580489Y1547700D01*
Y1548397D01*
G01X582463Y1540477D02*
X582796Y1540810D01*
Y1541294D01*
X582447Y1541643D01*
Y1546157D01*
X583444Y1547154D01*
X584667D01*
X585213Y1547700D01*
Y1548397D01*
G01X587188Y1540477D02*
X587521Y1540810D01*
Y1541294D01*
X587172Y1541643D01*
Y1546157D01*
X588169Y1547154D01*
X589392D01*
X589938Y1547700D01*
Y1548397D01*
G01X598586Y1459995D02*
X597211Y1461370D01*
Y1462519D01*
G02X598248Y1465019I3536J-2D01*
G01X603100Y1469871D01*
G03X603980Y1471995I-2126J2125D01*
G01Y1475784D01*
X604420Y1476224D01*
Y1477424D01*
X603980Y1477864D01*
Y1488214D01*
G02X604477Y1490757I6761J-1D01*
G01X604621Y1491111D01*
G03X606898Y1502733I-28531J11624D01*
G01Y1508415D01*
X607267Y1508784D01*
Y1511505D01*
G01X594986Y1459995D02*
X596361Y1461370D01*
Y1462520D01*
G02X597646Y1465621I4387J-1D01*
G01X602498Y1470473D01*
G03X603130Y1471996I-1523J1525D01*
G01Y1488213D01*
G02X603689Y1491077I7611J1D01*
G01X603833Y1491431D01*
G03X606048Y1502734I-27743J11305D01*
G01Y1507648D01*
X604896Y1508800D01*
Y1509865D01*
X605255Y1510224D01*
X605784D01*
X606085Y1509923D01*
Y1509459D01*
G01X591886Y1469695D02*
X590511Y1471070D01*
Y1474524D01*
X590951Y1474964D01*
Y1476164D01*
X590511Y1476604D01*
Y1477804D01*
G02X591801Y1482055I7649J0D01*
G01X599399Y1493421D01*
G03X602174Y1502566I-13681J9145D01*
G01Y1508415D01*
X602542Y1508783D01*
Y1511505D01*
G01X593093Y1538431D02*
X593095Y1538433D01*
Y1541647D01*
X592798Y1541944D01*
Y1545804D01*
X593298Y1546304D01*
X594108D01*
X594662Y1545750D01*
Y1544997D01*
G01X597818Y1538431D02*
X597820Y1538433D01*
Y1541647D01*
X597471Y1541996D01*
Y1545804D01*
X597971Y1546304D01*
X598833D01*
X599387Y1545750D01*
Y1544997D01*
G01X602542Y1538431D02*
X602544Y1538433D01*
Y1541647D01*
X602195Y1541996D01*
Y1545804D01*
X602695Y1546304D01*
X603557D01*
X604111Y1545750D01*
Y1544997D01*
G01X591912Y1540477D02*
X592245Y1540810D01*
Y1541294D01*
X591948Y1541591D01*
Y1546157D01*
X592945Y1547154D01*
X594116D01*
X594662Y1547700D01*
Y1548397D01*
G01X596637Y1540477D02*
X596970Y1540810D01*
Y1541294D01*
X596621Y1541643D01*
Y1546157D01*
X597618Y1547154D01*
X598841D01*
X599387Y1547700D01*
Y1548397D01*
G01X601361Y1540477D02*
X601694Y1540810D01*
Y1541294D01*
X601345Y1541643D01*
Y1546157D01*
X602342Y1547154D01*
X603565D01*
X604111Y1547700D01*
Y1548397D01*
G01X618686Y1469695D02*
X617498Y1470883D01*
G02X617311Y1471335I453J452D01*
G01Y1475760D01*
X617751Y1476200D01*
Y1477400D01*
X617311Y1477840D01*
Y1482744D01*
G03X616759Y1484339I-2578J1D01*
G02X616502Y1484767I1562J1229D01*
G02X616347Y1485504I1672J737D01*
G01Y1508415D01*
X616715Y1508783D01*
Y1511505D01*
G01X615086Y1469695D02*
X616274Y1470883D01*
G03X616461Y1471335I-453J452D01*
G01Y1482745D01*
G03X616091Y1483813I-1728J-1D01*
G02X615724Y1484424I2230J1755D01*
G02X615497Y1485505I2450J1079D01*
G01Y1507648D01*
X614345Y1508800D01*
Y1509865D01*
X614704Y1510224D01*
X615233D01*
X615534Y1509923D01*
Y1509459D01*
G01X611986Y1479395D02*
X610797Y1480584D01*
G02X610611Y1481034I451J450D01*
G01Y1484545D01*
X611051Y1484985D01*
Y1486185D01*
X610611Y1486625D01*
Y1487825D01*
G02X611081Y1489317I2604J0D01*
G03X611553Y1490800I-2135J1496D01*
G01X611623Y1507645D01*
Y1508415D01*
X611991Y1508783D01*
Y1511505D01*
G01X608386Y1479395D02*
X609574Y1480583D01*
G03X609761Y1481035I-453J452D01*
G01Y1487826D01*
G02X610386Y1489807I3454J-1D01*
G03X610703Y1490804I-1440J1007D01*
G01X610773Y1507648D01*
X609621Y1508800D01*
Y1509865D01*
X609980Y1510224D01*
X610509D01*
X610810Y1509923D01*
Y1509459D01*
G01X607267Y1538431D02*
X607269Y1538433D01*
Y1540809D01*
X607268Y1540810D01*
Y1541647D01*
X606954Y1541961D01*
Y1545804D01*
X607454Y1546304D01*
X608282D01*
X608836Y1545750D01*
Y1544997D01*
G01X611991Y1538431D02*
X611993Y1538433D01*
Y1541647D01*
X611644Y1541996D01*
Y1545804D01*
X612144Y1546304D01*
X613006D01*
X613560Y1545750D01*
Y1544997D01*
G01X618285D02*
Y1545749D01*
X617730Y1546304D01*
X616868D01*
X616368Y1545804D01*
Y1541996D01*
X616717Y1541647D01*
Y1538433D01*
X616715Y1538431D01*
G01X606085Y1540477D02*
X606418Y1540810D01*
Y1541294D01*
X606104Y1541608D01*
Y1546157D01*
X607101Y1547154D01*
X608289D01*
X608836Y1547701D01*
Y1548397D01*
G01X610810Y1540477D02*
X611143Y1540810D01*
Y1541294D01*
X610794Y1541643D01*
Y1546157D01*
X611791Y1547154D01*
X613014D01*
X613560Y1547700D01*
Y1548397D01*
G01X615534Y1540477D02*
X615867Y1540810D01*
Y1541294D01*
X615518Y1541643D01*
Y1546157D01*
X616515Y1547154D01*
X617738D01*
X618285Y1547701D01*
Y1548397D01*
G01X625386Y1459995D02*
X624011Y1461370D01*
Y1462706D01*
G02X625005Y1465103I3391J-2D01*
G01X629584Y1469682D01*
G03X630619Y1472179I-2497J2498D01*
G01Y1476358D01*
G03X630090Y1477635I-1806J0D01*
G01X626701Y1481024D01*
Y1481646D01*
X625851Y1482496D01*
X625229D01*
X621390Y1486335D01*
G02X621072Y1487102I766J767D01*
G01Y1508415D01*
X621440Y1508783D01*
Y1511505D01*
G01X621786Y1459995D02*
X623161Y1461370D01*
Y1462707D01*
G02X624403Y1465705I4242J-1D01*
G01X628982Y1470284D01*
G03X629769Y1472179I-1894J1898D01*
G01Y1476358D01*
G03X629488Y1477033I-955J-2D01*
G01X620788Y1485733D01*
G02X620222Y1487102I1369J1367D01*
G01Y1507648D01*
X619070Y1508800D01*
Y1509865D01*
X619429Y1510224D01*
X619958D01*
X620259Y1509923D01*
Y1509459D01*
G01X638786Y1479395D02*
X637407Y1480774D01*
Y1481113D01*
G03X637012Y1482070I-1353J2D01*
G01X633147Y1485934D01*
G03X632095Y1486368I-1050J-1053D01*
G01X631220D01*
G02X630794Y1486545I0J601D01*
G01X628118Y1489222D01*
Y1489843D01*
X627269Y1490692D01*
X626647D01*
X625943Y1491396D01*
G02X625796Y1491751I355J355D01*
G01Y1508415D01*
X626164Y1508783D01*
Y1511505D01*
G01X635186Y1479395D02*
X636557Y1480766D01*
Y1481113D01*
G03X636410Y1481468I-502J0D01*
G01X632546Y1485332D01*
G03X632096Y1485518I-450J-451D01*
G01X631219D01*
G02X630193Y1485943I0J1451D01*
G01X626046Y1490090D01*
X626045D01*
X625341Y1490794D01*
G02X624946Y1491751I958J955D01*
G01Y1507648D01*
X623794Y1508800D01*
Y1509865D01*
X624153Y1510224D01*
X624682D01*
X624983Y1509923D01*
Y1509459D01*
G01X641886Y1469695D02*
X643261Y1471070D01*
Y1481246D01*
G03X643114Y1481601I-502J0D01*
G01X630061Y1494654D01*
G02X629670Y1495607I962J951D01*
G01Y1507648D01*
X628518Y1508800D01*
Y1509865D01*
X628877Y1510224D01*
X629406D01*
X629707Y1509923D01*
Y1509459D01*
G01X645486Y1469695D02*
X644111Y1471070D01*
Y1476464D01*
X644551Y1476904D01*
Y1478104D01*
X644111Y1478544D01*
Y1481246D01*
G03X643716Y1482203I-1353J2D01*
G01X630667Y1495252D01*
G02X630520Y1495607I355J355D01*
G01Y1508415D01*
X630889Y1508784D01*
Y1511505D01*
G01X648586Y1459995D02*
X649961Y1461370D01*
Y1462750D01*
G02X650954Y1465147I3390J0D01*
G01X656545Y1470737D01*
G03X656692Y1471092I-355J355D01*
G01Y1474657D01*
G03X656406Y1475344I-972J-2D01*
G01X635525Y1496225D01*
G02X634395Y1498953I2728J2728D01*
G01Y1507648D01*
X633243Y1508800D01*
Y1509865D01*
X633602Y1510224D01*
X634131D01*
X634432Y1509923D01*
Y1509459D01*
G01X627734Y1544997D02*
Y1545749D01*
X627179Y1546304D01*
X626317D01*
X625817Y1545804D01*
Y1541996D01*
X626164Y1541649D01*
Y1538431D01*
G01X632458Y1544997D02*
Y1545749D01*
X631903Y1546304D01*
X631041D01*
X630541Y1545804D01*
Y1541996D01*
X630890Y1541647D01*
Y1538432D01*
X630889Y1538431D01*
G01X621440D02*
X621442Y1538433D01*
Y1541647D01*
X621162Y1541927D01*
Y1545804D01*
X621662Y1546304D01*
X622455D01*
X623009Y1545750D01*
Y1544997D01*
G01X627734Y1548397D02*
Y1547701D01*
X627187Y1547154D01*
X625964D01*
X624967Y1546157D01*
Y1541643D01*
X625314Y1541296D01*
Y1540808D01*
X624983Y1540477D01*
G01X629707D02*
X630040Y1540810D01*
Y1541294D01*
X629691Y1541643D01*
Y1546157D01*
X630688Y1547154D01*
X631911D01*
X632458Y1547701D01*
Y1548397D01*
G01X620259Y1540477D02*
X620592Y1540810D01*
Y1541294D01*
X620312Y1541574D01*
Y1546157D01*
X621309Y1547154D01*
X622463D01*
X623009Y1547700D01*
Y1548397D01*
G01X652186Y1459995D02*
X650811Y1461370D01*
Y1462750D01*
G02X651556Y1464545I2539J-2D01*
G01X655222Y1468211D01*
X655844D01*
X656694Y1469061D01*
Y1469683D01*
X657147Y1470136D01*
G03X657542Y1471092I-957J955D01*
G01Y1474658D01*
G03X657007Y1475946I-1822J-2D01*
G01X636127Y1496827D01*
G02X635245Y1498953I2125J2128D01*
G01Y1508415D01*
X635613Y1508783D01*
Y1511505D01*
G01X665586Y1459995D02*
X664211Y1461370D01*
Y1462708D01*
X664212Y1462707D01*
G02X665203Y1465102I3387J1D01*
G01X667626Y1467525D01*
X668248D01*
X669098Y1468375D01*
Y1468997D01*
X669946Y1469845D01*
G03X670802Y1471914I-2068J2067D01*
G01Y1472979D01*
G03X669874Y1475222I-3171J2D01*
G01X668199Y1476897D01*
G03X666475Y1477610I-1722J-1724D01*
G01X663007D01*
G02X661363Y1478291I0J2325D01*
G01X640116Y1499538D01*
G02X639969Y1499893I355J355D01*
G01Y1508415D01*
X640337Y1508783D01*
Y1511505D01*
G01X661986Y1459995D02*
X663361Y1461370D01*
Y1462707D01*
G02X664601Y1465704I4238J2D01*
G01X669344Y1470447D01*
G03X669952Y1471914I-1466J1467D01*
G01Y1472979D01*
G03X669272Y1474620I-2320J0D01*
G01X667597Y1476295D01*
G03X666475Y1476760I-1122J-1121D01*
G01X663007D01*
G02X660761Y1477689I-2J3176D01*
G01X639514Y1498936D01*
G02X639119Y1499893I958J955D01*
G01Y1507648D01*
X637967Y1508800D01*
Y1509865D01*
X638326Y1510224D01*
X638855D01*
X639156Y1509923D01*
Y1509459D01*
G01X665756Y1484182D02*
X664947Y1483373D01*
X664397Y1483145D01*
X663159D01*
X645473Y1500831D01*
G02X644695Y1502713I1883J1880D01*
G01X644694Y1502712D01*
Y1507585D01*
X645064Y1507955D01*
Y1511503D01*
X645062Y1511505D01*
G01X665756Y1480582D02*
X664043Y1482295D01*
X662806D01*
X644871Y1500230D01*
G02X643844Y1502713I2484J2481D01*
G01Y1507938D01*
X644214Y1508308D01*
Y1509126D01*
X643881Y1509459D01*
G01X637182Y1544997D02*
Y1545653D01*
X636531Y1546304D01*
X635766D01*
X635266Y1545804D01*
Y1541996D01*
X635615Y1541647D01*
Y1538433D01*
X635613Y1538431D01*
G01X640337D02*
X640339Y1538433D01*
Y1541647D01*
X640024Y1541962D01*
Y1545804D01*
X640524Y1546304D01*
X641352D01*
X641906Y1545750D01*
Y1544997D01*
G01X646631D02*
Y1545645D01*
X645972Y1546304D01*
X645215D01*
X644715Y1545804D01*
Y1541996D01*
X645064Y1541647D01*
Y1538433D01*
X645062Y1538431D01*
G01X634432Y1540477D02*
X634765Y1540810D01*
Y1541294D01*
X634416Y1541643D01*
Y1546157D01*
X635413Y1547154D01*
X636623D01*
X637182Y1547713D01*
Y1548397D01*
G01X639156Y1540477D02*
X639489Y1540810D01*
Y1541294D01*
X639174Y1541609D01*
Y1546157D01*
X640171Y1547154D01*
X641360D01*
X641906Y1547700D01*
Y1548397D01*
G01X643881Y1540477D02*
X644214Y1540810D01*
Y1541294D01*
X643865Y1541643D01*
Y1546157D01*
X644862Y1547154D01*
X646014D01*
X646631Y1547771D01*
Y1548397D01*
G01X665756Y1497582D02*
X664381Y1496207D01*
X657669D01*
G02X657271Y1496372I0J563D01*
G01X649787Y1503856D01*
G02X649418Y1504746I889J890D01*
G01Y1507585D01*
X649788Y1507955D01*
Y1511503D01*
X649786Y1511505D01*
G01X665756Y1493982D02*
X664381Y1495357D01*
X662563D01*
X662123Y1494917D01*
X660923D01*
X660483Y1495357D01*
X657669D01*
G02X656669Y1495770I-2J1413D01*
G01X649185Y1503254D01*
G02X648568Y1504746I1491J1490D01*
G01Y1507938D01*
X648938Y1508308D01*
Y1509126D01*
X648605Y1509459D01*
G01X651355Y1544997D02*
Y1545669D01*
X650720Y1546304D01*
X649939D01*
X649439Y1545804D01*
Y1541996D01*
X649788Y1541647D01*
Y1538433D01*
X649786Y1538431D01*
G01X648605Y1540477D02*
X648938Y1540810D01*
Y1541294D01*
X648589Y1541643D01*
Y1546157D01*
X649586Y1547154D01*
X650744D01*
X651355Y1547765D01*
Y1548397D01*
G01X1180724Y1502695D02*
X1179349Y1504070D01*
Y1506552D01*
G02X1180116Y1508401I2616J-2D01*
G01X1180305Y1508590D01*
G02X1181686Y1509514I3014J-3011D01*
G01X1185288Y1511006D01*
G03X1185766Y1511325I-563J1362D01*
G01X1186926Y1512485D01*
X1187548D01*
X1188398Y1513335D01*
Y1513957D01*
X1188914Y1514473D01*
G03X1189718Y1515676I-2621J2622D01*
G01X1192535Y1522480D01*
X1193064Y1523360D01*
G02X1194087Y1524811I10378J-6231D01*
G01X1202772Y1535384D01*
G03X1203639Y1537804I-2946J2421D01*
G01Y1541415D01*
X1204007Y1541783D01*
Y1544505D01*
G01X1177124Y1502695D02*
X1178499Y1504070D01*
Y1506552D01*
G02X1179514Y1509003I3467J0D01*
G01X1179703Y1509192D01*
G02X1181360Y1510300I3615J-3613D01*
G01X1184962Y1511792D01*
G03X1185164Y1511927I-238J575D01*
G01X1188312Y1515075D01*
G03X1188932Y1516002I-2018J2021D01*
G01X1191774Y1522864D01*
X1192335Y1523798D01*
G02X1193429Y1525351I11110J-6664D01*
G01X1202115Y1535924D01*
G03X1202789Y1537805I-2289J1881D01*
G01Y1540648D01*
X1201637Y1541800D01*
Y1542865D01*
X1201996Y1543224D01*
X1202525D01*
X1202826Y1542923D01*
Y1542459D01*
G01X1183824Y1492995D02*
X1185199Y1494370D01*
Y1495880D01*
G02X1186174Y1498237I3332J2D01*
G01X1190602Y1502664D01*
Y1502665D01*
X1191630Y1503693D01*
G03X1191930Y1504413I-718J722D01*
G01Y1510179D01*
G02X1192188Y1511483I3409J3D01*
G01X1195574Y1519660D01*
X1196641Y1521441D01*
X1207047Y1534121D01*
G03X1207513Y1535420I-1578J1299D01*
G01Y1540648D01*
X1206361Y1541800D01*
Y1542865D01*
X1206720Y1543224D01*
X1207249D01*
X1207550Y1542923D01*
Y1542459D01*
G01X1178086Y1516690D02*
X1179547Y1515229D01*
X1179878D01*
G03X1183173Y1516594I0J4659D01*
G01X1184457Y1517878D01*
G03X1184825Y1518429I-1200J1200D01*
G01X1186597Y1522711D01*
X1186359Y1523285D01*
X1186818Y1524395D01*
X1187394Y1524633D01*
X1187958Y1525997D01*
X1188624Y1526994D01*
X1188503Y1527605D01*
X1189170Y1528603D01*
X1189781Y1528725D01*
X1190229Y1529395D01*
G02X1190810Y1530103I3888J-2598D01*
G01X1193185Y1532478D01*
X1197169Y1537334D01*
X1197667Y1538164D01*
X1198064Y1539121D01*
Y1540648D01*
X1196912Y1541800D01*
Y1542865D01*
X1197271Y1543224D01*
X1197800D01*
X1198101Y1542923D01*
Y1542459D01*
G01X1178086Y1513090D02*
X1179375Y1514379D01*
X1179878D01*
G03X1183775Y1515992I2J5510D01*
G01X1185059Y1517276D01*
G03X1185611Y1518104I-1803J1800D01*
G01X1188712Y1525594D01*
X1189331Y1526522D01*
X1189332D01*
X1190488Y1528252D01*
Y1528253D01*
X1190936Y1528923D01*
G02X1191412Y1529501I3177J-2131D01*
G01X1193816Y1531906D01*
X1197866Y1536843D01*
X1198429Y1537780D01*
X1198914Y1538952D01*
Y1541415D01*
X1199282Y1541783D01*
Y1544505D01*
G01X1178086Y1534890D02*
X1179454Y1536258D01*
X1188002D01*
G03X1189105Y1536477I0J2889D01*
G01X1191487Y1537461D01*
G03X1192599Y1538205I-1295J3139D01*
G01X1194190Y1539802D01*
Y1541415D01*
X1194558Y1541783D01*
Y1544505D01*
G01X1178086Y1538490D02*
X1179468Y1537108D01*
X1180668D01*
X1181108Y1537548D01*
X1182308D01*
X1182748Y1537108D01*
X1183948D01*
X1184388Y1537548D01*
X1185588D01*
X1186028Y1537108D01*
X1188001D01*
G03X1188780Y1537263I-1J2039D01*
G01X1191163Y1538247D01*
G03X1191996Y1538805I-973J2353D01*
G01X1193340Y1540156D01*
Y1540648D01*
X1192188Y1541800D01*
Y1542865D01*
X1192547Y1543224D01*
X1193076D01*
X1193377Y1542923D01*
Y1542459D01*
G01X1185842Y1558565D02*
X1185990Y1558713D01*
X1189376D01*
G01X1185917Y1559835D02*
X1186189Y1559563D01*
X1186999D01*
X1187330Y1559894D01*
G01X1187424Y1492995D02*
X1186049Y1494370D01*
Y1495880D01*
G02X1186776Y1497635I2482J0D01*
G01X1189732Y1500591D01*
X1190354D01*
X1191204Y1501441D01*
Y1502063D01*
X1192232Y1503091D01*
G03X1192780Y1504413I-1321J1322D01*
G01Y1510179D01*
G02X1192974Y1511158I2559J2D01*
G01X1196336Y1519277D01*
X1197338Y1520950D01*
X1207704Y1533581D01*
G03X1208363Y1535419I-2235J1838D01*
G01Y1541415D01*
X1208731Y1541783D01*
Y1544505D01*
G01X1200824Y1512395D02*
X1199449Y1513770D01*
Y1514455D01*
X1200298Y1516502D01*
X1202432Y1519102D01*
X1203051Y1519163D01*
X1203813Y1520091D01*
X1203753Y1520711D01*
X1211619Y1530295D01*
G03X1213088Y1535250I-7643J4961D01*
G03Y1535253I-9112J1D01*
G03Y1535257I-9112J2D01*
G01Y1541415D01*
X1213456Y1541783D01*
Y1544505D01*
G01X1197224Y1512395D02*
X1198599Y1513770D01*
Y1514625D01*
X1199561Y1516944D01*
X1210931Y1530797D01*
G03X1212238Y1535252I-6955J4460D01*
G01Y1540648D01*
X1211086Y1541800D01*
Y1542865D01*
X1211445Y1543224D01*
X1211974D01*
X1212275Y1542923D01*
Y1542459D01*
G01X1194558Y1571431D02*
X1194560Y1571433D01*
Y1574647D01*
X1194123Y1575084D01*
Y1578716D01*
X1194711Y1579304D01*
X1195573D01*
X1196127Y1578750D01*
Y1577997D01*
G01X1199282Y1571431D02*
X1199284Y1571433D01*
Y1574647D01*
X1198935Y1574996D01*
Y1578804D01*
X1199435Y1579304D01*
X1200297D01*
X1200851Y1578750D01*
Y1577997D01*
G01X1193377Y1573477D02*
X1193710Y1573810D01*
Y1574294D01*
X1193273Y1574731D01*
Y1579069D01*
X1194358Y1580154D01*
X1195581D01*
X1196127Y1580700D01*
Y1581397D01*
G01X1198101Y1573477D02*
X1198434Y1573810D01*
Y1574294D01*
X1198085Y1574643D01*
Y1579157D01*
X1199082Y1580154D01*
X1200305D01*
X1200851Y1580700D01*
Y1581397D01*
G01X1207524Y1502695D02*
X1206149Y1504070D01*
Y1507524D01*
X1206589Y1507964D01*
Y1509164D01*
X1206149Y1509604D01*
Y1510804D01*
G02X1207439Y1515055I7649J0D01*
G01X1215037Y1526421D01*
G03X1217812Y1535566I-13681J9145D01*
G01Y1541415D01*
X1218180Y1541783D01*
Y1544505D01*
G01X1214224Y1492995D02*
X1212849Y1494370D01*
Y1495519D01*
G02X1213886Y1498019I3536J-2D01*
G01X1218738Y1502871D01*
G03X1219618Y1504995I-2126J2125D01*
G01Y1508784D01*
X1220058Y1509224D01*
Y1510424D01*
X1219618Y1510864D01*
Y1521214D01*
G02X1220115Y1523757I6761J-1D01*
G01X1220259Y1524111D01*
G03X1222536Y1535733I-28531J11624D01*
G01Y1541415D01*
X1222905Y1541784D01*
Y1544505D01*
G01X1203924Y1502695D02*
X1205299Y1504070D01*
Y1510804D01*
G02X1206732Y1515527I8499J0D01*
G01X1214330Y1526893D01*
G03X1216962Y1535566I-12974J8673D01*
G01Y1540648D01*
X1215810Y1541800D01*
Y1542865D01*
X1216169Y1543224D01*
X1216698D01*
X1216999Y1542923D01*
Y1542459D01*
G01X1210624Y1492995D02*
X1211999Y1494370D01*
Y1495520D01*
G02X1213284Y1498621I4387J-1D01*
G01X1218136Y1503473D01*
G03X1218768Y1504996I-1523J1525D01*
G01Y1521213D01*
G02X1219327Y1524077I7611J1D01*
G01X1219471Y1524431D01*
G03X1221686Y1535734I-27743J11305D01*
G01Y1540648D01*
X1220534Y1541800D01*
Y1542865D01*
X1220893Y1543224D01*
X1221422D01*
X1221723Y1542923D01*
Y1542459D01*
G01X1204007Y1571431D02*
X1204009Y1571433D01*
Y1574647D01*
X1203660Y1574996D01*
Y1578804D01*
X1204160Y1579304D01*
X1205022D01*
X1205576Y1578750D01*
Y1577997D01*
G01X1208731Y1571431D02*
X1208733Y1571433D01*
Y1574647D01*
X1208436Y1574944D01*
Y1578804D01*
X1208936Y1579304D01*
X1209746D01*
X1210300Y1578750D01*
Y1577997D01*
G01X1213456Y1571431D02*
X1213458Y1571433D01*
Y1574647D01*
X1213109Y1574996D01*
Y1578804D01*
X1213609Y1579304D01*
X1214471D01*
X1215025Y1578750D01*
Y1577997D01*
G01X1202826Y1573477D02*
X1203159Y1573810D01*
Y1574294D01*
X1202810Y1574643D01*
Y1579157D01*
X1203807Y1580154D01*
X1205030D01*
X1205576Y1580700D01*
Y1581397D01*
G01X1207550Y1573477D02*
X1207883Y1573810D01*
Y1574294D01*
X1207586Y1574591D01*
Y1579157D01*
X1208583Y1580154D01*
X1209754D01*
X1210300Y1580700D01*
Y1581397D01*
G01X1212275Y1573477D02*
X1212608Y1573810D01*
Y1574294D01*
X1212259Y1574643D01*
Y1579157D01*
X1213256Y1580154D01*
X1214479D01*
X1215025Y1580700D01*
Y1581397D01*
G01X1227624Y1512395D02*
X1226435Y1513584D01*
G02X1226249Y1514034I451J450D01*
G01Y1517545D01*
X1226689Y1517985D01*
Y1519185D01*
X1226249Y1519625D01*
Y1520825D01*
G02X1226719Y1522317I2604J0D01*
G03X1227191Y1523800I-2135J1496D01*
G01X1227261Y1540645D01*
Y1541415D01*
X1227629Y1541783D01*
Y1544505D01*
G01X1224024Y1512395D02*
X1225212Y1513583D01*
G03X1225399Y1514035I-453J452D01*
G01Y1520826D01*
G02X1226024Y1522807I3454J-1D01*
G03X1226341Y1523804I-1440J1007D01*
G01X1226411Y1540648D01*
X1225259Y1541800D01*
Y1542865D01*
X1225618Y1543224D01*
X1226147D01*
X1226448Y1542923D01*
Y1542459D01*
G01X1218180Y1571431D02*
X1218182Y1571433D01*
Y1574647D01*
X1217833Y1574996D01*
Y1578804D01*
X1218333Y1579304D01*
X1219195D01*
X1219749Y1578750D01*
Y1577997D01*
G01X1222905Y1571431D02*
X1222907Y1571433D01*
Y1573809D01*
X1222906Y1573810D01*
Y1574647D01*
X1222592Y1574961D01*
Y1578804D01*
X1223092Y1579304D01*
X1223920D01*
X1224474Y1578750D01*
Y1577997D01*
G01X1227629Y1571431D02*
X1227631Y1571433D01*
Y1574647D01*
X1227282Y1574996D01*
Y1578804D01*
X1227782Y1579304D01*
X1228644D01*
X1229198Y1578750D01*
Y1577997D01*
G01X1216999Y1573477D02*
X1217332Y1573810D01*
Y1574294D01*
X1216983Y1574643D01*
Y1579157D01*
X1217980Y1580154D01*
X1219203D01*
X1219749Y1580700D01*
Y1581397D01*
G01X1221723Y1573477D02*
X1222056Y1573810D01*
Y1574294D01*
X1221742Y1574608D01*
Y1579157D01*
X1222739Y1580154D01*
X1223927D01*
X1224474Y1580701D01*
Y1581397D01*
G01X1226448Y1573477D02*
X1226781Y1573810D01*
Y1574294D01*
X1226432Y1574643D01*
Y1579157D01*
X1227429Y1580154D01*
X1228652D01*
X1229198Y1580700D01*
Y1581397D01*
G01X1234324Y1502695D02*
X1233136Y1503883D01*
G02X1232949Y1504335I453J452D01*
G01Y1508760D01*
X1233389Y1509200D01*
Y1510400D01*
X1232949Y1510840D01*
Y1515744D01*
G03X1232397Y1517339I-2578J1D01*
G02X1232140Y1517767I1562J1229D01*
G02X1231985Y1518504I1672J737D01*
G01Y1541415D01*
X1232353Y1541783D01*
Y1544505D01*
G01X1241024Y1492995D02*
X1239649Y1494370D01*
Y1495706D01*
G02X1240643Y1498103I3391J-2D01*
G01X1245222Y1502682D01*
G03X1246257Y1505179I-2497J2498D01*
G01Y1509358D01*
G03X1245728Y1510635I-1806J0D01*
G01X1242339Y1514024D01*
Y1514646D01*
X1241489Y1515496D01*
X1240867D01*
X1237028Y1519335D01*
G02X1236710Y1520102I766J767D01*
G01Y1541415D01*
X1237078Y1541783D01*
Y1544505D01*
G01X1230724Y1502695D02*
X1231912Y1503883D01*
G03X1232099Y1504335I-453J452D01*
G01Y1515745D01*
G03X1231729Y1516813I-1728J-1D01*
G02X1231362Y1517424I2230J1755D01*
G02X1231135Y1518505I2450J1079D01*
G01Y1540648D01*
X1229983Y1541800D01*
Y1542865D01*
X1230342Y1543224D01*
X1230871D01*
X1231172Y1542923D01*
Y1542459D01*
G01X1237424Y1492995D02*
X1238799Y1494370D01*
Y1495707D01*
G02X1240041Y1498705I4242J-1D01*
G01X1244620Y1503284D01*
G03X1245407Y1505179I-1894J1898D01*
G01Y1509358D01*
G03X1245126Y1510033I-955J-2D01*
G01X1236426Y1518733D01*
G02X1235860Y1520102I1369J1367D01*
G01Y1540648D01*
X1234708Y1541800D01*
Y1542865D01*
X1235067Y1543224D01*
X1235596D01*
X1235897Y1542923D01*
Y1542459D01*
G01X1254424Y1512395D02*
X1253045Y1513774D01*
Y1514113D01*
G03X1252650Y1515070I-1353J2D01*
G01X1248785Y1518934D01*
G03X1247733Y1519368I-1050J-1053D01*
G01X1246858D01*
G02X1246432Y1519545I0J601D01*
G01X1243756Y1522222D01*
Y1522843D01*
X1242907Y1523692D01*
X1242285D01*
X1241581Y1524396D01*
G02X1241434Y1524751I355J355D01*
G01Y1541415D01*
X1241802Y1541783D01*
Y1544505D01*
G01X1250824Y1512395D02*
X1252195Y1513766D01*
Y1514113D01*
G03X1252048Y1514468I-502J0D01*
G01X1248184Y1518332D01*
G03X1247734Y1518518I-450J-451D01*
G01X1246857D01*
G02X1245831Y1518943I0J1451D01*
G01X1241684Y1523090D01*
X1241683D01*
X1240979Y1523794D01*
G02X1240584Y1524751I958J955D01*
G01Y1540648D01*
X1239432Y1541800D01*
Y1542865D01*
X1239791Y1543224D01*
X1240320D01*
X1240621Y1542923D01*
Y1542459D01*
G01X1257524Y1502695D02*
X1258899Y1504070D01*
Y1514246D01*
G03X1258752Y1514601I-502J0D01*
G01X1245699Y1527654D01*
G02X1245308Y1528607I962J951D01*
G01Y1540648D01*
X1244156Y1541800D01*
Y1542865D01*
X1244515Y1543224D01*
X1245044D01*
X1245345Y1542923D01*
Y1542459D01*
G01X1243372Y1577997D02*
Y1578749D01*
X1242817Y1579304D01*
X1241955D01*
X1241455Y1578804D01*
Y1574996D01*
X1241802Y1574649D01*
Y1571431D01*
G01X1233923Y1577997D02*
Y1578749D01*
X1233368Y1579304D01*
X1232506D01*
X1232006Y1578804D01*
Y1574996D01*
X1232355Y1574647D01*
Y1571433D01*
X1232353Y1571431D01*
G01X1237078D02*
X1237080Y1571433D01*
Y1574647D01*
X1236800Y1574927D01*
Y1578804D01*
X1237300Y1579304D01*
X1238093D01*
X1238647Y1578750D01*
Y1577997D01*
G01X1243372Y1581397D02*
Y1580701D01*
X1242825Y1580154D01*
X1241602D01*
X1240605Y1579157D01*
Y1574643D01*
X1240952Y1574296D01*
Y1573808D01*
X1240621Y1573477D01*
G01X1231172D02*
X1231505Y1573810D01*
Y1574294D01*
X1231156Y1574643D01*
Y1579157D01*
X1232153Y1580154D01*
X1233376D01*
X1233923Y1580701D01*
Y1581397D01*
G01X1235897Y1573477D02*
X1236230Y1573810D01*
Y1574294D01*
X1235950Y1574574D01*
Y1579157D01*
X1236947Y1580154D01*
X1238101D01*
X1238647Y1580700D01*
Y1581397D01*
G01X1261124Y1502695D02*
X1259749Y1504070D01*
Y1509464D01*
X1260189Y1509904D01*
Y1511104D01*
X1259749Y1511544D01*
Y1514246D01*
G03X1259354Y1515203I-1353J2D01*
G01X1246305Y1528252D01*
G02X1246158Y1528607I355J355D01*
G01Y1541415D01*
X1246527Y1541784D01*
Y1544505D01*
G01X1264224Y1492995D02*
X1265599Y1494370D01*
Y1495750D01*
G02X1266592Y1498147I3390J0D01*
G01X1272183Y1503737D01*
G03X1272330Y1504092I-355J355D01*
G01Y1507657D01*
G03X1272044Y1508344I-972J-2D01*
G01X1251163Y1529225D01*
G02X1250033Y1531953I2728J2728D01*
G01Y1540648D01*
X1248881Y1541800D01*
Y1542865D01*
X1249240Y1543224D01*
X1249769D01*
X1250070Y1542923D01*
Y1542459D01*
G01X1267824Y1492995D02*
X1266449Y1494370D01*
Y1495750D01*
G02X1267194Y1497545I2539J-2D01*
G01X1270860Y1501211D01*
X1271482D01*
X1272332Y1502061D01*
Y1502683D01*
X1272785Y1503136D01*
G03X1273180Y1504092I-957J955D01*
G01Y1507658D01*
G03X1272645Y1508946I-1822J-2D01*
G01X1251765Y1529827D01*
G02X1250883Y1531953I2125J2128D01*
G01Y1541415D01*
X1251251Y1541783D01*
Y1544505D01*
G01X1277624Y1492995D02*
X1278999Y1494370D01*
Y1495707D01*
G02X1280239Y1498704I4238J2D01*
G01X1284982Y1503447D01*
G03X1285590Y1504914I-1466J1467D01*
G01Y1505979D01*
G03X1284910Y1507620I-2320J0D01*
G01X1283235Y1509295D01*
G03X1282113Y1509760I-1122J-1121D01*
G01X1278645D01*
G02X1276399Y1510689I-2J3176D01*
G01X1255152Y1531936D01*
G02X1254757Y1532893I958J955D01*
G01Y1540648D01*
X1253605Y1541800D01*
Y1542865D01*
X1253964Y1543224D01*
X1254493D01*
X1254794Y1542923D01*
Y1542459D01*
G01X1281224Y1492995D02*
X1279849Y1494370D01*
Y1495708D01*
X1279850Y1495707D01*
G02X1280841Y1498102I3387J1D01*
G01X1283264Y1500525D01*
X1283886D01*
X1284736Y1501375D01*
Y1501997D01*
X1285584Y1502845D01*
G03X1286440Y1504914I-2068J2067D01*
G01Y1505979D01*
G03X1285512Y1508222I-3171J2D01*
G01X1283837Y1509897D01*
G03X1282113Y1510610I-1722J-1724D01*
G01X1278645D01*
G02X1277001Y1511291I0J2325D01*
G01X1255754Y1532538D01*
G02X1255607Y1532893I355J355D01*
G01Y1541415D01*
X1255975Y1541783D01*
Y1544505D01*
G01X1248096Y1577997D02*
Y1578749D01*
X1247541Y1579304D01*
X1246679D01*
X1246179Y1578804D01*
Y1574996D01*
X1246528Y1574647D01*
Y1571432D01*
X1246527Y1571431D01*
G01X1252820Y1577997D02*
Y1578653D01*
X1252169Y1579304D01*
X1251404D01*
X1250904Y1578804D01*
Y1574996D01*
X1251253Y1574647D01*
Y1571433D01*
X1251251Y1571431D01*
G01X1255975D02*
X1255977Y1571433D01*
Y1574647D01*
X1255662Y1574962D01*
Y1578804D01*
X1256162Y1579304D01*
X1256990D01*
X1257544Y1578750D01*
Y1577997D01*
G01X1245345Y1573477D02*
X1245678Y1573810D01*
Y1574294D01*
X1245329Y1574643D01*
Y1579157D01*
X1246326Y1580154D01*
X1247549D01*
X1248096Y1580701D01*
Y1581397D01*
G01X1250070Y1573477D02*
X1250403Y1573810D01*
Y1574294D01*
X1250054Y1574643D01*
Y1579157D01*
X1251051Y1580154D01*
X1252261D01*
X1252820Y1580713D01*
Y1581397D01*
G01X1254794Y1573477D02*
X1255127Y1573810D01*
Y1574294D01*
X1254812Y1574609D01*
Y1579157D01*
X1255809Y1580154D01*
X1256998D01*
X1257544Y1580700D01*
Y1581397D01*
G01X1281394Y1517182D02*
X1280585Y1516373D01*
X1280035Y1516145D01*
X1278797D01*
X1261111Y1533831D01*
G02X1260333Y1535713I1883J1880D01*
G01X1260332Y1535712D01*
Y1540585D01*
X1260702Y1540955D01*
Y1544503D01*
X1260700Y1544505D01*
G01X1281394Y1513582D02*
X1279681Y1515295D01*
X1278444D01*
X1260509Y1533230D01*
G02X1259482Y1535713I2484J2481D01*
G01Y1540938D01*
X1259852Y1541308D01*
Y1542126D01*
X1259519Y1542459D01*
G01X1281394Y1530582D02*
X1280019Y1529207D01*
X1273307D01*
G02X1272909Y1529372I0J563D01*
G01X1265425Y1536856D01*
G02X1265056Y1537746I889J890D01*
G01Y1540585D01*
X1265426Y1540955D01*
Y1544503D01*
X1265424Y1544505D01*
G01X1281394Y1526982D02*
X1280019Y1528357D01*
X1278201D01*
X1277761Y1527917D01*
X1276561D01*
X1276121Y1528357D01*
X1273307D01*
G02X1272307Y1528770I-2J1413D01*
G01X1264823Y1536254D01*
G02X1264206Y1537746I1491J1490D01*
G01Y1540938D01*
X1264576Y1541308D01*
Y1542126D01*
X1264243Y1542459D01*
G01X1262269Y1577997D02*
Y1578645D01*
X1261610Y1579304D01*
X1260853D01*
X1260353Y1578804D01*
Y1574996D01*
X1260702Y1574647D01*
Y1571433D01*
X1260700Y1571431D01*
G01X1266993Y1577997D02*
Y1578669D01*
X1266358Y1579304D01*
X1265577D01*
X1265077Y1578804D01*
Y1574996D01*
X1265426Y1574647D01*
Y1571433D01*
X1265424Y1571431D01*
G01X1259519Y1573477D02*
X1259852Y1573810D01*
Y1574294D01*
X1259503Y1574643D01*
Y1579157D01*
X1260500Y1580154D01*
X1261652D01*
X1262269Y1580771D01*
Y1581397D01*
G01X1264243Y1573477D02*
X1264576Y1573810D01*
Y1574294D01*
X1264227Y1574643D01*
Y1579157D01*
X1265224Y1580154D01*
X1266382D01*
X1266993Y1580765D01*
Y1581397D01*
G01X1308786Y1502695D02*
X1307411Y1504070D01*
Y1506552D01*
G02X1308178Y1508401I2616J-2D01*
G01X1308367Y1508590D01*
G02X1309748Y1509514I3014J-3011D01*
G01X1313350Y1511006D01*
G03X1313828Y1511325I-563J1362D01*
G01X1314988Y1512485D01*
X1315610D01*
X1316460Y1513335D01*
Y1513957D01*
X1316976Y1514473D01*
G03X1317780Y1515676I-2621J2622D01*
G01X1320597Y1522480D01*
X1321126Y1523360D01*
G02X1322149Y1524811I10378J-6231D01*
G01X1330834Y1535384D01*
G03X1331701Y1537804I-2946J2421D01*
G01Y1541415D01*
X1332069Y1541783D01*
Y1544505D01*
G01X1315486Y1492995D02*
X1314111Y1494370D01*
Y1495880D01*
G02X1314838Y1497635I2482J0D01*
G01X1317794Y1500591D01*
X1318416D01*
X1319266Y1501441D01*
Y1502063D01*
X1320294Y1503091D01*
G03X1320842Y1504413I-1321J1322D01*
G01Y1510179D01*
G02X1321036Y1511158I2559J2D01*
G01X1324398Y1519277D01*
X1325400Y1520950D01*
X1335766Y1533581D01*
G03X1336425Y1535419I-2235J1838D01*
G01Y1541415D01*
X1336793Y1541783D01*
Y1544505D01*
G01X1305186Y1502695D02*
X1306561Y1504070D01*
Y1506552D01*
G02X1307576Y1509003I3467J0D01*
G01X1307765Y1509192D01*
G02X1309422Y1510300I3615J-3613D01*
G01X1313024Y1511792D01*
G03X1313226Y1511927I-238J575D01*
G01X1316374Y1515075D01*
G03X1316994Y1516002I-2018J2021D01*
G01X1319836Y1522864D01*
X1320397Y1523798D01*
G02X1321491Y1525351I11110J-6664D01*
G01X1330177Y1535924D01*
G03X1330851Y1537805I-2289J1881D01*
G01Y1540648D01*
X1329699Y1541800D01*
Y1542865D01*
X1330058Y1543224D01*
X1330587D01*
X1330888Y1542923D01*
Y1542459D01*
G01X1311886Y1492995D02*
X1313261Y1494370D01*
Y1495880D01*
G02X1314236Y1498237I3332J2D01*
G01X1318664Y1502664D01*
Y1502665D01*
X1319692Y1503693D01*
G03X1319992Y1504413I-718J722D01*
G01Y1510179D01*
G02X1320250Y1511483I3409J3D01*
G01X1323636Y1519660D01*
X1324703Y1521441D01*
X1335109Y1534121D01*
G03X1335575Y1535420I-1578J1299D01*
G01Y1540648D01*
X1334423Y1541800D01*
Y1542865D01*
X1334782Y1543224D01*
X1335311D01*
X1335612Y1542923D01*
Y1542459D01*
G01X1306148Y1516690D02*
X1307609Y1515229D01*
X1307940D01*
G03X1311235Y1516594I0J4659D01*
G01X1312519Y1517878D01*
G03X1312887Y1518429I-1200J1200D01*
G01X1314659Y1522711D01*
X1314421Y1523285D01*
X1314880Y1524395D01*
X1315456Y1524633D01*
X1316020Y1525997D01*
X1316686Y1526994D01*
X1316565Y1527605D01*
X1317232Y1528603D01*
X1317843Y1528725D01*
X1318291Y1529395D01*
G02X1318872Y1530103I3888J-2598D01*
G01X1321247Y1532478D01*
X1325231Y1537334D01*
X1325729Y1538164D01*
X1326126Y1539121D01*
Y1540648D01*
X1324974Y1541800D01*
Y1542865D01*
X1325333Y1543224D01*
X1325862D01*
X1326163Y1542923D01*
Y1542459D01*
G01X1306148Y1513090D02*
X1307437Y1514379D01*
X1307940D01*
G03X1311837Y1515992I2J5510D01*
G01X1313121Y1517276D01*
G03X1313673Y1518104I-1803J1800D01*
G01X1316774Y1525594D01*
X1317393Y1526522D01*
X1317394D01*
X1318550Y1528252D01*
Y1528253D01*
X1318998Y1528923D01*
G02X1319474Y1529501I3177J-2131D01*
G01X1321878Y1531906D01*
X1325928Y1536843D01*
X1326491Y1537780D01*
X1326976Y1538952D01*
Y1541415D01*
X1327344Y1541783D01*
Y1544505D01*
G01X1306148Y1534890D02*
X1307516Y1536258D01*
X1316064D01*
G03X1317167Y1536477I0J2889D01*
G01X1319549Y1537461D01*
G03X1320661Y1538205I-1295J3139D01*
G01X1322252Y1539802D01*
Y1541415D01*
X1322620Y1541783D01*
Y1544505D01*
G01X1306148Y1538490D02*
X1307530Y1537108D01*
X1308730D01*
X1309170Y1537548D01*
X1310370D01*
X1310810Y1537108D01*
X1312010D01*
X1312450Y1537548D01*
X1313650D01*
X1314090Y1537108D01*
X1316063D01*
G03X1316842Y1537263I-1J2039D01*
G01X1319225Y1538247D01*
G03X1320058Y1538805I-973J2353D01*
G01X1321402Y1540156D01*
Y1540648D01*
X1320250Y1541800D01*
Y1542865D01*
X1320609Y1543224D01*
X1321138D01*
X1321439Y1542923D01*
Y1542459D01*
G01X1313904Y1558565D02*
X1314052Y1558713D01*
X1317438D01*
G01X1313979Y1559835D02*
X1314251Y1559563D01*
X1315061D01*
X1315392Y1559894D01*
G01X1331986Y1502695D02*
X1333361Y1504070D01*
Y1510804D01*
G02X1334794Y1515527I8499J0D01*
G01X1342392Y1526893D01*
G03X1345024Y1535566I-12974J8673D01*
G01Y1540648D01*
X1343872Y1541800D01*
Y1542865D01*
X1344231Y1543224D01*
X1344760D01*
X1345061Y1542923D01*
Y1542459D01*
G01X1328886Y1512395D02*
X1327511Y1513770D01*
Y1514455D01*
X1328360Y1516502D01*
X1330494Y1519102D01*
X1331113Y1519163D01*
X1331875Y1520091D01*
X1331815Y1520711D01*
X1339681Y1530295D01*
G03X1341150Y1535250I-7643J4961D01*
G03Y1535253I-9112J1D01*
G03Y1535257I-9112J2D01*
G01Y1541415D01*
X1341518Y1541783D01*
Y1544505D01*
G01X1325286Y1512395D02*
X1326661Y1513770D01*
Y1514625D01*
X1327623Y1516944D01*
X1338993Y1530797D01*
G03X1340300Y1535252I-6955J4460D01*
G01Y1540648D01*
X1339148Y1541800D01*
Y1542865D01*
X1339507Y1543224D01*
X1340036D01*
X1340337Y1542923D01*
Y1542459D01*
G01X1322620Y1571431D02*
X1322622Y1571433D01*
Y1574647D01*
X1322185Y1575084D01*
Y1578716D01*
X1322773Y1579304D01*
X1323635D01*
X1324189Y1578750D01*
Y1577997D01*
G01X1327344Y1571431D02*
X1327346Y1571433D01*
Y1574647D01*
X1326997Y1574996D01*
Y1578804D01*
X1327497Y1579304D01*
X1328359D01*
X1328913Y1578750D01*
Y1577997D01*
G01X1332069Y1571431D02*
X1332071Y1571433D01*
Y1574647D01*
X1331722Y1574996D01*
Y1578804D01*
X1332222Y1579304D01*
X1333084D01*
X1333638Y1578750D01*
Y1577997D01*
G01X1321439Y1573477D02*
X1321772Y1573810D01*
Y1574294D01*
X1321335Y1574731D01*
Y1579069D01*
X1322420Y1580154D01*
X1323643D01*
X1324189Y1580700D01*
Y1581397D01*
G01X1326163Y1573477D02*
X1326496Y1573810D01*
Y1574294D01*
X1326147Y1574643D01*
Y1579157D01*
X1327144Y1580154D01*
X1328367D01*
X1328913Y1580700D01*
Y1581397D01*
G01X1330888Y1573477D02*
X1331221Y1573810D01*
Y1574294D01*
X1330872Y1574643D01*
Y1579157D01*
X1331869Y1580154D01*
X1333092D01*
X1333638Y1580700D01*
Y1581397D01*
G01X1335586Y1502695D02*
X1334211Y1504070D01*
Y1507524D01*
X1334651Y1507964D01*
Y1509164D01*
X1334211Y1509604D01*
Y1510804D01*
G02X1335501Y1515055I7649J0D01*
G01X1343099Y1526421D01*
G03X1345874Y1535566I-13681J9145D01*
G01Y1541415D01*
X1346242Y1541783D01*
Y1544505D01*
G01X1342286Y1492995D02*
X1340911Y1494370D01*
Y1495519D01*
G02X1341948Y1498019I3536J-2D01*
G01X1346800Y1502871D01*
G03X1347680Y1504995I-2126J2125D01*
G01Y1508784D01*
X1348120Y1509224D01*
Y1510424D01*
X1347680Y1510864D01*
Y1521214D01*
G02X1348177Y1523757I6761J-1D01*
G01X1348321Y1524111D01*
G03X1350598Y1535733I-28531J11624D01*
G01Y1541415D01*
X1350967Y1541784D01*
Y1544505D01*
G01X1338686Y1492995D02*
X1340061Y1494370D01*
Y1495520D01*
G02X1341346Y1498621I4387J-1D01*
G01X1346198Y1503473D01*
G03X1346830Y1504996I-1523J1525D01*
G01Y1521213D01*
G02X1347389Y1524077I7611J1D01*
G01X1347533Y1524431D01*
G03X1349748Y1535734I-27743J11305D01*
G01Y1540648D01*
X1348596Y1541800D01*
Y1542865D01*
X1348955Y1543224D01*
X1349484D01*
X1349785Y1542923D01*
Y1542459D01*
G01X1336793Y1571431D02*
X1336795Y1571433D01*
Y1574647D01*
X1336498Y1574944D01*
Y1578804D01*
X1336998Y1579304D01*
X1337808D01*
X1338362Y1578750D01*
Y1577997D01*
G01X1341518Y1571431D02*
X1341520Y1571433D01*
Y1574647D01*
X1341171Y1574996D01*
Y1578804D01*
X1341671Y1579304D01*
X1342533D01*
X1343087Y1578750D01*
Y1577997D01*
G01X1346242Y1571431D02*
X1346244Y1571433D01*
Y1574647D01*
X1345895Y1574996D01*
Y1578804D01*
X1346395Y1579304D01*
X1347257D01*
X1347811Y1578750D01*
Y1577997D01*
G01X1335612Y1573477D02*
X1335945Y1573810D01*
Y1574294D01*
X1335648Y1574591D01*
Y1579157D01*
X1336645Y1580154D01*
X1337816D01*
X1338362Y1580700D01*
Y1581397D01*
G01X1340337Y1573477D02*
X1340670Y1573810D01*
Y1574294D01*
X1340321Y1574643D01*
Y1579157D01*
X1341318Y1580154D01*
X1342541D01*
X1343087Y1580700D01*
Y1581397D01*
G01X1345061Y1573477D02*
X1345394Y1573810D01*
Y1574294D01*
X1345045Y1574643D01*
Y1579157D01*
X1346042Y1580154D01*
X1347265D01*
X1347811Y1580700D01*
Y1581397D01*
G01X1362386Y1502695D02*
X1361198Y1503883D01*
G02X1361011Y1504335I453J452D01*
G01Y1508760D01*
X1361451Y1509200D01*
Y1510400D01*
X1361011Y1510840D01*
Y1515744D01*
G03X1360459Y1517339I-2578J1D01*
G02X1360202Y1517767I1562J1229D01*
G02X1360047Y1518504I1672J737D01*
G01Y1541415D01*
X1360415Y1541783D01*
Y1544505D01*
G01X1358786Y1502695D02*
X1359974Y1503883D01*
G03X1360161Y1504335I-453J452D01*
G01Y1515745D01*
G03X1359791Y1516813I-1728J-1D01*
G02X1359424Y1517424I2230J1755D01*
G02X1359197Y1518505I2450J1079D01*
G01Y1540648D01*
X1358045Y1541800D01*
Y1542865D01*
X1358404Y1543224D01*
X1358933D01*
X1359234Y1542923D01*
Y1542459D01*
G01X1355686Y1512395D02*
X1354497Y1513584D01*
G02X1354311Y1514034I451J450D01*
G01Y1517545D01*
X1354751Y1517985D01*
Y1519185D01*
X1354311Y1519625D01*
Y1520825D01*
G02X1354781Y1522317I2604J0D01*
G03X1355253Y1523800I-2135J1496D01*
G01X1355323Y1540645D01*
Y1541415D01*
X1355691Y1541783D01*
Y1544505D01*
G01X1352086Y1512395D02*
X1353274Y1513583D01*
G03X1353461Y1514035I-453J452D01*
G01Y1520826D01*
G02X1354086Y1522807I3454J-1D01*
G03X1354403Y1523804I-1440J1007D01*
G01X1354473Y1540648D01*
X1353321Y1541800D01*
Y1542865D01*
X1353680Y1543224D01*
X1354209D01*
X1354510Y1542923D01*
Y1542459D01*
G01X1365486Y1492995D02*
X1366861Y1494370D01*
Y1495707D01*
G02X1368103Y1498705I4242J-1D01*
G01X1372682Y1503284D01*
G03X1373469Y1505179I-1894J1898D01*
G01Y1509358D01*
G03X1373188Y1510033I-955J-2D01*
G01X1364488Y1518733D01*
G02X1363922Y1520102I1369J1367D01*
G01Y1540648D01*
X1362770Y1541800D01*
Y1542865D01*
X1363129Y1543224D01*
X1363658D01*
X1363959Y1542923D01*
Y1542459D01*
G01X1350967Y1571431D02*
X1350969Y1571433D01*
Y1573809D01*
X1350968Y1573810D01*
Y1574647D01*
X1350654Y1574961D01*
Y1578804D01*
X1351154Y1579304D01*
X1351982D01*
X1352536Y1578750D01*
Y1577997D01*
G01X1355691Y1571431D02*
X1355693Y1571433D01*
Y1574647D01*
X1355344Y1574996D01*
Y1578804D01*
X1355844Y1579304D01*
X1356706D01*
X1357260Y1578750D01*
Y1577997D01*
G01X1361985D02*
Y1578749D01*
X1361430Y1579304D01*
X1360568D01*
X1360068Y1578804D01*
Y1574996D01*
X1360417Y1574647D01*
Y1571433D01*
X1360415Y1571431D01*
G01X1349785Y1573477D02*
X1350118Y1573810D01*
Y1574294D01*
X1349804Y1574608D01*
Y1579157D01*
X1350801Y1580154D01*
X1351989D01*
X1352536Y1580701D01*
Y1581397D01*
G01X1354510Y1573477D02*
X1354843Y1573810D01*
Y1574294D01*
X1354494Y1574643D01*
Y1579157D01*
X1355491Y1580154D01*
X1356714D01*
X1357260Y1580700D01*
Y1581397D01*
G01X1359234Y1573477D02*
X1359567Y1573810D01*
Y1574294D01*
X1359218Y1574643D01*
Y1579157D01*
X1360215Y1580154D01*
X1361438D01*
X1361985Y1580701D01*
Y1581397D01*
G01X1369086Y1492995D02*
X1367711Y1494370D01*
Y1495706D01*
G02X1368705Y1498103I3391J-2D01*
G01X1373284Y1502682D01*
G03X1374319Y1505179I-2497J2498D01*
G01Y1509358D01*
G03X1373790Y1510635I-1806J0D01*
G01X1370401Y1514024D01*
Y1514646D01*
X1369551Y1515496D01*
X1368929D01*
X1365090Y1519335D01*
G02X1364772Y1520102I766J767D01*
G01Y1541415D01*
X1365140Y1541783D01*
Y1544505D01*
G01X1382486Y1512395D02*
X1381107Y1513774D01*
Y1514113D01*
G03X1380712Y1515070I-1353J2D01*
G01X1376847Y1518934D01*
G03X1375795Y1519368I-1050J-1053D01*
G01X1374920D01*
G02X1374494Y1519545I0J601D01*
G01X1371818Y1522222D01*
Y1522843D01*
X1370969Y1523692D01*
X1370347D01*
X1369643Y1524396D01*
G02X1369496Y1524751I355J355D01*
G01Y1541415D01*
X1369864Y1541783D01*
Y1544505D01*
G01X1378886Y1512395D02*
X1380257Y1513766D01*
Y1514113D01*
G03X1380110Y1514468I-502J0D01*
G01X1376246Y1518332D01*
G03X1375796Y1518518I-450J-451D01*
G01X1374919D01*
G02X1373893Y1518943I0J1451D01*
G01X1369746Y1523090D01*
X1369745D01*
X1369041Y1523794D01*
G02X1368646Y1524751I958J955D01*
G01Y1540648D01*
X1367494Y1541800D01*
Y1542865D01*
X1367853Y1543224D01*
X1368382D01*
X1368683Y1542923D01*
Y1542459D01*
G01X1389186Y1502695D02*
X1387811Y1504070D01*
Y1509464D01*
X1388251Y1509904D01*
Y1511104D01*
X1387811Y1511544D01*
Y1514246D01*
G03X1387416Y1515203I-1353J2D01*
G01X1374367Y1528252D01*
G02X1374220Y1528607I355J355D01*
G01Y1541415D01*
X1374589Y1541784D01*
Y1544505D01*
G01X1385586Y1502695D02*
X1386961Y1504070D01*
Y1514246D01*
G03X1386814Y1514601I-502J0D01*
G01X1373761Y1527654D01*
G02X1373370Y1528607I962J951D01*
G01Y1540648D01*
X1372218Y1541800D01*
Y1542865D01*
X1372577Y1543224D01*
X1373106D01*
X1373407Y1542923D01*
Y1542459D01*
G01X1392286Y1492995D02*
X1393661Y1494370D01*
Y1495750D01*
G02X1394654Y1498147I3390J0D01*
G01X1400245Y1503737D01*
G03X1400392Y1504092I-355J355D01*
G01Y1507657D01*
G03X1400106Y1508344I-972J-2D01*
G01X1379225Y1529225D01*
G02X1378095Y1531953I2728J2728D01*
G01Y1540648D01*
X1376943Y1541800D01*
Y1542865D01*
X1377302Y1543224D01*
X1377831D01*
X1378132Y1542923D01*
Y1542459D01*
G01X1371434Y1577997D02*
Y1578749D01*
X1370879Y1579304D01*
X1370017D01*
X1369517Y1578804D01*
Y1574996D01*
X1369864Y1574649D01*
Y1571431D01*
G01X1376158Y1577997D02*
Y1578749D01*
X1375603Y1579304D01*
X1374741D01*
X1374241Y1578804D01*
Y1574996D01*
X1374590Y1574647D01*
Y1571432D01*
X1374589Y1571431D01*
G01X1365140D02*
X1365142Y1571433D01*
Y1574647D01*
X1364862Y1574927D01*
Y1578804D01*
X1365362Y1579304D01*
X1366155D01*
X1366709Y1578750D01*
Y1577997D01*
G01X1371434Y1581397D02*
Y1580701D01*
X1370887Y1580154D01*
X1369664D01*
X1368667Y1579157D01*
Y1574643D01*
X1369014Y1574296D01*
Y1573808D01*
X1368683Y1573477D01*
G01X1373407D02*
X1373740Y1573810D01*
Y1574294D01*
X1373391Y1574643D01*
Y1579157D01*
X1374388Y1580154D01*
X1375611D01*
X1376158Y1580701D01*
Y1581397D01*
G01X1378132Y1573477D02*
X1378465Y1573810D01*
Y1574294D01*
X1378116Y1574643D01*
Y1579157D01*
X1379113Y1580154D01*
X1380323D01*
X1380882Y1580713D01*
Y1581397D01*
G01X1363959Y1573477D02*
X1364292Y1573810D01*
Y1574294D01*
X1364012Y1574574D01*
Y1579157D01*
X1365009Y1580154D01*
X1366163D01*
X1366709Y1580700D01*
Y1581397D01*
G01X1395886Y1492995D02*
X1394511Y1494370D01*
Y1495750D01*
G02X1395256Y1497545I2539J-2D01*
G01X1398922Y1501211D01*
X1399544D01*
X1400394Y1502061D01*
Y1502683D01*
X1400847Y1503136D01*
G03X1401242Y1504092I-957J955D01*
G01Y1507658D01*
G03X1400707Y1508946I-1822J-2D01*
G01X1379827Y1529827D01*
G02X1378945Y1531953I2125J2128D01*
G01Y1541415D01*
X1379313Y1541783D01*
Y1544505D01*
G01X1405686Y1492995D02*
X1407061Y1494370D01*
Y1495707D01*
G02X1408301Y1498704I4238J2D01*
G01X1413044Y1503447D01*
G03X1413652Y1504914I-1466J1467D01*
G01Y1505979D01*
G03X1412972Y1507620I-2320J0D01*
G01X1411297Y1509295D01*
G03X1410175Y1509760I-1122J-1121D01*
G01X1406707D01*
G02X1404461Y1510689I-2J3176D01*
G01X1383214Y1531936D01*
G02X1382819Y1532893I958J955D01*
G01Y1540648D01*
X1381667Y1541800D01*
Y1542865D01*
X1382026Y1543224D01*
X1382555D01*
X1382856Y1542923D01*
Y1542459D01*
G01X1409286Y1492995D02*
X1407911Y1494370D01*
Y1495708D01*
X1407912Y1495707D01*
G02X1408903Y1498102I3387J1D01*
G01X1411326Y1500525D01*
X1411948D01*
X1412798Y1501375D01*
Y1501997D01*
X1413646Y1502845D01*
G03X1414502Y1504914I-2068J2067D01*
G01Y1505979D01*
G03X1413574Y1508222I-3171J2D01*
G01X1411899Y1509897D01*
G03X1410175Y1510610I-1722J-1724D01*
G01X1406707D01*
G02X1405063Y1511291I0J2325D01*
G01X1383816Y1532538D01*
G02X1383669Y1532893I355J355D01*
G01Y1541415D01*
X1384037Y1541783D01*
Y1544505D01*
G01X1409456Y1513582D02*
X1407743Y1515295D01*
X1406506D01*
X1388571Y1533230D01*
G02X1387544Y1535713I2484J2481D01*
G01Y1540938D01*
X1387914Y1541308D01*
Y1542126D01*
X1387581Y1542459D01*
G01X1409456Y1517182D02*
X1408647Y1516373D01*
X1408097Y1516145D01*
X1406859D01*
X1389173Y1533831D01*
G02X1388395Y1535713I1883J1880D01*
G01X1388394Y1535712D01*
Y1540585D01*
X1388764Y1540955D01*
Y1544503D01*
X1388762Y1544505D01*
G01X1409456Y1526982D02*
X1408081Y1528357D01*
X1406263D01*
X1405823Y1527917D01*
X1404623D01*
X1404183Y1528357D01*
X1401369D01*
G02X1400369Y1528770I-2J1413D01*
G01X1392885Y1536254D01*
G02X1392268Y1537746I1491J1490D01*
G01Y1540938D01*
X1392638Y1541308D01*
Y1542126D01*
X1392305Y1542459D01*
G01X1409456Y1530582D02*
X1408081Y1529207D01*
X1401369D01*
G02X1400971Y1529372I0J563D01*
G01X1393487Y1536856D01*
G02X1393118Y1537746I889J890D01*
G01Y1540585D01*
X1393488Y1540955D01*
Y1544503D01*
X1393486Y1544505D01*
G01X1380882Y1577997D02*
Y1578653D01*
X1380231Y1579304D01*
X1379466D01*
X1378966Y1578804D01*
Y1574996D01*
X1379315Y1574647D01*
Y1571433D01*
X1379313Y1571431D01*
G01X1384037D02*
X1384039Y1571433D01*
Y1574647D01*
X1383724Y1574962D01*
Y1578804D01*
X1384224Y1579304D01*
X1385052D01*
X1385606Y1578750D01*
Y1577997D01*
G01X1390331D02*
Y1578645D01*
X1389672Y1579304D01*
X1388915D01*
X1388415Y1578804D01*
Y1574996D01*
X1388764Y1574647D01*
Y1571433D01*
X1388762Y1571431D01*
G01X1395055Y1577997D02*
Y1578669D01*
X1394420Y1579304D01*
X1393639D01*
X1393139Y1578804D01*
Y1574996D01*
X1393488Y1574647D01*
Y1571433D01*
X1393486Y1571431D01*
G01X1382856Y1573477D02*
X1383189Y1573810D01*
Y1574294D01*
X1382874Y1574609D01*
Y1579157D01*
X1383871Y1580154D01*
X1385060D01*
X1385606Y1580700D01*
Y1581397D01*
G01X1387581Y1573477D02*
X1387914Y1573810D01*
Y1574294D01*
X1387565Y1574643D01*
Y1579157D01*
X1388562Y1580154D01*
X1389714D01*
X1390331Y1580771D01*
Y1581397D01*
G01X1392305Y1573477D02*
X1392638Y1573810D01*
Y1574294D01*
X1392289Y1574643D01*
Y1579157D01*
X1393286Y1580154D01*
X1394444D01*
X1395055Y1580765D01*
Y1581397D01*
G01X1444898Y1502695D02*
X1443523Y1504070D01*
Y1506552D01*
G02X1444290Y1508401I2616J-2D01*
G01X1444479Y1508590D01*
G02X1445860Y1509514I3014J-3011D01*
G01X1449462Y1511006D01*
G03X1449940Y1511325I-563J1362D01*
G01X1451100Y1512485D01*
X1451722D01*
X1452572Y1513335D01*
Y1513957D01*
X1453088Y1514473D01*
G03X1453892Y1515676I-2621J2622D01*
G01X1456709Y1522480D01*
X1457238Y1523360D01*
G02X1458261Y1524811I10378J-6231D01*
G01X1466946Y1535384D01*
G03X1467813Y1537804I-2946J2421D01*
G01Y1541415D01*
X1468181Y1541783D01*
Y1544505D01*
G01X1451598Y1492995D02*
X1450223Y1494370D01*
Y1495880D01*
G02X1450950Y1497635I2482J0D01*
G01X1453906Y1500591D01*
X1454528D01*
X1455378Y1501441D01*
Y1502063D01*
X1456406Y1503091D01*
G03X1456954Y1504413I-1321J1322D01*
G01Y1510179D01*
G02X1457148Y1511158I2559J2D01*
G01X1460510Y1519277D01*
X1461512Y1520950D01*
X1471878Y1533581D01*
G03X1472537Y1535419I-2235J1838D01*
G01Y1541415D01*
X1472905Y1541783D01*
Y1544505D01*
G01X1441298Y1502695D02*
X1442673Y1504070D01*
Y1506552D01*
G02X1443688Y1509003I3467J0D01*
G01X1443877Y1509192D01*
G02X1445534Y1510300I3615J-3613D01*
G01X1449136Y1511792D01*
G03X1449338Y1511927I-238J575D01*
G01X1452486Y1515075D01*
G03X1453106Y1516002I-2018J2021D01*
G01X1455948Y1522864D01*
X1456509Y1523798D01*
G02X1457603Y1525351I11110J-6664D01*
G01X1466289Y1535924D01*
G03X1466963Y1537805I-2289J1881D01*
G01Y1540648D01*
X1465811Y1541800D01*
Y1542865D01*
X1466170Y1543224D01*
X1466699D01*
X1467000Y1542923D01*
Y1542459D01*
G01X1447998Y1492995D02*
X1449373Y1494370D01*
Y1495880D01*
G02X1450348Y1498237I3332J2D01*
G01X1454776Y1502664D01*
Y1502665D01*
X1455804Y1503693D01*
G03X1456104Y1504413I-718J722D01*
G01Y1510179D01*
G02X1456362Y1511483I3409J3D01*
G01X1459748Y1519660D01*
X1460815Y1521441D01*
X1471221Y1534121D01*
G03X1471687Y1535420I-1578J1299D01*
G01Y1540648D01*
X1470535Y1541800D01*
Y1542865D01*
X1470894Y1543224D01*
X1471423D01*
X1471724Y1542923D01*
Y1542459D01*
G01X1442260Y1516690D02*
X1443721Y1515229D01*
X1444052D01*
G03X1447347Y1516594I0J4659D01*
G01X1448631Y1517878D01*
G03X1448999Y1518429I-1200J1200D01*
G01X1450771Y1522711D01*
X1450533Y1523285D01*
X1450992Y1524395D01*
X1451568Y1524633D01*
X1452132Y1525997D01*
X1452798Y1526994D01*
X1452677Y1527605D01*
X1453344Y1528603D01*
X1453955Y1528725D01*
X1454403Y1529395D01*
G02X1454984Y1530103I3888J-2598D01*
G01X1457359Y1532478D01*
X1461343Y1537334D01*
X1461841Y1538164D01*
X1462238Y1539121D01*
Y1540648D01*
X1461086Y1541800D01*
Y1542865D01*
X1461445Y1543224D01*
X1461974D01*
X1462275Y1542923D01*
Y1542459D01*
G01X1442260Y1513090D02*
X1443549Y1514379D01*
X1444052D01*
G03X1447949Y1515992I2J5510D01*
G01X1449233Y1517276D01*
G03X1449785Y1518104I-1803J1800D01*
G01X1452886Y1525594D01*
X1453505Y1526522D01*
X1453506D01*
X1454662Y1528252D01*
Y1528253D01*
X1455110Y1528923D01*
G02X1455586Y1529501I3177J-2131D01*
G01X1457990Y1531906D01*
X1462040Y1536843D01*
X1462603Y1537780D01*
X1463088Y1538952D01*
Y1541415D01*
X1463456Y1541783D01*
Y1544505D01*
G01X1442260Y1534890D02*
X1443628Y1536258D01*
X1452176D01*
G03X1453279Y1536477I0J2889D01*
G01X1455661Y1537461D01*
G03X1456773Y1538205I-1295J3139D01*
G01X1458364Y1539802D01*
Y1541415D01*
X1458732Y1541783D01*
Y1544505D01*
G01X1442260Y1538490D02*
X1443642Y1537108D01*
X1444842D01*
X1445282Y1537548D01*
X1446482D01*
X1446922Y1537108D01*
X1448122D01*
X1448562Y1537548D01*
X1449762D01*
X1450202Y1537108D01*
X1452175D01*
G03X1452954Y1537263I-1J2039D01*
G01X1455337Y1538247D01*
G03X1456170Y1538805I-973J2353D01*
G01X1457514Y1540156D01*
Y1540648D01*
X1456362Y1541800D01*
Y1542865D01*
X1456721Y1543224D01*
X1457250D01*
X1457551Y1542923D01*
Y1542459D01*
G01X1450016Y1558565D02*
X1450164Y1558713D01*
X1453550D01*
G01X1450091Y1559835D02*
X1450363Y1559563D01*
X1451173D01*
X1451504Y1559894D01*
G01X1468098Y1502695D02*
X1469473Y1504070D01*
Y1510804D01*
G02X1470906Y1515527I8499J0D01*
G01X1478504Y1526893D01*
G03X1481136Y1535566I-12974J8673D01*
G01Y1540648D01*
X1479984Y1541800D01*
Y1542865D01*
X1480343Y1543224D01*
X1480872D01*
X1481173Y1542923D01*
Y1542459D01*
G01X1464998Y1512395D02*
X1463623Y1513770D01*
Y1514455D01*
X1464472Y1516502D01*
X1466606Y1519102D01*
X1467225Y1519163D01*
X1467987Y1520091D01*
X1467927Y1520711D01*
X1475793Y1530295D01*
G03X1477262Y1535250I-7643J4961D01*
G03Y1535253I-9112J1D01*
G03Y1535257I-9112J2D01*
G01Y1541415D01*
X1477630Y1541783D01*
Y1544505D01*
G01X1461398Y1512395D02*
X1462773Y1513770D01*
Y1514625D01*
X1463735Y1516944D01*
X1475105Y1530797D01*
G03X1476412Y1535252I-6955J4460D01*
G01Y1540648D01*
X1475260Y1541800D01*
Y1542865D01*
X1475619Y1543224D01*
X1476148D01*
X1476449Y1542923D01*
Y1542459D01*
G01X1458732Y1571431D02*
X1458734Y1571433D01*
Y1574647D01*
X1458297Y1575084D01*
Y1578716D01*
X1458885Y1579304D01*
X1459747D01*
X1460301Y1578750D01*
Y1577997D01*
G01X1463456Y1571431D02*
X1463458Y1571433D01*
Y1574647D01*
X1463109Y1574996D01*
Y1578804D01*
X1463609Y1579304D01*
X1464471D01*
X1465025Y1578750D01*
Y1577997D01*
G01X1468181Y1571431D02*
X1468183Y1571433D01*
Y1574647D01*
X1467834Y1574996D01*
Y1578804D01*
X1468334Y1579304D01*
X1469196D01*
X1469750Y1578750D01*
Y1577997D01*
G01X1457551Y1573477D02*
X1457884Y1573810D01*
Y1574294D01*
X1457447Y1574731D01*
Y1579069D01*
X1458532Y1580154D01*
X1459755D01*
X1460301Y1580700D01*
Y1581397D01*
G01X1462275Y1573477D02*
X1462608Y1573810D01*
Y1574294D01*
X1462259Y1574643D01*
Y1579157D01*
X1463256Y1580154D01*
X1464479D01*
X1465025Y1580700D01*
Y1581397D01*
G01X1467000Y1573477D02*
X1467333Y1573810D01*
Y1574294D01*
X1466984Y1574643D01*
Y1579157D01*
X1467981Y1580154D01*
X1469204D01*
X1469750Y1580700D01*
Y1581397D01*
G01X1471698Y1502695D02*
X1470323Y1504070D01*
Y1507524D01*
X1470763Y1507964D01*
Y1509164D01*
X1470323Y1509604D01*
Y1510804D01*
G02X1471613Y1515055I7649J0D01*
G01X1479211Y1526421D01*
G03X1481986Y1535566I-13681J9145D01*
G01Y1541415D01*
X1482354Y1541783D01*
Y1544505D01*
G01X1478398Y1492995D02*
X1477023Y1494370D01*
Y1495519D01*
G02X1478060Y1498019I3536J-2D01*
G01X1482912Y1502871D01*
G03X1483792Y1504995I-2126J2125D01*
G01Y1508784D01*
X1484232Y1509224D01*
Y1510424D01*
X1483792Y1510864D01*
Y1521214D01*
G02X1484289Y1523757I6761J-1D01*
G01X1484433Y1524111D01*
G03X1486710Y1535733I-28531J11624D01*
G01Y1541415D01*
X1487079Y1541784D01*
Y1544505D01*
G01X1474798Y1492995D02*
X1476173Y1494370D01*
Y1495520D01*
G02X1477458Y1498621I4387J-1D01*
G01X1482310Y1503473D01*
G03X1482942Y1504996I-1523J1525D01*
G01Y1521213D01*
G02X1483501Y1524077I7611J1D01*
G01X1483645Y1524431D01*
G03X1485860Y1535734I-27743J11305D01*
G01Y1540648D01*
X1484708Y1541800D01*
Y1542865D01*
X1485067Y1543224D01*
X1485596D01*
X1485897Y1542923D01*
Y1542459D01*
G01X1472905Y1571431D02*
X1472907Y1571433D01*
Y1574647D01*
X1472610Y1574944D01*
Y1578804D01*
X1473110Y1579304D01*
X1473920D01*
X1474474Y1578750D01*
Y1577997D01*
G01X1477630Y1571431D02*
X1477632Y1571433D01*
Y1574647D01*
X1477283Y1574996D01*
Y1578804D01*
X1477783Y1579304D01*
X1478645D01*
X1479199Y1578750D01*
Y1577997D01*
G01X1482354Y1571431D02*
X1482356Y1571433D01*
Y1574647D01*
X1482007Y1574996D01*
Y1578804D01*
X1482507Y1579304D01*
X1483369D01*
X1483923Y1578750D01*
Y1577997D01*
G01X1471724Y1573477D02*
X1472057Y1573810D01*
Y1574294D01*
X1471760Y1574591D01*
Y1579157D01*
X1472757Y1580154D01*
X1473928D01*
X1474474Y1580700D01*
Y1581397D01*
G01X1476449Y1573477D02*
X1476782Y1573810D01*
Y1574294D01*
X1476433Y1574643D01*
Y1579157D01*
X1477430Y1580154D01*
X1478653D01*
X1479199Y1580700D01*
Y1581397D01*
G01X1481173Y1573477D02*
X1481506Y1573810D01*
Y1574294D01*
X1481157Y1574643D01*
Y1579157D01*
X1482154Y1580154D01*
X1483377D01*
X1483923Y1580700D01*
Y1581397D01*
G01X1498498Y1502695D02*
X1497310Y1503883D01*
G02X1497123Y1504335I453J452D01*
G01Y1508760D01*
X1497563Y1509200D01*
Y1510400D01*
X1497123Y1510840D01*
Y1515744D01*
G03X1496571Y1517339I-2578J1D01*
G02X1496314Y1517767I1562J1229D01*
G02X1496159Y1518504I1672J737D01*
G01Y1541415D01*
X1496527Y1541783D01*
Y1544505D01*
G01X1494898Y1502695D02*
X1496086Y1503883D01*
G03X1496273Y1504335I-453J452D01*
G01Y1515745D01*
G03X1495903Y1516813I-1728J-1D01*
G02X1495536Y1517424I2230J1755D01*
G02X1495309Y1518505I2450J1079D01*
G01Y1540648D01*
X1494157Y1541800D01*
Y1542865D01*
X1494516Y1543224D01*
X1495045D01*
X1495346Y1542923D01*
Y1542459D01*
G01X1491798Y1512395D02*
X1490609Y1513584D01*
G02X1490423Y1514034I451J450D01*
G01Y1517545D01*
X1490863Y1517985D01*
Y1519185D01*
X1490423Y1519625D01*
Y1520825D01*
G02X1490893Y1522317I2604J0D01*
G03X1491365Y1523800I-2135J1496D01*
G01X1491435Y1540645D01*
Y1541415D01*
X1491803Y1541783D01*
Y1544505D01*
G01X1488198Y1512395D02*
X1489386Y1513583D01*
G03X1489573Y1514035I-453J452D01*
G01Y1520826D01*
G02X1490198Y1522807I3454J-1D01*
G03X1490515Y1523804I-1440J1007D01*
G01X1490585Y1540648D01*
X1489433Y1541800D01*
Y1542865D01*
X1489792Y1543224D01*
X1490321D01*
X1490622Y1542923D01*
Y1542459D01*
G01X1487079Y1571431D02*
X1487081Y1571433D01*
Y1573809D01*
X1487080Y1573810D01*
Y1574647D01*
X1486766Y1574961D01*
Y1578804D01*
X1487266Y1579304D01*
X1488094D01*
X1488648Y1578750D01*
Y1577997D01*
G01X1491803Y1571431D02*
X1491805Y1571433D01*
Y1574647D01*
X1491456Y1574996D01*
Y1578804D01*
X1491956Y1579304D01*
X1492818D01*
X1493372Y1578750D01*
Y1577997D01*
G01X1498097D02*
Y1578749D01*
X1497542Y1579304D01*
X1496680D01*
X1496180Y1578804D01*
Y1574996D01*
X1496529Y1574647D01*
Y1571433D01*
X1496527Y1571431D01*
G01X1485897Y1573477D02*
X1486230Y1573810D01*
Y1574294D01*
X1485916Y1574608D01*
Y1579157D01*
X1486913Y1580154D01*
X1488101D01*
X1488648Y1580701D01*
Y1581397D01*
G01X1490622Y1573477D02*
X1490955Y1573810D01*
Y1574294D01*
X1490606Y1574643D01*
Y1579157D01*
X1491603Y1580154D01*
X1492826D01*
X1493372Y1580700D01*
Y1581397D01*
G01X1495346Y1573477D02*
X1495679Y1573810D01*
Y1574294D01*
X1495330Y1574643D01*
Y1579157D01*
X1496327Y1580154D01*
X1497550D01*
X1498097Y1580701D01*
Y1581397D01*
G01X1505198Y1492995D02*
X1503823Y1494370D01*
Y1495706D01*
G02X1504817Y1498103I3391J-2D01*
G01X1509396Y1502682D01*
G03X1510431Y1505179I-2497J2498D01*
G01Y1509358D01*
G03X1509902Y1510635I-1806J0D01*
G01X1506513Y1514024D01*
Y1514646D01*
X1505663Y1515496D01*
X1505041D01*
X1501202Y1519335D01*
G02X1500884Y1520102I766J767D01*
G01Y1541415D01*
X1501252Y1541783D01*
Y1544505D01*
G01X1501598Y1492995D02*
X1502973Y1494370D01*
Y1495707D01*
G02X1504215Y1498705I4242J-1D01*
G01X1508794Y1503284D01*
G03X1509581Y1505179I-1894J1898D01*
G01Y1509358D01*
G03X1509300Y1510033I-955J-2D01*
G01X1500600Y1518733D01*
G02X1500034Y1520102I1369J1367D01*
G01Y1540648D01*
X1498882Y1541800D01*
Y1542865D01*
X1499241Y1543224D01*
X1499770D01*
X1500071Y1542923D01*
Y1542459D01*
G01X1518598Y1512395D02*
X1517219Y1513774D01*
Y1514113D01*
G03X1516824Y1515070I-1353J2D01*
G01X1512959Y1518934D01*
G03X1511907Y1519368I-1050J-1053D01*
G01X1511032D01*
G02X1510606Y1519545I0J601D01*
G01X1507930Y1522222D01*
Y1522843D01*
X1507081Y1523692D01*
X1506459D01*
X1505755Y1524396D01*
G02X1505608Y1524751I355J355D01*
G01Y1541415D01*
X1505976Y1541783D01*
Y1544505D01*
G01X1514998Y1512395D02*
X1516369Y1513766D01*
Y1514113D01*
G03X1516222Y1514468I-502J0D01*
G01X1512358Y1518332D01*
G03X1511908Y1518518I-450J-451D01*
G01X1511031D01*
G02X1510005Y1518943I0J1451D01*
G01X1505858Y1523090D01*
X1505857D01*
X1505153Y1523794D01*
G02X1504758Y1524751I958J955D01*
G01Y1540648D01*
X1503606Y1541800D01*
Y1542865D01*
X1503965Y1543224D01*
X1504494D01*
X1504795Y1542923D01*
Y1542459D01*
G01X1525298Y1502695D02*
X1523923Y1504070D01*
Y1509464D01*
X1524363Y1509904D01*
Y1511104D01*
X1523923Y1511544D01*
Y1514246D01*
G03X1523528Y1515203I-1353J2D01*
G01X1510479Y1528252D01*
G02X1510332Y1528607I355J355D01*
G01Y1541415D01*
X1510701Y1541784D01*
Y1544505D01*
G01X1521698Y1502695D02*
X1523073Y1504070D01*
Y1514246D01*
G03X1522926Y1514601I-502J0D01*
G01X1509873Y1527654D01*
G02X1509482Y1528607I962J951D01*
G01Y1540648D01*
X1508330Y1541800D01*
Y1542865D01*
X1508689Y1543224D01*
X1509218D01*
X1509519Y1542923D01*
Y1542459D01*
G01X1507546Y1577997D02*
Y1578749D01*
X1506991Y1579304D01*
X1506129D01*
X1505629Y1578804D01*
Y1574996D01*
X1505976Y1574649D01*
Y1571431D01*
G01X1512270Y1577997D02*
Y1578749D01*
X1511715Y1579304D01*
X1510853D01*
X1510353Y1578804D01*
Y1574996D01*
X1510702Y1574647D01*
Y1571432D01*
X1510701Y1571431D01*
G01X1501252D02*
X1501254Y1571433D01*
Y1574647D01*
X1500974Y1574927D01*
Y1578804D01*
X1501474Y1579304D01*
X1502267D01*
X1502821Y1578750D01*
Y1577997D01*
G01X1507546Y1581397D02*
Y1580701D01*
X1506999Y1580154D01*
X1505776D01*
X1504779Y1579157D01*
Y1574643D01*
X1505126Y1574296D01*
Y1573808D01*
X1504795Y1573477D01*
G01X1509519D02*
X1509852Y1573810D01*
Y1574294D01*
X1509503Y1574643D01*
Y1579157D01*
X1510500Y1580154D01*
X1511723D01*
X1512270Y1580701D01*
Y1581397D01*
G01X1500071Y1573477D02*
X1500404Y1573810D01*
Y1574294D01*
X1500124Y1574574D01*
Y1579157D01*
X1501121Y1580154D01*
X1502275D01*
X1502821Y1580700D01*
Y1581397D01*
G01X1531998Y1492995D02*
X1530623Y1494370D01*
Y1495750D01*
G02X1531368Y1497545I2539J-2D01*
G01X1535034Y1501211D01*
X1535656D01*
X1536506Y1502061D01*
Y1502683D01*
X1536959Y1503136D01*
G03X1537354Y1504092I-957J955D01*
G01Y1507658D01*
G03X1536819Y1508946I-1822J-2D01*
G01X1515939Y1529827D01*
G02X1515057Y1531953I2125J2128D01*
G01Y1541415D01*
X1515425Y1541783D01*
Y1544505D01*
G01X1528398Y1492995D02*
X1529773Y1494370D01*
Y1495750D01*
G02X1530766Y1498147I3390J0D01*
G01X1536357Y1503737D01*
G03X1536504Y1504092I-355J355D01*
G01Y1507657D01*
G03X1536218Y1508344I-972J-2D01*
G01X1515337Y1529225D01*
G02X1514207Y1531953I2728J2728D01*
G01Y1540648D01*
X1513055Y1541800D01*
Y1542865D01*
X1513414Y1543224D01*
X1513943D01*
X1514244Y1542923D01*
Y1542459D01*
G01X1545398Y1492995D02*
X1544023Y1494370D01*
Y1495708D01*
X1544024Y1495707D01*
G02X1545015Y1498102I3387J1D01*
G01X1547438Y1500525D01*
X1548060D01*
X1548910Y1501375D01*
Y1501997D01*
X1549758Y1502845D01*
G03X1550614Y1504914I-2068J2067D01*
G01Y1505979D01*
G03X1549686Y1508222I-3171J2D01*
G01X1548011Y1509897D01*
G03X1546287Y1510610I-1722J-1724D01*
G01X1542819D01*
G02X1541175Y1511291I0J2325D01*
G01X1519928Y1532538D01*
G02X1519781Y1532893I355J355D01*
G01Y1541415D01*
X1520149Y1541783D01*
Y1544505D01*
G01X1545568Y1513582D02*
X1543855Y1515295D01*
X1542618D01*
X1524683Y1533230D01*
G02X1523656Y1535713I2484J2481D01*
G01Y1540938D01*
X1524026Y1541308D01*
Y1542126D01*
X1523693Y1542459D01*
G01X1541798Y1492995D02*
X1543173Y1494370D01*
Y1495707D01*
G02X1544413Y1498704I4238J2D01*
G01X1549156Y1503447D01*
G03X1549764Y1504914I-1466J1467D01*
G01Y1505979D01*
G03X1549084Y1507620I-2320J0D01*
G01X1547409Y1509295D01*
G03X1546287Y1509760I-1122J-1121D01*
G01X1542819D01*
G02X1540573Y1510689I-2J3176D01*
G01X1519326Y1531936D01*
G02X1518931Y1532893I958J955D01*
G01Y1540648D01*
X1517779Y1541800D01*
Y1542865D01*
X1518138Y1543224D01*
X1518667D01*
X1518968Y1542923D01*
Y1542459D01*
G01X1545568Y1517182D02*
X1544759Y1516373D01*
X1544209Y1516145D01*
X1542971D01*
X1525285Y1533831D01*
G02X1524507Y1535713I1883J1880D01*
G01X1524506Y1535712D01*
Y1540585D01*
X1524876Y1540955D01*
Y1544503D01*
X1524874Y1544505D01*
G01X1516994Y1577997D02*
Y1578653D01*
X1516343Y1579304D01*
X1515578D01*
X1515078Y1578804D01*
Y1574996D01*
X1515427Y1574647D01*
Y1571433D01*
X1515425Y1571431D01*
G01X1520149D02*
X1520151Y1571433D01*
Y1574647D01*
X1519836Y1574962D01*
Y1578804D01*
X1520336Y1579304D01*
X1521164D01*
X1521718Y1578750D01*
Y1577997D01*
G01X1526443D02*
Y1578645D01*
X1525784Y1579304D01*
X1525027D01*
X1524527Y1578804D01*
Y1574996D01*
X1524876Y1574647D01*
Y1571433D01*
X1524874Y1571431D01*
G01X1514244Y1573477D02*
X1514577Y1573810D01*
Y1574294D01*
X1514228Y1574643D01*
Y1579157D01*
X1515225Y1580154D01*
X1516435D01*
X1516994Y1580713D01*
Y1581397D01*
G01X1518968Y1573477D02*
X1519301Y1573810D01*
Y1574294D01*
X1518986Y1574609D01*
Y1579157D01*
X1519983Y1580154D01*
X1521172D01*
X1521718Y1580700D01*
Y1581397D01*
G01X1523693Y1573477D02*
X1524026Y1573810D01*
Y1574294D01*
X1523677Y1574643D01*
Y1579157D01*
X1524674Y1580154D01*
X1525826D01*
X1526443Y1580771D01*
Y1581397D01*
G01X1545568Y1530582D02*
X1544193Y1529207D01*
X1537481D01*
G02X1537083Y1529372I0J563D01*
G01X1529599Y1536856D01*
G02X1529230Y1537746I889J890D01*
G01Y1540585D01*
X1529600Y1540955D01*
Y1544503D01*
X1529598Y1544505D01*
G01X1545568Y1526982D02*
X1544193Y1528357D01*
X1542375D01*
X1541935Y1527917D01*
X1540735D01*
X1540295Y1528357D01*
X1537481D01*
G02X1536481Y1528770I-2J1413D01*
G01X1528997Y1536254D01*
G02X1528380Y1537746I1491J1490D01*
G01Y1540938D01*
X1528750Y1541308D01*
Y1542126D01*
X1528417Y1542459D01*
G01X1531167Y1577997D02*
Y1578669D01*
X1530532Y1579304D01*
X1529751D01*
X1529251Y1578804D01*
Y1574996D01*
X1529600Y1574647D01*
Y1571433D01*
X1529598Y1571431D01*
G01X1528417Y1573477D02*
X1528750Y1573810D01*
Y1574294D01*
X1528401Y1574643D01*
Y1579157D01*
X1529398Y1580154D01*
X1530556D01*
X1531167Y1580765D01*
Y1581397D01*
G01X1572960Y1502695D02*
X1571585Y1504070D01*
Y1506552D01*
G02X1572352Y1508401I2616J-2D01*
G01X1572541Y1508590D01*
G02X1573922Y1509514I3014J-3011D01*
G01X1577524Y1511006D01*
G03X1578002Y1511325I-563J1362D01*
G01X1579162Y1512485D01*
X1579784D01*
X1580634Y1513335D01*
Y1513957D01*
X1581150Y1514473D01*
G03X1581954Y1515676I-2621J2622D01*
G01X1584771Y1522480D01*
X1585300Y1523360D01*
G02X1586323Y1524811I10378J-6231D01*
G01X1595008Y1535384D01*
G03X1595875Y1537804I-2946J2421D01*
G01Y1541415D01*
X1596243Y1541783D01*
Y1544505D01*
G01X1569360Y1502695D02*
X1570735Y1504070D01*
Y1506552D01*
G02X1571750Y1509003I3467J0D01*
G01X1571939Y1509192D01*
G02X1573596Y1510300I3615J-3613D01*
G01X1577198Y1511792D01*
G03X1577400Y1511927I-238J575D01*
G01X1580548Y1515075D01*
G03X1581168Y1516002I-2018J2021D01*
G01X1584010Y1522864D01*
X1584571Y1523798D01*
G02X1585665Y1525351I11110J-6664D01*
G01X1594351Y1535924D01*
G03X1595025Y1537805I-2289J1881D01*
G01Y1540648D01*
X1593873Y1541800D01*
Y1542865D01*
X1594232Y1543224D01*
X1594761D01*
X1595062Y1542923D01*
Y1542459D01*
G01X1570322Y1516690D02*
X1571783Y1515229D01*
X1572114D01*
G03X1575409Y1516594I0J4659D01*
G01X1576693Y1517878D01*
G03X1577061Y1518429I-1200J1200D01*
G01X1578833Y1522711D01*
X1578595Y1523285D01*
X1579054Y1524395D01*
X1579630Y1524633D01*
X1580194Y1525997D01*
X1580860Y1526994D01*
X1580739Y1527605D01*
X1581406Y1528603D01*
X1582017Y1528725D01*
X1582465Y1529395D01*
G02X1583046Y1530103I3888J-2598D01*
G01X1585421Y1532478D01*
X1589405Y1537334D01*
X1589903Y1538164D01*
X1590300Y1539121D01*
Y1540648D01*
X1589148Y1541800D01*
Y1542865D01*
X1589507Y1543224D01*
X1590036D01*
X1590337Y1542923D01*
Y1542459D01*
G01X1570322Y1513090D02*
X1571611Y1514379D01*
X1572114D01*
G03X1576011Y1515992I2J5510D01*
G01X1577295Y1517276D01*
G03X1577847Y1518104I-1803J1800D01*
G01X1580948Y1525594D01*
X1581567Y1526522D01*
X1581568D01*
X1582724Y1528252D01*
Y1528253D01*
X1583172Y1528923D01*
G02X1583648Y1529501I3177J-2131D01*
G01X1586052Y1531906D01*
X1590102Y1536843D01*
X1590665Y1537780D01*
X1591150Y1538952D01*
Y1541415D01*
X1591518Y1541783D01*
Y1544505D01*
G01X1570322Y1534890D02*
X1571690Y1536258D01*
X1580238D01*
G03X1581341Y1536477I0J2889D01*
G01X1583723Y1537461D01*
G03X1584835Y1538205I-1295J3139D01*
G01X1586426Y1539802D01*
Y1541415D01*
X1586794Y1541783D01*
Y1544505D01*
G01X1570322Y1538490D02*
X1571704Y1537108D01*
X1572904D01*
X1573344Y1537548D01*
X1574544D01*
X1574984Y1537108D01*
X1576184D01*
X1576624Y1537548D01*
X1577824D01*
X1578264Y1537108D01*
X1580237D01*
G03X1581016Y1537263I-1J2039D01*
G01X1583399Y1538247D01*
G03X1584232Y1538805I-973J2353D01*
G01X1585576Y1540156D01*
Y1540648D01*
X1584424Y1541800D01*
Y1542865D01*
X1584783Y1543224D01*
X1585312D01*
X1585613Y1542923D01*
Y1542459D01*
G01X1578078Y1558565D02*
X1578226Y1558713D01*
X1581612D01*
G01X1578153Y1559835D02*
X1578425Y1559563D01*
X1579235D01*
X1579566Y1559894D01*
G01X1579660Y1492995D02*
X1578285Y1494370D01*
Y1495880D01*
G02X1579012Y1497635I2482J0D01*
G01X1581968Y1500591D01*
X1582590D01*
X1583440Y1501441D01*
Y1502063D01*
X1584468Y1503091D01*
G03X1585016Y1504413I-1321J1322D01*
G01Y1510179D01*
G02X1585210Y1511158I2559J2D01*
G01X1588572Y1519277D01*
X1589574Y1520950D01*
X1599940Y1533581D01*
G03X1600599Y1535419I-2235J1838D01*
G01Y1541415D01*
X1600967Y1541783D01*
Y1544505D01*
G01X1576060Y1492995D02*
X1577435Y1494370D01*
Y1495880D01*
G02X1578410Y1498237I3332J2D01*
G01X1582838Y1502664D01*
Y1502665D01*
X1583866Y1503693D01*
G03X1584166Y1504413I-718J722D01*
G01Y1510179D01*
G02X1584424Y1511483I3409J3D01*
G01X1587810Y1519660D01*
X1588877Y1521441D01*
X1599283Y1534121D01*
G03X1599749Y1535420I-1578J1299D01*
G01Y1540648D01*
X1598597Y1541800D01*
Y1542865D01*
X1598956Y1543224D01*
X1599485D01*
X1599786Y1542923D01*
Y1542459D01*
G01X1586794Y1571431D02*
X1586796Y1571433D01*
Y1574647D01*
X1586359Y1575084D01*
Y1578716D01*
X1586947Y1579304D01*
X1587809D01*
X1588363Y1578750D01*
Y1577997D01*
G01X1585613Y1573477D02*
X1585946Y1573810D01*
Y1574294D01*
X1585509Y1574731D01*
Y1579069D01*
X1586594Y1580154D01*
X1587817D01*
X1588363Y1580700D01*
Y1581397D01*
G01X1599760Y1502695D02*
X1598385Y1504070D01*
Y1507524D01*
X1598825Y1507964D01*
Y1509164D01*
X1598385Y1509604D01*
Y1510804D01*
G02X1599675Y1515055I7649J0D01*
G01X1607273Y1526421D01*
G03X1610048Y1535566I-13681J9145D01*
G01Y1541415D01*
X1610416Y1541783D01*
Y1544505D01*
G01X1596160Y1502695D02*
X1597535Y1504070D01*
Y1510804D01*
G02X1598968Y1515527I8499J0D01*
G01X1606566Y1526893D01*
G03X1609198Y1535566I-12974J8673D01*
G01Y1540648D01*
X1608046Y1541800D01*
Y1542865D01*
X1608405Y1543224D01*
X1608934D01*
X1609235Y1542923D01*
Y1542459D01*
G01X1593060Y1512395D02*
X1591685Y1513770D01*
Y1514455D01*
X1592534Y1516502D01*
X1594668Y1519102D01*
X1595287Y1519163D01*
X1596049Y1520091D01*
X1595989Y1520711D01*
X1603855Y1530295D01*
G03X1605324Y1535250I-7643J4961D01*
G03Y1535253I-9112J1D01*
G03Y1535257I-9112J2D01*
G01Y1541415D01*
X1605692Y1541783D01*
Y1544505D01*
G01X1589460Y1512395D02*
X1590835Y1513770D01*
Y1514625D01*
X1591797Y1516944D01*
X1603167Y1530797D01*
G03X1604474Y1535252I-6955J4460D01*
G01Y1540648D01*
X1603322Y1541800D01*
Y1542865D01*
X1603681Y1543224D01*
X1604210D01*
X1604511Y1542923D01*
Y1542459D01*
G01X1591518Y1571431D02*
X1591520Y1571433D01*
Y1574647D01*
X1591171Y1574996D01*
Y1578804D01*
X1591671Y1579304D01*
X1592533D01*
X1593087Y1578750D01*
Y1577997D01*
G01X1596243Y1571431D02*
X1596245Y1571433D01*
Y1574647D01*
X1595896Y1574996D01*
Y1578804D01*
X1596396Y1579304D01*
X1597258D01*
X1597812Y1578750D01*
Y1577997D01*
G01X1600967Y1571431D02*
X1600969Y1571433D01*
Y1574647D01*
X1600672Y1574944D01*
Y1578804D01*
X1601172Y1579304D01*
X1601982D01*
X1602536Y1578750D01*
Y1577997D01*
G01X1590337Y1573477D02*
X1590670Y1573810D01*
Y1574294D01*
X1590321Y1574643D01*
Y1579157D01*
X1591318Y1580154D01*
X1592541D01*
X1593087Y1580700D01*
Y1581397D01*
G01X1595062Y1573477D02*
X1595395Y1573810D01*
Y1574294D01*
X1595046Y1574643D01*
Y1579157D01*
X1596043Y1580154D01*
X1597266D01*
X1597812Y1580700D01*
Y1581397D01*
G01X1599786Y1573477D02*
X1600119Y1573810D01*
Y1574294D01*
X1599822Y1574591D01*
Y1579157D01*
X1600819Y1580154D01*
X1601990D01*
X1602536Y1580700D01*
Y1581397D01*
G01X1606460Y1492995D02*
X1605085Y1494370D01*
Y1495519D01*
G02X1606122Y1498019I3536J-2D01*
G01X1610974Y1502871D01*
G03X1611854Y1504995I-2126J2125D01*
G01Y1508784D01*
X1612294Y1509224D01*
Y1510424D01*
X1611854Y1510864D01*
Y1521214D01*
G02X1612351Y1523757I6761J-1D01*
G01X1612495Y1524111D01*
G03X1614772Y1535733I-28531J11624D01*
G01Y1541415D01*
X1615141Y1541784D01*
Y1544505D01*
G01X1602860Y1492995D02*
X1604235Y1494370D01*
Y1495520D01*
G02X1605520Y1498621I4387J-1D01*
G01X1610372Y1503473D01*
G03X1611004Y1504996I-1523J1525D01*
G01Y1521213D01*
G02X1611563Y1524077I7611J1D01*
G01X1611707Y1524431D01*
G03X1613922Y1535734I-27743J11305D01*
G01Y1540648D01*
X1612770Y1541800D01*
Y1542865D01*
X1613129Y1543224D01*
X1613658D01*
X1613959Y1542923D01*
Y1542459D01*
G01X1616260Y1512395D02*
X1617448Y1513583D01*
G03X1617635Y1514035I-453J452D01*
G01Y1520826D01*
G02X1618260Y1522807I3454J-1D01*
G03X1618577Y1523804I-1440J1007D01*
G01X1618647Y1540648D01*
X1617495Y1541800D01*
Y1542865D01*
X1617854Y1543224D01*
X1618383D01*
X1618684Y1542923D01*
Y1542459D01*
G01X1605692Y1571431D02*
X1605694Y1571433D01*
Y1574647D01*
X1605345Y1574996D01*
Y1578804D01*
X1605845Y1579304D01*
X1606707D01*
X1607261Y1578750D01*
Y1577997D01*
G01X1610416Y1571431D02*
X1610418Y1571433D01*
Y1574647D01*
X1610069Y1574996D01*
Y1578804D01*
X1610569Y1579304D01*
X1611431D01*
X1611985Y1578750D01*
Y1577997D01*
G01X1615141Y1571431D02*
X1615143Y1571433D01*
Y1573809D01*
X1615142Y1573810D01*
Y1574647D01*
X1614828Y1574961D01*
Y1578804D01*
X1615328Y1579304D01*
X1616156D01*
X1616710Y1578750D01*
Y1577997D01*
G01X1604511Y1573477D02*
X1604844Y1573810D01*
Y1574294D01*
X1604495Y1574643D01*
Y1579157D01*
X1605492Y1580154D01*
X1606715D01*
X1607261Y1580700D01*
Y1581397D01*
G01X1609235Y1573477D02*
X1609568Y1573810D01*
Y1574294D01*
X1609219Y1574643D01*
Y1579157D01*
X1610216Y1580154D01*
X1611439D01*
X1611985Y1580700D01*
Y1581397D01*
G01X1613959Y1573477D02*
X1614292Y1573810D01*
Y1574294D01*
X1613978Y1574608D01*
Y1579157D01*
X1614975Y1580154D01*
X1616163D01*
X1616710Y1580701D01*
Y1581397D01*
G01X1626560Y1502695D02*
X1625372Y1503883D01*
G02X1625185Y1504335I453J452D01*
G01Y1508760D01*
X1625625Y1509200D01*
Y1510400D01*
X1625185Y1510840D01*
Y1515744D01*
G03X1624633Y1517339I-2578J1D01*
G02X1624376Y1517767I1562J1229D01*
G02X1624221Y1518504I1672J737D01*
G01Y1541415D01*
X1624589Y1541783D01*
Y1544505D01*
G01X1633260Y1492995D02*
X1631885Y1494370D01*
Y1495706D01*
G02X1632879Y1498103I3391J-2D01*
G01X1637458Y1502682D01*
G03X1638493Y1505179I-2497J2498D01*
G01Y1509358D01*
G03X1637964Y1510635I-1806J0D01*
G01X1634575Y1514024D01*
Y1514646D01*
X1633725Y1515496D01*
X1633103D01*
X1629264Y1519335D01*
G02X1628946Y1520102I766J767D01*
G01Y1541415D01*
X1629314Y1541783D01*
Y1544505D01*
G01X1622960Y1502695D02*
X1624148Y1503883D01*
G03X1624335Y1504335I-453J452D01*
G01Y1515745D01*
G03X1623965Y1516813I-1728J-1D01*
G02X1623598Y1517424I2230J1755D01*
G02X1623371Y1518505I2450J1079D01*
G01Y1540648D01*
X1622219Y1541800D01*
Y1542865D01*
X1622578Y1543224D01*
X1623107D01*
X1623408Y1542923D01*
Y1542459D01*
G01X1629660Y1492995D02*
X1631035Y1494370D01*
Y1495707D01*
G02X1632277Y1498705I4242J-1D01*
G01X1636856Y1503284D01*
G03X1637643Y1505179I-1894J1898D01*
G01Y1509358D01*
G03X1637362Y1510033I-955J-2D01*
G01X1628662Y1518733D01*
G02X1628096Y1520102I1369J1367D01*
G01Y1540648D01*
X1626944Y1541800D01*
Y1542865D01*
X1627303Y1543224D01*
X1627832D01*
X1628133Y1542923D01*
Y1542459D01*
G01X1619860Y1512395D02*
X1618671Y1513584D01*
G02X1618485Y1514034I451J450D01*
G01Y1517545D01*
X1618925Y1517985D01*
Y1519185D01*
X1618485Y1519625D01*
Y1520825D01*
G02X1618955Y1522317I2604J0D01*
G03X1619427Y1523800I-2135J1496D01*
G01X1619497Y1540645D01*
Y1541415D01*
X1619865Y1541783D01*
Y1544505D01*
G01X1643060Y1512395D02*
X1644431Y1513766D01*
Y1514113D01*
G03X1644284Y1514468I-502J0D01*
G01X1640420Y1518332D01*
G03X1639970Y1518518I-450J-451D01*
G01X1639093D01*
G02X1638067Y1518943I0J1451D01*
G01X1633920Y1523090D01*
X1633919D01*
X1633215Y1523794D01*
G02X1632820Y1524751I958J955D01*
G01Y1540648D01*
X1631668Y1541800D01*
Y1542865D01*
X1632027Y1543224D01*
X1632556D01*
X1632857Y1542923D01*
Y1542459D01*
G01X1619865Y1571431D02*
X1619867Y1571433D01*
Y1574647D01*
X1619518Y1574996D01*
Y1578804D01*
X1620018Y1579304D01*
X1620880D01*
X1621434Y1578750D01*
Y1577997D01*
G01X1626159D02*
Y1578749D01*
X1625604Y1579304D01*
X1624742D01*
X1624242Y1578804D01*
Y1574996D01*
X1624591Y1574647D01*
Y1571433D01*
X1624589Y1571431D01*
G01X1629314D02*
X1629316Y1571433D01*
Y1574647D01*
X1629036Y1574927D01*
Y1578804D01*
X1629536Y1579304D01*
X1630329D01*
X1630883Y1578750D01*
Y1577997D01*
G01X1618684Y1573477D02*
X1619017Y1573810D01*
Y1574294D01*
X1618668Y1574643D01*
Y1579157D01*
X1619665Y1580154D01*
X1620888D01*
X1621434Y1580700D01*
Y1581397D01*
G01X1623408Y1573477D02*
X1623741Y1573810D01*
Y1574294D01*
X1623392Y1574643D01*
Y1579157D01*
X1624389Y1580154D01*
X1625612D01*
X1626159Y1580701D01*
Y1581397D01*
G01X1628133Y1573477D02*
X1628466Y1573810D01*
Y1574294D01*
X1628186Y1574574D01*
Y1579157D01*
X1629183Y1580154D01*
X1630337D01*
X1630883Y1580700D01*
Y1581397D01*
G01X1646660Y1512395D02*
X1645281Y1513774D01*
Y1514113D01*
G03X1644886Y1515070I-1353J2D01*
G01X1641021Y1518934D01*
G03X1639969Y1519368I-1050J-1053D01*
G01X1639094D01*
G02X1638668Y1519545I0J601D01*
G01X1635992Y1522222D01*
Y1522843D01*
X1635143Y1523692D01*
X1634521D01*
X1633817Y1524396D01*
G02X1633670Y1524751I355J355D01*
G01Y1541415D01*
X1634038Y1541783D01*
Y1544505D01*
G01X1653360Y1502695D02*
X1651985Y1504070D01*
Y1509464D01*
X1652425Y1509904D01*
Y1511104D01*
X1651985Y1511544D01*
Y1514246D01*
G03X1651590Y1515203I-1353J2D01*
G01X1638541Y1528252D01*
G02X1638394Y1528607I355J355D01*
G01Y1541415D01*
X1638763Y1541784D01*
Y1544505D01*
G01X1649760Y1502695D02*
X1651135Y1504070D01*
Y1514246D01*
G03X1650988Y1514601I-502J0D01*
G01X1637935Y1527654D01*
G02X1637544Y1528607I962J951D01*
G01Y1540648D01*
X1636392Y1541800D01*
Y1542865D01*
X1636751Y1543224D01*
X1637280D01*
X1637581Y1542923D01*
Y1542459D01*
G01X1660060Y1492995D02*
X1658685Y1494370D01*
Y1495750D01*
G02X1659430Y1497545I2539J-2D01*
G01X1663096Y1501211D01*
X1663718D01*
X1664568Y1502061D01*
Y1502683D01*
X1665021Y1503136D01*
G03X1665416Y1504092I-957J955D01*
G01Y1507658D01*
G03X1664881Y1508946I-1822J-2D01*
G01X1644001Y1529827D01*
G02X1643119Y1531953I2125J2128D01*
G01Y1541415D01*
X1643487Y1541783D01*
Y1544505D01*
G01X1656460Y1492995D02*
X1657835Y1494370D01*
Y1495750D01*
G02X1658828Y1498147I3390J0D01*
G01X1664419Y1503737D01*
G03X1664566Y1504092I-355J355D01*
G01Y1507657D01*
G03X1664280Y1508344I-972J-2D01*
G01X1643399Y1529225D01*
G02X1642269Y1531953I2728J2728D01*
G01Y1540648D01*
X1641117Y1541800D01*
Y1542865D01*
X1641476Y1543224D01*
X1642005D01*
X1642306Y1542923D01*
Y1542459D01*
G01X1669860Y1492995D02*
X1671235Y1494370D01*
Y1495707D01*
G02X1672475Y1498704I4238J2D01*
G01X1677218Y1503447D01*
G03X1677826Y1504914I-1466J1467D01*
G01Y1505979D01*
G03X1677146Y1507620I-2320J0D01*
G01X1675471Y1509295D01*
G03X1674349Y1509760I-1122J-1121D01*
G01X1670881D01*
G02X1668635Y1510689I-2J3176D01*
G01X1647388Y1531936D01*
G02X1646993Y1532893I958J955D01*
G01Y1540648D01*
X1645841Y1541800D01*
Y1542865D01*
X1646200Y1543224D01*
X1646729D01*
X1647030Y1542923D01*
Y1542459D01*
G01X1635608Y1577997D02*
Y1578749D01*
X1635053Y1579304D01*
X1634191D01*
X1633691Y1578804D01*
Y1574996D01*
X1634038Y1574649D01*
Y1571431D01*
G01X1640332Y1577997D02*
Y1578749D01*
X1639777Y1579304D01*
X1638915D01*
X1638415Y1578804D01*
Y1574996D01*
X1638764Y1574647D01*
Y1571432D01*
X1638763Y1571431D01*
G01X1645056Y1577997D02*
Y1578653D01*
X1644405Y1579304D01*
X1643640D01*
X1643140Y1578804D01*
Y1574996D01*
X1643489Y1574647D01*
Y1571433D01*
X1643487Y1571431D01*
G01X1635608Y1581397D02*
Y1580701D01*
X1635061Y1580154D01*
X1633838D01*
X1632841Y1579157D01*
Y1574643D01*
X1633188Y1574296D01*
Y1573808D01*
X1632857Y1573477D01*
G01X1637581D02*
X1637914Y1573810D01*
Y1574294D01*
X1637565Y1574643D01*
Y1579157D01*
X1638562Y1580154D01*
X1639785D01*
X1640332Y1580701D01*
Y1581397D01*
G01X1642306Y1573477D02*
X1642639Y1573810D01*
Y1574294D01*
X1642290Y1574643D01*
Y1579157D01*
X1643287Y1580154D01*
X1644497D01*
X1645056Y1580713D01*
Y1581397D01*
G01X1647030Y1573477D02*
X1647363Y1573810D01*
Y1574294D01*
X1647048Y1574609D01*
Y1579157D01*
X1648045Y1580154D01*
X1649234D01*
X1649780Y1580700D01*
Y1581397D01*
G01X1673460Y1492995D02*
X1672085Y1494370D01*
Y1495708D01*
X1672086Y1495707D01*
G02X1673077Y1498102I3387J1D01*
G01X1675500Y1500525D01*
X1676122D01*
X1676972Y1501375D01*
Y1501997D01*
X1677820Y1502845D01*
G03X1678676Y1504914I-2068J2067D01*
G01Y1505979D01*
G03X1677748Y1508222I-3171J2D01*
G01X1676073Y1509897D01*
G03X1674349Y1510610I-1722J-1724D01*
G01X1670881D01*
G02X1669237Y1511291I0J2325D01*
G01X1647990Y1532538D01*
G02X1647843Y1532893I355J355D01*
G01Y1541415D01*
X1648211Y1541783D01*
Y1544505D01*
G01X1673630Y1517182D02*
X1672821Y1516373D01*
X1672271Y1516145D01*
X1671033D01*
X1653347Y1533831D01*
G02X1652569Y1535713I1883J1880D01*
G01X1652568Y1535712D01*
Y1540585D01*
X1652938Y1540955D01*
Y1544503D01*
X1652936Y1544505D01*
G01X1673630Y1530582D02*
X1672255Y1529207D01*
X1665543D01*
G02X1665145Y1529372I0J563D01*
G01X1657661Y1536856D01*
G02X1657292Y1537746I889J890D01*
G01Y1540585D01*
X1657662Y1540955D01*
Y1544503D01*
X1657660Y1544505D01*
G01X1673630Y1513582D02*
X1671917Y1515295D01*
X1670680D01*
X1652745Y1533230D01*
G02X1651718Y1535713I2484J2481D01*
G01Y1540938D01*
X1652088Y1541308D01*
Y1542126D01*
X1651755Y1542459D01*
G01X1673630Y1526982D02*
X1672255Y1528357D01*
X1670437D01*
X1669997Y1527917D01*
X1668797D01*
X1668357Y1528357D01*
X1665543D01*
G02X1664543Y1528770I-2J1413D01*
G01X1657059Y1536254D01*
G02X1656442Y1537746I1491J1490D01*
G01Y1540938D01*
X1656812Y1541308D01*
Y1542126D01*
X1656479Y1542459D01*
G01X1648211Y1571431D02*
X1648213Y1571433D01*
Y1574647D01*
X1647898Y1574962D01*
Y1578804D01*
X1648398Y1579304D01*
X1649226D01*
X1649780Y1578750D01*
Y1577997D01*
G01X1654505D02*
Y1578645D01*
X1653846Y1579304D01*
X1653089D01*
X1652589Y1578804D01*
Y1574996D01*
X1652938Y1574647D01*
Y1571433D01*
X1652936Y1571431D01*
G01X1659229Y1577997D02*
Y1578669D01*
X1658594Y1579304D01*
X1657813D01*
X1657313Y1578804D01*
Y1574996D01*
X1657662Y1574647D01*
Y1571433D01*
X1657660Y1571431D01*
G01X1651755Y1573477D02*
X1652088Y1573810D01*
Y1574294D01*
X1651739Y1574643D01*
Y1579157D01*
X1652736Y1580154D01*
X1653888D01*
X1654505Y1580771D01*
Y1581397D01*
G01X1656479Y1573477D02*
X1656812Y1573810D01*
Y1574294D01*
X1656463Y1574643D01*
Y1579157D01*
X1657460Y1580154D01*
X1658618D01*
X1659229Y1580765D01*
Y1581397D01*
G54D18*
X17363Y230264D03*
X10543Y230308D03*
X36595Y385068D03*
X32774Y525886D03*
X46834Y363428D03*
X50631Y1530187D03*
X42150Y1550596D03*
X46150D03*
X45633Y1595412D03*
X50133D03*
X55190Y363428D03*
X64442Y504481D03*
X53299Y546811D03*
X63148Y546776D03*
X58365D03*
X59427Y1646903D03*
X66127Y1681903D03*
X76378Y1409171D03*
X72378D03*
X79323Y1530043D03*
X72768Y1547312D03*
X76806Y1596423D03*
X78406Y1604723D03*
X73427Y1646903D03*
X68427D03*
X82127Y1681903D03*
X86374Y1530687D03*
X90127Y1681903D03*
X92257Y1721347D03*
X98101Y1363553D03*
X108511Y1547012D03*
X115016Y294713D03*
Y315147D03*
X118407Y521307D03*
X126910Y1364151D03*
X119632Y1381874D03*
X115066Y1529743D03*
X120353Y1649103D03*
X124353D03*
X116353D03*
X123353Y1690482D03*
X140360Y424096D03*
X130701Y1363553D03*
X140353Y1649103D03*
X128353D03*
X127353Y1690603D03*
X132767Y1723257D03*
X150318Y210474D03*
Y218474D03*
X152232Y1381874D03*
X143500Y1442516D03*
X147000D03*
X148353Y1649103D03*
X144253D03*
X147253Y1690603D03*
X154740Y1707516D03*
X149900Y1712882D03*
Y1719882D03*
X159510Y1363924D03*
X163401Y1363553D03*
X159427Y1690603D03*
X167500Y1715516D03*
X162740Y1707516D03*
X184932Y1381874D03*
X181760Y1707404D03*
X185760Y1725892D03*
X189410Y390676D03*
X192210Y1364151D03*
X196301Y1363553D03*
X194000Y1715016D03*
X189760Y1707404D03*
X211000Y1712016D03*
X228675Y564125D03*
X225110Y1364151D03*
X229101Y1363553D03*
X217832Y1381874D03*
X236266Y62378D03*
X240266D03*
X244266D03*
X232817Y564093D03*
X239843Y712264D03*
X248266Y62378D03*
X251487Y104776D03*
X255270Y211986D03*
X255466Y645275D03*
X257910Y1364151D03*
X250632Y1381874D03*
X275797Y124059D03*
X269405Y582051D03*
X262466Y595169D03*
X263866Y587970D03*
X269061Y644465D03*
X272955Y653096D03*
X272932Y670417D03*
X262701Y1317407D03*
X261778Y1364141D03*
X279783Y124084D03*
X288597Y215535D03*
X288949Y246427D03*
X276801Y578594D03*
X288196Y679516D03*
X284232Y1335728D03*
X305266Y68123D03*
X301315Y95815D03*
X305315D03*
X293000Y219516D03*
X292949Y246427D03*
X292705Y582970D03*
X301791Y678706D03*
X305685Y687337D03*
X305662Y704658D03*
X295597Y1317379D03*
X291510Y1317805D03*
X310339Y228367D03*
X320966Y699666D03*
X317128Y1335700D03*
X325617Y73879D03*
X333988Y593820D03*
X334561Y698856D03*
X324557Y1317943D03*
X328501Y1317322D03*
X346695Y234071D03*
X342000Y277516D03*
X348157Y571356D03*
X338455Y707487D03*
X338432Y724808D03*
X350032Y1335643D03*
X352608Y276846D03*
X355828Y291906D03*
X354026Y699398D03*
X357310Y1317920D03*
X361301Y1317522D03*
X378184Y468867D03*
X375943Y534212D03*
X367621Y698588D03*
X371515Y707219D03*
X371492Y724540D03*
X386703Y123853D03*
X390859Y123900D03*
X387184Y473011D03*
X382184Y501617D03*
X392184D03*
X380771Y534154D03*
X387066Y699466D03*
X390110Y1318120D03*
X382832Y1335843D03*
X393883Y1336853D03*
X382992Y1674962D03*
X387324Y1675011D03*
X392324D03*
X407299Y206636D03*
X403299D03*
Y214587D03*
X407299D03*
X406184Y501617D03*
X397184D03*
X400673Y570869D03*
X400661Y698656D03*
X404555Y707287D03*
X404532Y724608D03*
X399000Y1624229D03*
X397324Y1675011D03*
X409000Y1677516D03*
X423299Y206636D03*
X415299D03*
X419299D03*
X415299Y214587D03*
X419984Y501540D03*
X410984D03*
X424784Y501463D03*
X420066Y681666D03*
X423926Y1029020D03*
X422692Y1337451D03*
X415414Y1355174D03*
X413000Y1677516D03*
X438673Y77216D03*
X433685Y91173D03*
X429685D03*
X429673Y77216D03*
X433673Y84216D03*
X438673D03*
X437997Y160641D03*
X433997D03*
X439299Y206636D03*
X435299D03*
X427299D03*
X431299D03*
Y214587D03*
X427299D03*
X435299D03*
X439500Y486516D03*
X433661Y680856D03*
X437555Y689487D03*
X437532Y706808D03*
X435146Y1029020D03*
X427666D03*
X431406D03*
X438886D03*
X426561Y1337435D03*
X428500Y1634016D03*
X442673Y84216D03*
X449997Y160641D03*
X445997D03*
X449997Y153641D03*
X445997D03*
X453997Y160641D03*
X443299Y206636D03*
X447299D03*
Y214587D03*
X443299D03*
X452466Y657066D03*
X450107Y1029020D03*
X442626D03*
X453847D03*
X446366D03*
X447576Y1644498D03*
X443594Y1644543D03*
X461997Y160641D03*
X469997D03*
X457931Y215194D03*
X465699Y285576D03*
X468500Y490016D03*
X466061Y656256D03*
X469955Y664887D03*
X469932Y682208D03*
X457587Y1029020D03*
X457000Y1644016D03*
X465000Y1647516D03*
X468500Y1711516D03*
X473997Y160641D03*
X481997D03*
X477997D03*
X484063Y308488D03*
X485066Y630566D03*
X498385Y108215D03*
X498661Y629756D03*
X502555Y638387D03*
X502532Y655708D03*
X528304Y211013D03*
X518500Y429516D03*
X522500D03*
X518366Y596466D03*
X531961Y595656D03*
X539503Y595432D03*
X543371Y595444D03*
X535855Y604287D03*
X535832Y621608D03*
X540106Y659816D03*
X550196Y184772D03*
X552699Y294576D03*
X573911Y214712D03*
X571063Y317488D03*
X568451Y1265034D03*
X564509Y1265030D03*
X586394Y90189D03*
X578454Y83155D03*
X577859Y214712D03*
X586500Y458016D03*
Y464516D03*
X583125Y751881D03*
X579125D03*
X587521Y751949D03*
X590501Y90189D03*
X602280D03*
X602328Y103586D03*
X590512D03*
X593758Y418721D03*
X603456Y751895D03*
X599489Y751881D03*
X595489D03*
X591521Y751949D03*
X618182Y90189D03*
X618256Y103586D03*
X608794Y191277D03*
X615385Y398669D03*
X607456Y751895D03*
X615443Y751907D03*
X611443D03*
X621310Y175625D03*
X630609Y227491D03*
X626705Y299821D03*
X631505Y286871D03*
X630195Y1386973D03*
X626295D03*
X634095D03*
X642301Y150067D03*
X638000Y415516D03*
X634244Y507554D03*
X646236Y1353453D03*
X638436D03*
X642436D03*
X656000Y518016D03*
Y510016D03*
X650036Y1353453D03*
X653836D03*
X657836D03*
X672800Y371878D03*
X676800D03*
X675500Y393378D03*
X666948Y398203D03*
X678071Y1308705D03*
X684643Y108901D03*
X680800Y371878D03*
X684800D03*
X693367Y363420D03*
X683500Y393378D03*
X679500D03*
X691500D03*
X699520Y363420D03*
X708500Y507878D03*
X704666Y507833D03*
X708509Y523861D03*
X704500Y524378D03*
X700500D03*
X708500Y540378D03*
X704500D03*
X696283Y540803D03*
X702645Y618627D03*
X698645D03*
X705657Y1381562D03*
X703799Y1627709D03*
X705688Y1647458D03*
X706623Y1663092D03*
X708953Y128184D03*
X719334Y363378D03*
X711458Y363376D03*
X716300Y376878D03*
X719500Y393378D03*
X723500D03*
X716500Y507878D03*
X720500D03*
X712500D03*
X712484Y523067D03*
X723032Y524331D03*
X719518Y524347D03*
X716016Y524441D03*
X710464Y549489D03*
X711845Y587733D03*
X711907Y603369D03*
X722129Y661183D03*
X718129D03*
X719152Y1627597D03*
X715309Y1677059D03*
X721909Y1681387D03*
X737093Y87993D03*
X737340Y115751D03*
X735449Y372044D03*
X731406Y376847D03*
X731500Y393378D03*
X727500D03*
X724500Y507878D03*
X737324Y524019D03*
X730310Y524299D03*
X733811Y524253D03*
X726793Y524365D03*
X724500Y540378D03*
X734557Y1381917D03*
X738439Y1381662D03*
X727188Y1399693D03*
X724723Y1627036D03*
X729616Y1677277D03*
X725632Y1677276D03*
X737467Y1680623D03*
X741270Y115675D03*
X739500Y376878D03*
X743500D03*
X748500Y540378D03*
X740500D03*
X751770Y1628299D03*
X752187Y1675010D03*
X741326Y1677073D03*
X745537Y1677158D03*
X745382Y1687286D03*
X760193Y93364D03*
X760500Y109516D03*
X759000Y363878D03*
X763500Y376878D03*
X767500Y393378D03*
X763500D03*
X760500Y540378D03*
X756500D03*
X767339Y1382017D03*
X759970Y1399793D03*
X758030Y1663099D03*
X772000Y524378D03*
X771216Y1382017D03*
X806500Y1327016D03*
X812526Y1345269D03*
X808526D03*
X831540Y62859D03*
X834616Y104297D03*
X835114Y117714D03*
X833715Y225084D03*
X831000Y508516D03*
X841900Y542313D03*
X834750Y566238D03*
X856630Y63009D03*
X850016Y90267D03*
X858783Y224499D03*
X863294Y266052D03*
X863571Y293901D03*
X867571D03*
X886503Y271423D03*
X925468Y264163D03*
X920268Y272375D03*
X922447Y1152591D03*
X949263Y274672D03*
X965442Y164901D03*
X969472Y1152591D03*
X985500Y152315D03*
X989605Y179569D03*
X985445Y179599D03*
X988835Y191969D03*
X988460Y363552D03*
X1005735Y157959D03*
X1001395Y218439D03*
X1004460Y363552D03*
X1000460D03*
X996460D03*
X992460D03*
X1009618Y399081D03*
X1020202Y538292D03*
X1007011Y550165D03*
X1034838Y538292D03*
X1030000Y557516D03*
X1035500D03*
X1050104Y1662400D03*
X1069236Y393973D03*
X1075526Y424480D03*
X1069839Y1363534D03*
X1092948Y476371D03*
X1091370Y1381855D03*
X1095489Y1696120D03*
X1094514Y1715932D03*
X1102439Y1363534D03*
X1098648Y1364132D03*
X1108747Y1535896D03*
X1109522Y1551449D03*
X1109000Y1665516D03*
X1098514Y1722932D03*
X1123970Y1381855D03*
X1114117Y1535896D03*
X1121010Y1588914D03*
X1125010D03*
X1115027Y1593267D03*
X1115394Y1622843D03*
X1112500Y1665516D03*
X1135139Y1363534D03*
X1131248Y1364132D03*
X1137846Y1456464D03*
X1133846D03*
X1132168Y1623481D03*
X1136097Y1623484D03*
X1166203Y74293D03*
X1163948Y1364132D03*
X1168039Y1363534D03*
X1156670Y1381855D03*
X1184000Y425941D03*
X1172000Y427516D03*
X1180000D03*
X1176000D03*
X1196848Y1364132D03*
X1189570Y1381855D03*
X1189407Y1712034D03*
X1200839Y1363534D03*
X1214254Y1713952D03*
Y1706952D03*
Y1727952D03*
Y1720952D03*
X1230312Y91151D03*
X1229648Y1364132D03*
X1222370Y1381855D03*
X1238830Y1317388D03*
X1233516Y1364122D03*
X1259472Y87380D03*
X1248859Y1420016D03*
X1252859D03*
X1253000Y1427016D03*
X1273677Y762004D03*
X1271726Y1317360D03*
X1267639Y1317786D03*
X1260361Y1335709D03*
X1275981Y87630D03*
X1284764Y92320D03*
X1280764D03*
X1288677Y759004D03*
X1277677Y762004D03*
X1281677D03*
X1296200Y61427D03*
X1292786Y545339D03*
X1298886Y593571D03*
X1292677Y762504D03*
X1296677D03*
X1300677Y759004D03*
X1300686Y1317924D03*
X1304630Y1317303D03*
X1293257Y1335681D03*
X1308110Y61427D03*
X1307366Y549729D03*
X1320020Y61495D03*
X1333399Y92600D03*
X1332360Y558711D03*
X1333439Y1317901D03*
X1326161Y1335624D03*
X1337399Y92600D03*
X1341399D03*
X1348199D03*
X1337430Y1317503D03*
X1356199Y92566D03*
X1352199D03*
X1360109D03*
X1350772Y674684D03*
X1358961Y1335824D03*
X1366018Y614609D03*
X1366239Y1318101D03*
X1370012Y1336834D03*
X1379613Y613799D03*
X1383507Y622430D03*
X1383484Y639751D03*
X1391543Y1355155D03*
X1398718Y647509D03*
X1403808Y1029019D03*
X1407548D03*
X1400068D03*
X1403690Y1286281D03*
X1398821Y1337432D03*
X1412313Y646699D03*
X1416207Y655330D03*
X1416184Y672651D03*
X1422508Y1029019D03*
X1415028D03*
X1411288D03*
X1418768D03*
X1419622Y1610283D03*
X1415623Y1599175D03*
X1438262Y55408D03*
X1434513Y109916D03*
X1439049Y116959D03*
X1431318Y680089D03*
X1429989Y1029019D03*
X1433729D03*
X1426249D03*
X1446869Y108377D03*
X1443049Y116959D03*
X1444769Y168733D03*
X1439769D03*
X1449769D03*
X1439769Y176733D03*
X1449769D03*
X1441741Y596382D03*
X1444913Y679279D03*
X1448807Y687910D03*
X1448784Y705231D03*
X1440500Y1617516D03*
X1445500D03*
X1449070Y1681238D03*
X1445079Y1681194D03*
X1454549Y116959D03*
X1460508Y136459D03*
X1454769Y168733D03*
X1464236Y699666D03*
X1461702Y1667904D03*
X1483820Y125774D03*
X1477831Y698856D03*
X1481725Y707487D03*
X1481702Y724808D03*
X1491560Y594553D03*
X1497318Y699666D03*
X1513644Y222191D03*
Y213341D03*
X1513348Y256554D03*
X1510913Y698856D03*
X1527853Y562780D03*
X1514807Y707487D03*
X1514784Y724808D03*
X1539693Y538129D03*
X1537853Y562780D03*
X1530118Y699666D03*
X1543713Y698856D03*
X1547607Y707487D03*
X1547584Y724808D03*
X1561345Y574714D03*
X1563248Y677726D03*
X1584079Y561624D03*
X1576843Y676916D03*
X1580737Y685547D03*
X1580714Y702868D03*
X1579177Y1262304D03*
X1596018Y643957D03*
X1605286Y547189D03*
X1609286D03*
X1609613Y643147D03*
X1613507Y651778D03*
X1613484Y669099D03*
X1625000Y386016D03*
X1629018Y624957D03*
X1621000Y1432516D03*
X1638334Y558303D03*
X1646507Y632778D03*
X1646484Y650099D03*
X1641804Y1308077D03*
X1636167Y1438994D03*
X1661928Y224688D03*
X1659610Y397218D03*
X1653790Y428560D03*
X1657545D03*
X1650035D03*
X1649979Y619062D03*
X1654147Y619014D03*
X1651959Y692763D03*
X1653390Y1380851D03*
X1649024Y1406737D03*
X1653024D03*
X1656824D03*
X1660624D03*
X1654513Y1708700D03*
X1658513Y1711850D03*
X1654513Y1715700D03*
Y1723850D03*
Y1730850D03*
X1663610Y397218D03*
X1674921Y1398982D03*
X1668424Y1406737D03*
X1664424D03*
X1689000Y228516D03*
X1688504Y401576D03*
X1690154Y428701D03*
X1682290Y1381206D03*
X1686172Y1380951D03*
X1681000Y1433516D03*
Y1440016D03*
X1684012Y1666257D03*
X1689513Y1708700D03*
Y1715700D03*
X1693000Y228516D03*
X1694314Y428671D03*
X1695529Y1545284D03*
X1716931Y75771D03*
X1711798Y75783D03*
Y62295D03*
X1716558D03*
X1721344Y62472D03*
X1713418Y125183D03*
X1710426Y407679D03*
X1715072Y1381306D03*
X1718949D03*
X1707703Y1399082D03*
X1726608Y105900D03*
X1730202Y1596109D03*
X1726202D03*
X1725423Y1687172D03*
X1735463Y1688981D03*
X1729436Y1687181D03*
X1728633Y1712206D03*
Y1720356D03*
X1732633Y1723506D03*
X1728633Y1727356D03*
X1750918Y125183D03*
X1751983Y258153D03*
X1737914Y1563223D03*
X1747963Y1644881D03*
X1740463Y1688981D03*
X1745463D03*
X1757322Y125187D03*
X1766606Y1563079D03*
X1760051Y1580348D03*
X1757963Y1647981D03*
X1752963Y1644881D03*
X1762963Y1647981D03*
X1767638Y69632D03*
X1767891Y97336D03*
X1771891D03*
X1773657Y1563723D03*
X1790738Y75003D03*
X1793444Y180660D03*
X1797011D03*
X1789811D03*
X1795794Y1580048D03*
X1800511Y180660D03*
X1804111D03*
X1807711D03*
X1811711Y177560D03*
X1802349Y1562779D03*
X1819705Y156888D03*
X1816308Y202045D03*
G54D147*
X312693Y59753D03*
X328441D03*
X747269Y79238D03*
X763017D03*
X1655999Y385598D03*
X1671747D03*
X1784364Y61037D03*
X1800112D03*
G54D165*
X391703Y1616822D03*
X399183D03*
X434260Y1634000D03*
X441740D03*
X666860Y1514200D03*
X674340D03*
X1674734Y1547200D03*
X1682214D03*
G54D219*
X641437Y1692156D03*
X643997D03*
X646556D03*
X638878D03*
Y1709734D03*
X641437D03*
X643997D03*
X646556D03*
G54D156*
X347673Y130005D03*
Y126265D03*
Y122525D03*
X357319D03*
Y130005D03*
X1492797Y134562D03*
Y127082D03*
X1502443D03*
Y130822D03*
Y134562D03*
G54D174*
X428899Y225205D03*
Y227764D03*
Y230323D03*
Y232883D03*
Y235442D03*
Y238001D03*
X451931Y225205D03*
Y238001D03*
Y235442D03*
Y232883D03*
Y230323D03*
Y227764D03*
X506945Y227882D03*
Y230441D03*
Y233000D03*
Y235560D03*
Y238119D03*
Y240678D03*
X529977D03*
Y238119D03*
Y235560D03*
Y233000D03*
Y230441D03*
Y227882D03*
G54D264*
X845291Y1526035D03*
X853479D03*
X945177Y1464749D03*
X953365D03*
G54D129*
X270414Y64236D03*
X288918D03*
X953693Y187871D03*
X972197D03*
X1686919Y386516D03*
X1705423D03*
X1730367Y75039D03*
X1748871D03*
G54D27*
X31099Y387783D03*
X24997D03*
X31099Y395067D03*
X24997D03*
X486949Y109959D03*
Y117243D03*
X493051D03*
Y109959D03*
G54D228*
X723436Y648667D03*
X716822D03*
X1148544Y1556029D03*
X1141930D03*
X1469652Y1679401D03*
X1476266D03*
G54D273*
X913386Y179390D03*
Y177027D03*
Y174665D03*
Y172303D03*
Y169941D03*
Y167579D03*
Y195925D03*
Y193563D03*
Y191201D03*
Y188838D03*
Y186476D03*
Y184114D03*
Y181752D03*
Y210098D03*
Y207736D03*
Y205374D03*
Y203012D03*
Y200649D03*
Y198287D03*
Y224272D03*
Y221909D03*
Y219547D03*
Y217185D03*
Y214823D03*
Y212461D03*
Y231358D03*
Y228996D03*
Y226634D03*
X931496Y179390D03*
Y177027D03*
Y174665D03*
Y172303D03*
Y169941D03*
Y167579D03*
Y195925D03*
Y193563D03*
Y191201D03*
Y188838D03*
Y186476D03*
Y184114D03*
Y181752D03*
Y210098D03*
Y207736D03*
Y205374D03*
Y203012D03*
Y200649D03*
Y198287D03*
Y224272D03*
Y221909D03*
Y219547D03*
Y217185D03*
Y214823D03*
Y212461D03*
Y231358D03*
Y228996D03*
Y226634D03*
G54D81*
X111369Y1683513D03*
X109269D03*
X107169D03*
X109269D03*
X111369Y1688013D03*
X109269D03*
X107169D03*
X109269D03*
X155811Y1661655D03*
X153711D03*
X155811D03*
Y1666210D03*
X153711D03*
X155811D03*
X168113Y1483690D03*
X170213D03*
X168113Y1480090D03*
X170213D03*
X165750Y1491010D03*
X167850D03*
X168113Y1501890D03*
X170213D03*
X168113Y1505490D03*
X170213D03*
X165640Y1494340D03*
X167740D03*
X163288Y1510800D03*
X165388D03*
X164288Y1518040D03*
X166388D03*
X169288Y1510800D03*
X171388D03*
X169288Y1514420D03*
X171388D03*
X169288Y1518040D03*
X171388D03*
X166383Y1523431D03*
X168483D03*
X166383Y1526631D03*
X168483D03*
X164650Y1534800D03*
X162550D03*
Y1531600D03*
X164650D03*
X162550Y1542500D03*
X164650D03*
X162550Y1538000D03*
X164650D03*
X157911Y1661655D03*
Y1666210D03*
X179786Y1649166D03*
X181886D03*
X179786Y1652366D03*
X181886D03*
X179786Y1655566D03*
X181886D03*
X186386Y1658766D03*
X179786D03*
X181886D03*
X188486D03*
X275621Y1480582D03*
X273521D03*
X275621Y1484182D03*
X273521D03*
X275621Y1493982D03*
X273521D03*
X275621Y1497582D03*
X273521D03*
X273350Y1535270D03*
X275450D03*
X273350Y1538370D03*
X275450D03*
X280450Y1506600D03*
X278350D03*
X283550Y1505000D03*
X285650D03*
X278350Y1503100D03*
X280450D03*
X296175Y1480090D03*
X298275D03*
X296175Y1483690D03*
X298275D03*
X296175Y1505490D03*
X298275D03*
X296175Y1501890D03*
X298275D03*
X297350Y1518040D03*
X299450D03*
X297350Y1514420D03*
X299450D03*
X292350Y1517640D03*
X294450D03*
X297350Y1510800D03*
X299450D03*
X291350D03*
X293450D03*
X294445Y1523431D03*
X296545D03*
X294445Y1526631D03*
X296545D03*
X296207Y1532851D03*
X294107D03*
X371850Y1579400D03*
X369750D03*
X371850Y1582600D03*
X369750D03*
X372950Y1639400D03*
X370850D03*
X379250D03*
X377150D03*
X379250Y1642600D03*
X377150D03*
X379250Y1649000D03*
X377150D03*
X379250Y1645800D03*
X377150D03*
X383673Y1576448D03*
X385773D03*
X403683Y1480582D03*
X401583D03*
X403683Y1484182D03*
X401583D03*
X403683Y1497582D03*
X401583D03*
X403683Y1493982D03*
X401583D03*
X408512Y1506600D03*
X406412D03*
Y1503100D03*
X404312D03*
X409150Y1544200D03*
Y1538000D03*
X403005Y1598560D03*
X400905D03*
X411612Y1505000D03*
X413712D03*
X411400Y1533440D03*
X413500D03*
X411250Y1544200D03*
Y1538000D03*
X418090Y1557310D03*
X415990D03*
X411319Y1563520D03*
X413419D03*
X432286Y1480090D03*
X434386D03*
X432286Y1483690D03*
X434386D03*
X432286Y1501890D03*
X434386D03*
X432286Y1505490D03*
X434386D03*
X433461Y1518040D03*
X435561D03*
X433461Y1514420D03*
X435561D03*
X428461Y1517640D03*
X430561D03*
X433461Y1510800D03*
X435561D03*
X427461D03*
X429561D03*
X430556Y1523431D03*
X432656D03*
X430556Y1526631D03*
X432656D03*
X434558Y1563907D03*
X436658D03*
X431491Y1596983D03*
X429391D03*
X445567Y1579843D03*
X447667D03*
X463950Y1579400D03*
X466050D03*
X463950Y1576200D03*
X466050D03*
X513770Y107320D03*
X511670D03*
X518270D03*
X520370D03*
X539794Y1484182D03*
X537694D03*
X539794Y1480582D03*
X537694D03*
X539794Y1493982D03*
X537694D03*
X539794Y1497582D03*
X537694D03*
X542523Y1506600D03*
Y1503100D03*
X537547Y1534709D03*
X539647D03*
X537547Y1539572D03*
X539647D03*
X548338Y1503960D03*
X550438D03*
X544623Y1506600D03*
Y1503100D03*
X556523Y1517640D03*
X558623D03*
X555523Y1510800D03*
X557623D03*
X558618Y1523431D03*
Y1526631D03*
X558280Y1532851D03*
X560348Y1483690D03*
X562448D03*
X560348Y1480090D03*
X562448D03*
X560348Y1501890D03*
X562448D03*
X560348Y1505490D03*
X562448D03*
X561523Y1518040D03*
X563623D03*
X561523Y1514420D03*
X563623D03*
X561523Y1510800D03*
X563623D03*
X560718Y1523431D03*
Y1526631D03*
X560380Y1532851D03*
X643455Y1685970D03*
X641355D03*
X649750Y1652400D03*
X651850D03*
X667856Y1484182D03*
X665756D03*
X667856Y1480582D03*
X665756D03*
X667856Y1493982D03*
X665756D03*
X667856Y1497582D03*
X665756D03*
X672099Y1505135D03*
X674199D03*
Y1508335D03*
X672099D03*
X674536Y1652759D03*
X676636D03*
X667312Y1689063D03*
X665212D03*
X686211Y1537520D03*
X684111D03*
X691211D03*
X689111D03*
X686211Y1540720D03*
X684111D03*
X691211D03*
X689111D03*
X698990Y1536250D03*
X701090D03*
X698990Y1531700D03*
X701090D03*
X698990Y1548400D03*
X701090D03*
X698990Y1551700D03*
X701090D03*
X698990Y1541800D03*
X701090D03*
X711792Y173587D03*
X709692D03*
X711792Y177187D03*
X709692D03*
X711792Y185587D03*
X709692D03*
X711792Y189187D03*
X709692D03*
X711792Y197087D03*
X709692D03*
X711792Y200687D03*
X709692D03*
X711792Y208921D03*
X709692D03*
X711792Y212521D03*
X709692D03*
X709150Y1545100D03*
X711250D03*
X709150Y1551700D03*
X711250D03*
X709150Y1538500D03*
X711250D03*
X942596Y208375D03*
X940496D03*
X942596Y204775D03*
X940496D03*
X942596Y211897D03*
X940496D03*
X942596Y215497D03*
X940496D03*
X942596Y229635D03*
X940496D03*
X942596Y226035D03*
X940496D03*
X949296Y218948D03*
X947196D03*
X949296Y222548D03*
X947196D03*
X1141310Y1565312D03*
X1143410D03*
X1148727Y1565315D03*
X1146627D03*
X1161522Y1544575D03*
X1159422D03*
X1170423Y1564600D03*
X1160818Y1554023D03*
X1158718D03*
X1170423Y1575500D03*
Y1571000D03*
Y1567800D03*
X1175986Y1516690D03*
X1178086D03*
X1175986Y1513090D03*
X1178086D03*
X1175986Y1534890D03*
X1178086D03*
X1175986Y1538490D03*
X1178086D03*
X1177161Y1551040D03*
X1179261D03*
X1177161Y1547420D03*
X1179261D03*
X1172161Y1551040D03*
X1174261D03*
X1177161Y1543800D03*
X1179261D03*
X1171161D03*
X1173261D03*
X1174256Y1556431D03*
X1176356D03*
X1174256Y1559631D03*
X1176356D03*
X1172523Y1564600D03*
Y1575500D03*
Y1571000D03*
Y1567800D03*
X1283494Y1517182D03*
X1281394D03*
X1283494Y1513582D03*
X1281394D03*
X1283494Y1530582D03*
X1281394D03*
X1283494Y1526982D03*
X1281394D03*
X1286223Y1536100D03*
X1288323D03*
Y1539600D03*
X1286223D03*
X1281223Y1571370D03*
X1283323D03*
X1281223Y1568270D03*
X1283323D03*
X1304048Y1513090D03*
Y1516690D03*
Y1534890D03*
X1301834Y1528147D03*
X1303934D03*
X1301834Y1525001D03*
X1303934D03*
X1304048Y1538490D03*
X1291423Y1538000D03*
X1293523D03*
X1300223Y1550640D03*
X1302323D03*
X1299223Y1543800D03*
X1301323D03*
X1302318Y1556431D03*
X1304418D03*
X1302318Y1559631D03*
X1304418D03*
X1304080Y1565851D03*
X1301980D03*
X1306148Y1513090D03*
Y1516690D03*
Y1534890D03*
Y1538490D03*
X1305223Y1543800D03*
X1307323D03*
X1305223Y1551040D03*
X1307323D03*
X1305223Y1547420D03*
X1307323D03*
X1411556Y1517182D03*
X1409456D03*
X1411556Y1513582D03*
X1409456D03*
X1411556Y1526982D03*
X1409456D03*
X1411556Y1530582D03*
X1409456D03*
X1414285Y1536100D03*
X1412185D03*
X1419485Y1538000D03*
X1421585D03*
X1416385Y1539600D03*
X1414285D03*
X1419273Y1566440D03*
X1421373D03*
X1417023Y1577200D03*
X1419123D03*
X1416950Y1580400D03*
X1419050D03*
X1417023Y1571000D03*
X1419123D03*
X1436335Y1550640D03*
X1438435D03*
X1435335Y1543800D03*
X1437435D03*
X1438430Y1556431D03*
Y1559631D03*
X1440160Y1513090D03*
X1442260D03*
X1440160Y1516690D03*
X1442260D03*
X1440160Y1534890D03*
X1442260D03*
X1440160Y1538490D03*
X1442260D03*
X1441335Y1543800D03*
X1443435D03*
X1441335Y1551040D03*
X1443435D03*
X1441335Y1547420D03*
X1443435D03*
X1440530Y1556431D03*
Y1559631D03*
X1441187Y1682665D03*
X1439087D03*
X1441187Y1686165D03*
X1439087D03*
X1439050Y1679544D03*
X1441150D03*
X1439067Y1689273D03*
X1441167D03*
X1482680Y1668917D03*
X1480580D03*
X1482450Y1678500D03*
X1484550D03*
X1547668Y1513582D03*
X1545568D03*
X1547668Y1517182D03*
X1545568D03*
X1547668Y1530582D03*
X1545568D03*
X1547668Y1526982D03*
X1545568D03*
X1550396Y1536100D03*
X1552496D03*
X1555596Y1538000D03*
X1557696D03*
X1552496Y1539600D03*
X1550396D03*
X1545396Y1571370D03*
X1547496D03*
X1545397Y1568270D03*
X1547497D03*
X1568222Y1513090D03*
X1570322D03*
X1568222Y1516690D03*
X1570322D03*
X1568222Y1534890D03*
X1570322D03*
X1568222Y1538490D03*
X1570322D03*
X1564397Y1550640D03*
X1566497D03*
X1569397Y1543800D03*
X1571497D03*
X1563397D03*
X1565497D03*
X1569397Y1551040D03*
X1571497D03*
X1569397Y1547420D03*
X1571497D03*
X1566492Y1556431D03*
X1568592D03*
X1566492Y1559631D03*
X1568592D03*
X1568253Y1565851D03*
X1566153D03*
X1656089Y1704237D03*
X1658189D03*
X1675730Y1517182D03*
X1673630D03*
X1675730Y1513582D03*
X1673630D03*
X1675730Y1530582D03*
X1673630D03*
X1675730Y1526982D03*
X1673630D03*
X1668268Y1670149D03*
X1666168D03*
X1679972Y1538135D03*
X1682072D03*
Y1541335D03*
X1679972D03*
X1691975Y1570520D03*
Y1573720D03*
X1694075Y1570520D03*
Y1573720D03*
X1700950Y1595000D03*
X1703050D03*
X1700950Y1598100D03*
X1703050D03*
X1700950Y1604300D03*
X1703050D03*
X1700950Y1601200D03*
X1703050D03*
X1700950Y1607400D03*
X1703050D03*
X1715693Y1606340D03*
X1717793D03*
X1715693Y1599740D03*
X1717793D03*
X1715693Y1612940D03*
X1717793D03*
G54D138*
X268312Y605247D03*
X281698Y594223D03*
G54D246*
X776768Y1581379D03*
Y1579410D03*
Y1577442D03*
Y1587284D03*
Y1585316D03*
Y1583347D03*
X794386Y1577442D03*
Y1581379D03*
Y1579410D03*
Y1587284D03*
Y1583347D03*
Y1585316D03*
X818768Y1581379D03*
Y1579410D03*
Y1577442D03*
Y1587284D03*
Y1585316D03*
Y1583347D03*
X836386Y1577442D03*
Y1581379D03*
Y1579410D03*
Y1587284D03*
Y1583347D03*
Y1585316D03*
X860768Y1581379D03*
Y1579410D03*
Y1577442D03*
Y1587284D03*
Y1585316D03*
Y1583347D03*
X878386Y1577442D03*
Y1581379D03*
Y1579410D03*
Y1587284D03*
Y1583347D03*
Y1585316D03*
X902768Y1581379D03*
Y1579410D03*
Y1577442D03*
Y1587284D03*
Y1585316D03*
Y1583347D03*
X920386Y1577442D03*
Y1581379D03*
Y1579410D03*
Y1587284D03*
Y1583347D03*
Y1585316D03*
G54D309*
X1627179Y576851D03*
Y611015D03*
G54D90*
X138003Y1663229D03*
G54D54*
X65205Y1526394D03*
X100948D03*
X112601Y1360516D03*
X145201D03*
X177901D03*
X210801D03*
X243601D03*
X277201Y1314370D03*
X310097Y1314342D03*
X343001Y1314285D03*
X375801Y1314485D03*
X408383Y1333816D03*
X720157Y1378525D03*
X752939Y1378625D03*
X1084339Y1360497D03*
X1116939D03*
X1149639D03*
X1182539D03*
X1215339D03*
X1253330Y1314351D03*
X1286226Y1314323D03*
X1319130Y1314266D03*
X1351930Y1314466D03*
X1384512Y1333797D03*
X1667890Y1377814D03*
X1700672Y1377914D03*
X1752488Y1559430D03*
X1788231D03*
G54D192*
X476826Y304928D03*
X563826Y313928D03*
G54D36*
X53333Y527713D03*
G54D63*
X65446Y1665880D03*
G54D291*
X1091434Y1538875D03*
Y1562693D03*
G54D318*
X1797245Y201297D03*
G54D327*
X1859986Y1403418D03*
X1859706Y1709011D03*
X1866790Y463389D03*
X1871790Y476573D03*
X1861790D03*
X1870648Y783729D03*
X1860648D03*
X1865648Y796913D03*
X1867295Y837583D03*
X1862295Y850767D03*
X1872295D03*
X1871790Y1158071D03*
X1861790D03*
X1866790Y1171255D03*
X1864986Y1390234D03*
X1869986Y1403418D03*
X1869706Y1709011D03*
X1864706Y1722195D03*
X1886862Y94107D03*
X1881862Y107291D03*
X1882340Y410829D03*
X1887340Y424013D03*
X1887711Y463680D03*
X1882711Y476864D03*
X1882240Y783474D03*
X1887240Y796658D03*
X1888273Y837632D03*
X1883273Y850816D03*
X1882579Y1158348D03*
X1887579Y1171532D03*
X1886223Y1391283D03*
X1881223Y1404467D03*
X1881177Y1709323D03*
X1886177Y1722507D03*
X1891862Y107291D03*
X1892340Y410829D03*
X1892711Y476864D03*
X1892240Y783474D03*
X1893273Y850816D03*
X1892579Y1158348D03*
X1891223Y1404467D03*
X1891177Y1709323D03*
X2077012Y95128D03*
X2082012Y108312D03*
X2072012D03*
X2071128Y410829D03*
X2081128D03*
X2076128Y424013D03*
G54D237*
X731743Y-23871D03*
X1183222Y-20011D03*
Y-11D03*
Y19989D03*
X1442081Y-20011D03*
Y-11D03*
Y19989D03*
X1735375Y-24212D03*
G54D45*
X60303Y20354D03*
X312921Y24291D03*
X505185Y41141D03*
X757803Y45078D03*
X929331Y160413D03*
X922441Y237697D03*
X1534712Y20354D03*
X1787330Y24291D03*
G54D72*
X102160Y1444500D03*
X103950Y1436000D03*
X246314Y561512D03*
X265210Y559512D03*
X527280Y120930D03*
X533520Y122200D03*
X663728Y422820D03*
X666919Y471854D03*
X829390Y1466384D03*
X818885Y1467654D03*
X1189242Y1465128D03*
X1178737Y1466398D03*
X1310450Y556184D03*
X1662146Y1414965D03*
G54D282*
X968690Y1633144D03*
Y1659128D03*
X996314Y1633113D03*
Y1659097D03*
G54D183*
X481211Y215652D03*
Y217227D03*
X488297D03*
Y215652D03*
Y214077D03*
X509320Y212498D03*
Y214072D03*
X514832D03*
X572342Y223921D03*
Y225496D03*
Y227071D03*
X579428Y223921D03*
Y225496D03*
X796276Y1342737D03*
Y1341162D03*
Y1339587D03*
Y1338012D03*
Y1336438D03*
Y1345886D03*
Y1344312D03*
X905618Y1143945D03*
Y1145519D03*
Y1147094D03*
Y1148669D03*
Y1150244D03*
Y1151819D03*
Y1153393D03*
X952643Y1143945D03*
Y1145519D03*
Y1147094D03*
Y1148669D03*
Y1150244D03*
Y1151819D03*
Y1153393D03*
X1315411Y549885D03*
Y551459D03*
Y553034D03*
Y554609D03*
Y556184D03*
Y557759D03*
Y559333D03*
X1621536Y549540D03*
Y551114D03*
Y552689D03*
Y554264D03*
Y555839D03*
Y557414D03*
Y558988D03*
G54D255*
X804455Y1345269D03*
G54D346*
G01X302468Y1012647D02*
X299926Y1015189D01*
X292202D01*
X281102Y1004089D01*
X268635D01*
X263768Y1008956D01*
X230109D01*
X225759Y1004606D01*
Y1001946D01*
X223933Y1000120D01*
X220805D01*
X219802Y1001123D01*
X217827D01*
G01X301520Y1011699D02*
X299370Y1013849D01*
X292758D01*
X281658Y1002749D01*
X268079D01*
X263212Y1007616D01*
X230665D01*
X227099Y1004050D01*
Y1001390D01*
X224489Y998780D01*
X220803D01*
X219800Y997777D01*
X217827D01*
G01X321645Y1011419D02*
X319807Y1010372D01*
G01X319795Y1008230D02*
X317957Y1007183D01*
G01X332748Y1011419D02*
X330910Y1010372D01*
G01X334598Y1008230D02*
X332760Y1007183D01*
G01X347551Y1011419D02*
X345713Y1010372D01*
G01X345700Y1008230D02*
X343862Y1007183D01*
G01X358653Y1011419D02*
X356815Y1010372D01*
G01X360504Y1008230D02*
X358665Y1007183D01*
G01X373456Y1011419D02*
X371618Y1010372D01*
G01X371606Y1008230D02*
X369768Y1007183D01*
G01X506685Y1011419D02*
X508523Y1010372D01*
G01X508535Y1008230D02*
X510373Y1007183D01*
G01X521488Y1011419D02*
X523326Y1010372D01*
G01X519637Y1008230D02*
X521475Y1007183D01*
G01X532590Y1011419D02*
X534428Y1010372D01*
G01X534441Y1008230D02*
X536279Y1007183D01*
G01X558496Y1011419D02*
X560334Y1010372D01*
G01X547393Y1011419D02*
X549231Y1010372D01*
G01X545543Y1008230D02*
X547381Y1007183D01*
G01X578865Y1011646D02*
X592662D01*
X600209Y1004099D01*
X612606D01*
X616009Y1007502D01*
X619452D01*
X620179Y1008229D01*
Y1010730D01*
X621690Y1012241D01*
X623829D01*
X625340Y1010730D01*
Y1008229D01*
X626067Y1007502D01*
X627094D01*
X627821Y1008229D01*
Y1010730D01*
X629332Y1012241D01*
X631471D01*
X632982Y1010730D01*
Y1008229D01*
X633709Y1007502D01*
X635222D01*
X642604Y1000120D01*
X644375D01*
X645378Y1001123D01*
X647354D01*
G01X578865Y1010306D02*
X592106D01*
X599653Y1002759D01*
X613162D01*
X616565Y1006162D01*
X620008D01*
X621519Y1007673D01*
Y1010174D01*
X622246Y1010901D01*
X623273D01*
X624000Y1010174D01*
Y1007673D01*
X625511Y1006162D01*
X627650D01*
X629161Y1007673D01*
Y1010174D01*
X629888Y1010901D01*
X630915D01*
X631642Y1010174D01*
Y1007673D01*
X633153Y1006162D01*
X634666D01*
X642048Y998780D01*
X644375D01*
X645378Y997777D01*
X647354D01*
G01X560346Y1008230D02*
X562184Y1007183D01*
G01X1278610Y1012646D02*
X1276068Y1015188D01*
X1268344D01*
X1257244Y1004088D01*
X1244777D01*
X1239910Y1008955D01*
X1206251D01*
X1201901Y1004605D01*
Y1001945D01*
X1200075Y1000119D01*
X1196947D01*
X1195944Y1001122D01*
X1193969D01*
G01X1277662Y1011698D02*
X1275512Y1013848D01*
X1268900D01*
X1257800Y1002748D01*
X1244221D01*
X1239354Y1007615D01*
X1206807D01*
X1203241Y1004049D01*
Y1001389D01*
X1200631Y998779D01*
X1196945D01*
X1195942Y997776D01*
X1193969D01*
G01X1290386Y1011418D02*
X1288548Y1010371D01*
G01X1297787Y1011418D02*
X1295949Y1010371D01*
G01X1295937Y1008229D02*
X1294099Y1007182D01*
G01X1301488Y1011418D02*
X1299650Y1010371D01*
G01X1308890Y1011418D02*
X1307052Y1010371D01*
G01X1310740Y1008229D02*
X1308902Y1007182D01*
G01X1316291Y1011418D02*
X1314453Y1010371D01*
G01X1323693Y1011418D02*
X1321855Y1010371D01*
G01X1321842Y1008229D02*
X1320004Y1007182D01*
G01X1334795Y1011418D02*
X1332957Y1010371D01*
G01X1327394Y1011418D02*
X1325556Y1010371D01*
G01X1349598Y1011418D02*
X1347760Y1010371D01*
G01X1347748Y1008229D02*
X1345910Y1007182D01*
G01X1336646Y1008229D02*
X1334807Y1007182D01*
G01X1342197Y1011418D02*
X1340359Y1010371D01*
G01X1353299Y1011418D02*
X1351461Y1010371D01*
G01X1482827Y1011418D02*
X1484665Y1010371D01*
G01X1484677Y1008229D02*
X1486515Y1007182D01*
G01X1497630Y1011418D02*
X1499468Y1010371D01*
G01X1495779Y1008229D02*
X1497617Y1007182D01*
G01X1508732Y1011418D02*
X1510570Y1010371D01*
G01X1510583Y1008229D02*
X1512421Y1007182D01*
G01X1523535Y1011418D02*
X1525373Y1010371D01*
G01X1521685Y1008229D02*
X1523523Y1007182D01*
G01X1534638Y1011418D02*
X1536476Y1010371D01*
G01X1536488Y1008229D02*
X1538326Y1007182D01*
G01X1555007Y1011645D02*
X1568808D01*
X1576355Y1004098D01*
X1588748D01*
X1592151Y1007501D01*
X1595594D01*
X1596321Y1008228D01*
Y1010729D01*
X1597832Y1012240D01*
X1599971D01*
X1601482Y1010729D01*
Y1008228D01*
X1602209Y1007501D01*
X1603236D01*
X1603963Y1008228D01*
Y1010729D01*
X1605474Y1012240D01*
X1607613D01*
X1609124Y1010729D01*
Y1008228D01*
X1609851Y1007501D01*
X1611364D01*
X1618746Y1000119D01*
X1620517D01*
X1621520Y1001122D01*
X1623496D01*
G01X1555007Y1010305D02*
X1568252D01*
X1575799Y1002758D01*
X1589304D01*
X1592707Y1006161D01*
X1596150D01*
X1597661Y1007672D01*
Y1010173D01*
X1598388Y1010900D01*
X1599415D01*
X1600142Y1010173D01*
Y1007672D01*
X1601653Y1006161D01*
X1603792D01*
X1605303Y1007672D01*
Y1010173D01*
X1606030Y1010900D01*
X1607057D01*
X1607784Y1010173D01*
Y1007672D01*
X1609295Y1006161D01*
X1610808D01*
X1618190Y998779D01*
X1620517D01*
X1621520Y997776D01*
X1623496D01*
G01X2078539Y582541D02*
X2074796D01*
X2074273Y583064D01*
Y1174161D01*
X2074853Y1174741D01*
X2078539D01*
G01X2068539Y582541D02*
X2072509D01*
X2072933Y582965D01*
Y1174157D01*
X2072349Y1174741D01*
X2068539D01*
G54D337*
G01X796276Y1347855D02*
X797338D01*
X799071Y1349588D01*
Y1350088D01*
G54D19*
X17363Y233231D03*
X10543Y233275D03*
X36595Y388035D03*
X32774Y528853D03*
X46834Y366395D03*
X50631Y1533154D03*
X42150Y1553563D03*
X46150D03*
X45633Y1598379D03*
X50133D03*
X55190Y366395D03*
X64442Y507448D03*
X53299Y549778D03*
X63148Y549743D03*
X58365D03*
X59427Y1649870D03*
X66127Y1684870D03*
X76378Y1412138D03*
X72378D03*
X79323Y1533010D03*
X72768Y1550279D03*
X76806Y1599390D03*
X78406Y1607690D03*
X73427Y1649870D03*
X68427D03*
X82127Y1684870D03*
X86374Y1533654D03*
X90127Y1684870D03*
X92257Y1724314D03*
X98101Y1366520D03*
X108511Y1549979D03*
X115016Y297680D03*
Y318114D03*
X118407Y524274D03*
X126910Y1367118D03*
X119632Y1384841D03*
X115066Y1532710D03*
X120353Y1652070D03*
X124353D03*
X116353D03*
X123353Y1693449D03*
X140360Y427063D03*
X130701Y1366520D03*
X140353Y1652070D03*
X128353D03*
X127353Y1693570D03*
X132767Y1726224D03*
X150318Y213441D03*
Y221441D03*
X152232Y1384841D03*
X143500Y1445483D03*
X147000D03*
X148353Y1652070D03*
X144253D03*
X147253Y1693570D03*
X154740Y1710483D03*
X149900Y1715849D03*
Y1722849D03*
X159510Y1366891D03*
X163401Y1366520D03*
X159427Y1693570D03*
X162740Y1710483D03*
X167500Y1718483D03*
X184932Y1384841D03*
X181760Y1710371D03*
X185760Y1728859D03*
X189410Y393643D03*
X192210Y1367118D03*
X196301Y1366520D03*
X189760Y1710371D03*
X194000Y1717983D03*
X211000Y1714983D03*
X228675Y567092D03*
X225110Y1367118D03*
X229101Y1366520D03*
X217832Y1384841D03*
X236266Y65345D03*
X240266D03*
X244266D03*
X232817Y567060D03*
X239843Y715231D03*
X248266Y65345D03*
X251487Y107743D03*
X255270Y214953D03*
X255466Y648242D03*
X257910Y1367118D03*
X250632Y1384841D03*
X275797Y127026D03*
X262466Y598136D03*
X269405Y585018D03*
X263866Y590937D03*
X269061Y647432D03*
X272955Y656063D03*
X272932Y673384D03*
X262701Y1320374D03*
X261778Y1367108D03*
X279783Y127051D03*
X288597Y218502D03*
X288949Y249394D03*
X276801Y581561D03*
X288196Y682483D03*
X284232Y1338695D03*
X305266Y71090D03*
X301315Y98782D03*
X305315D03*
X293000Y222483D03*
X292949Y249394D03*
X292705Y585937D03*
X301791Y681673D03*
X305685Y690304D03*
X305662Y707625D03*
X295597Y1320346D03*
X291510Y1320772D03*
X310339Y231334D03*
X320966Y702633D03*
X317128Y1338667D03*
X325617Y76846D03*
X333988Y596787D03*
X334561Y701823D03*
X324557Y1320910D03*
X328501Y1320289D03*
X346695Y237038D03*
X342000Y280483D03*
X348157Y574323D03*
X338455Y710454D03*
X338432Y727775D03*
X350032Y1338610D03*
X352608Y279813D03*
X355828Y294873D03*
X354026Y702365D03*
X357310Y1320887D03*
X361301Y1320489D03*
X378184Y471834D03*
X375943Y537179D03*
X367621Y701555D03*
X371515Y710186D03*
X371492Y727507D03*
X386703Y126820D03*
X390859Y126867D03*
X387184Y475978D03*
X382184Y504584D03*
X392184D03*
X380771Y537121D03*
X387066Y702433D03*
X390110Y1321087D03*
X382832Y1338810D03*
X393883Y1339820D03*
X382992Y1677929D03*
X387324Y1677978D03*
X392324D03*
X407299Y209603D03*
X403299D03*
Y217554D03*
X407299D03*
X406184Y504584D03*
X397184D03*
X400673Y573836D03*
X400661Y701623D03*
X404555Y710254D03*
X404532Y727575D03*
X399000Y1627196D03*
X397324Y1677978D03*
X409000Y1680483D03*
X423299Y209603D03*
X415299D03*
X419299D03*
X415299Y217554D03*
X419984Y504507D03*
X410984D03*
X424784Y504430D03*
X420066Y684633D03*
X423926Y1031987D03*
X422692Y1340418D03*
X415414Y1358141D03*
X413000Y1680483D03*
X438673Y80183D03*
X429673D03*
X433673Y87183D03*
X438673D03*
X433685Y94140D03*
X429685D03*
X437997Y163608D03*
X433997D03*
X439299Y209603D03*
X435299D03*
X427299D03*
X431299D03*
Y217554D03*
X427299D03*
X435299D03*
X439500Y489483D03*
X433661Y683823D03*
X437555Y692454D03*
X437532Y709775D03*
X435146Y1031987D03*
X427666D03*
X431406D03*
X438886D03*
X426561Y1340402D03*
X428500Y1636983D03*
X442673Y87183D03*
X449997Y163608D03*
X445997D03*
X449997Y156608D03*
X445997D03*
X453997Y163608D03*
X443299Y209603D03*
X447299D03*
Y217554D03*
X443299D03*
X452466Y660033D03*
X450107Y1031987D03*
X442626D03*
X453847D03*
X446366D03*
X447576Y1647465D03*
X443594Y1647510D03*
X461997Y163608D03*
X469997D03*
X457931Y218161D03*
X465699Y288543D03*
X468500Y492983D03*
X466061Y659223D03*
X469955Y667854D03*
X469932Y685175D03*
X457587Y1031987D03*
X457000Y1646983D03*
X465000Y1650483D03*
X468500Y1714483D03*
X473997Y163608D03*
X481997D03*
X477997D03*
X484063Y311455D03*
X485066Y633533D03*
X498385Y111182D03*
X498661Y632723D03*
X502555Y641354D03*
X502532Y658675D03*
X528304Y213980D03*
X518500Y432483D03*
X522500D03*
X518366Y599433D03*
X531961Y598623D03*
X539503Y598399D03*
X543371Y598411D03*
X535855Y607254D03*
X535832Y624575D03*
X540106Y662783D03*
X550196Y187739D03*
X552699Y297543D03*
X573911Y217679D03*
X571063Y320455D03*
X568451Y1268001D03*
X564509Y1267997D03*
X578454Y86122D03*
X586394Y93156D03*
X577859Y217679D03*
X586500Y460983D03*
Y467483D03*
X583125Y754848D03*
X579125D03*
X587521Y754916D03*
X602328Y106553D03*
X590512D03*
X590501Y93156D03*
X602280D03*
X593758Y421688D03*
X603456Y754862D03*
X599489Y754848D03*
X595489D03*
X591521Y754916D03*
X618256Y106553D03*
X618182Y93156D03*
X608794Y194244D03*
X615385Y401636D03*
X607456Y754862D03*
X615443Y754874D03*
X611443D03*
X621310Y178592D03*
X630609Y230458D03*
X631505Y289838D03*
X626705Y302788D03*
X630195Y1389940D03*
X626295D03*
X634095D03*
X642301Y153034D03*
X638000Y418483D03*
X634244Y510521D03*
X646236Y1356420D03*
X638436D03*
X642436D03*
X656000Y520983D03*
Y512983D03*
X650036Y1356420D03*
X653836D03*
X657836D03*
X672800Y374845D03*
X676800D03*
X675500Y396345D03*
X666948Y401170D03*
X678071Y1311672D03*
X684643Y111868D03*
X680800Y374845D03*
X684800D03*
X693367Y366387D03*
X683500Y396345D03*
X679500D03*
X691500D03*
X699520Y366387D03*
X708500Y510845D03*
X704666Y510800D03*
X704500Y527345D03*
X700500D03*
X708509Y526828D03*
X708500Y543345D03*
X704500D03*
X696283Y543770D03*
X702645Y621594D03*
X698645D03*
X705657Y1384529D03*
X703799Y1630676D03*
X705688Y1650425D03*
X706623Y1666059D03*
X708953Y131151D03*
X719334Y366345D03*
X711458Y366343D03*
X716300Y379845D03*
X719500Y396345D03*
X723500D03*
X716500Y510845D03*
X720500D03*
X712500D03*
X723032Y527298D03*
X719518Y527314D03*
X712484Y526034D03*
X716016Y527408D03*
X710464Y552456D03*
X711845Y590700D03*
X711907Y606336D03*
X722129Y664150D03*
X718129D03*
X719152Y1630564D03*
X715309Y1680026D03*
X721909Y1684354D03*
X737093Y90960D03*
X737340Y118718D03*
X735449Y375011D03*
X731406Y379814D03*
X731500Y396345D03*
X727500D03*
X724500Y510845D03*
X730310Y527266D03*
X733811Y527220D03*
X726793Y527332D03*
X737324Y526986D03*
X724500Y543345D03*
X734557Y1384884D03*
X738439Y1384629D03*
X727188Y1402660D03*
X724723Y1630003D03*
X729616Y1680244D03*
X725632Y1680243D03*
X737467Y1683590D03*
X741270Y118642D03*
X739500Y379845D03*
X743500D03*
X748500Y543345D03*
X740500D03*
X751770Y1631266D03*
X752187Y1677977D03*
X741326Y1680040D03*
X745537Y1680125D03*
X745382Y1690253D03*
X760193Y96331D03*
X760500Y112483D03*
X759000Y366845D03*
X763500Y379845D03*
X767500Y396345D03*
X763500D03*
X760500Y543345D03*
X756500D03*
X767339Y1384984D03*
X759970Y1402760D03*
X758030Y1666066D03*
X772000Y527345D03*
X771216Y1384984D03*
X806500Y1329983D03*
X812526Y1348236D03*
X808526D03*
X831540Y65826D03*
X834616Y107264D03*
X835114Y120681D03*
X833715Y228051D03*
X831000Y511483D03*
X841900Y545280D03*
X834750Y569205D03*
X856630Y65976D03*
X850016Y93234D03*
X858783Y227466D03*
X863294Y269019D03*
X863571Y296868D03*
X867571D03*
X886503Y274390D03*
X925468Y267130D03*
X920268Y275342D03*
X922447Y1155558D03*
X949263Y277639D03*
X965442Y167868D03*
X969472Y1155558D03*
X985500Y155282D03*
X989605Y182536D03*
X988835Y194936D03*
X985445Y182566D03*
X988460Y366519D03*
X1005735Y160926D03*
X1001395Y221406D03*
X1004460Y366519D03*
X1000460D03*
X996460D03*
X992460D03*
X1009618Y402048D03*
X1020202Y541259D03*
X1007011Y553132D03*
X1034838Y541259D03*
X1030000Y560483D03*
X1035500D03*
X1050104Y1665367D03*
X1069236Y396940D03*
X1075526Y427447D03*
X1069839Y1366501D03*
X1092948Y479338D03*
X1091370Y1384822D03*
X1095489Y1699087D03*
X1094514Y1718899D03*
X1102439Y1366501D03*
X1098648Y1367099D03*
X1108747Y1538863D03*
X1109522Y1554416D03*
X1109000Y1668483D03*
X1098514Y1725899D03*
X1123970Y1384822D03*
X1114117Y1538863D03*
X1121010Y1591881D03*
X1125010D03*
X1115027Y1596234D03*
X1115394Y1625810D03*
X1112500Y1668483D03*
X1135139Y1366501D03*
X1131248Y1367099D03*
X1137846Y1459431D03*
X1133846D03*
X1132168Y1626448D03*
X1136097Y1626451D03*
X1166203Y77260D03*
X1163948Y1367099D03*
X1168039Y1366501D03*
X1156670Y1384822D03*
X1184000Y428908D03*
X1172000Y430483D03*
X1180000D03*
X1176000D03*
X1196848Y1367099D03*
X1189570Y1384822D03*
X1189407Y1715001D03*
X1200839Y1366501D03*
X1214254Y1709919D03*
Y1730919D03*
Y1723919D03*
Y1716919D03*
X1230312Y94118D03*
X1229648Y1367099D03*
X1222370Y1384822D03*
X1238830Y1320355D03*
X1233516Y1367089D03*
X1259472Y90347D03*
X1248859Y1422983D03*
X1252859D03*
X1253000Y1429983D03*
X1273677Y764971D03*
X1271726Y1320327D03*
X1267639Y1320753D03*
X1260361Y1338676D03*
X1275981Y90597D03*
X1284764Y95287D03*
X1280764D03*
X1288677Y761971D03*
X1277677Y764971D03*
X1281677D03*
X1296200Y64394D03*
X1292786Y548306D03*
X1298886Y596538D03*
X1300677Y761971D03*
X1292677Y765471D03*
X1296677D03*
X1300686Y1320891D03*
X1304630Y1320270D03*
X1293257Y1338648D03*
X1308110Y64394D03*
X1307366Y552696D03*
X1320020Y64462D03*
X1333399Y95567D03*
X1332360Y561678D03*
X1333439Y1320868D03*
X1326161Y1338591D03*
X1337399Y95567D03*
X1341399D03*
X1348199D03*
X1337430Y1320470D03*
X1356199Y95533D03*
X1352199D03*
X1360109D03*
X1350772Y677651D03*
X1358961Y1338791D03*
X1366018Y617576D03*
X1366239Y1321068D03*
X1370012Y1339801D03*
X1379613Y616766D03*
X1383507Y625397D03*
X1383484Y642718D03*
X1391543Y1358122D03*
X1398718Y650476D03*
X1403808Y1031986D03*
X1407548D03*
X1400068D03*
X1403690Y1289248D03*
X1398821Y1340399D03*
X1412313Y649666D03*
X1416207Y658297D03*
X1416184Y675618D03*
X1422508Y1031986D03*
X1415028D03*
X1411288D03*
X1418768D03*
X1415623Y1602142D03*
X1419622Y1613250D03*
X1438262Y58375D03*
X1434513Y112883D03*
X1439049Y119926D03*
X1431318Y683056D03*
X1429989Y1031986D03*
X1433729D03*
X1426249D03*
X1446869Y111344D03*
X1443049Y119926D03*
X1444769Y171700D03*
X1439769D03*
X1449769D03*
X1439769Y179700D03*
X1449769D03*
X1441741Y599349D03*
X1444913Y682246D03*
X1448807Y690877D03*
X1448784Y708198D03*
X1440500Y1620483D03*
X1445500D03*
X1449070Y1684205D03*
X1445079Y1684161D03*
X1454549Y119926D03*
X1460508Y139426D03*
X1454769Y171700D03*
X1464236Y702633D03*
X1461702Y1670871D03*
X1483820Y128741D03*
X1477831Y701823D03*
X1481725Y710454D03*
X1481702Y727775D03*
X1491560Y597520D03*
X1497318Y702633D03*
X1513644Y225158D03*
Y216308D03*
X1513348Y259521D03*
X1510913Y701823D03*
X1527853Y565747D03*
X1514807Y710454D03*
X1514784Y727775D03*
X1539693Y541096D03*
X1537853Y565747D03*
X1530118Y702633D03*
X1543713Y701823D03*
X1547607Y710454D03*
X1547584Y727775D03*
X1561345Y577681D03*
X1563248Y680693D03*
X1584079Y564591D03*
X1576843Y679883D03*
X1580737Y688514D03*
X1580714Y705835D03*
X1579177Y1265271D03*
X1596018Y646924D03*
X1605286Y550156D03*
X1609286D03*
X1609613Y646114D03*
X1613507Y654745D03*
X1613484Y672066D03*
X1625000Y388983D03*
X1629018Y627924D03*
X1621000Y1435483D03*
X1638334Y561270D03*
X1646507Y635745D03*
X1646484Y653066D03*
X1641804Y1311044D03*
X1636167Y1441961D03*
X1661928Y227655D03*
X1659610Y400185D03*
X1653790Y431527D03*
X1657545D03*
X1650035D03*
X1649979Y622029D03*
X1654147Y621981D03*
X1651959Y695730D03*
X1653390Y1383818D03*
X1649024Y1409704D03*
X1653024D03*
X1656824D03*
X1660624D03*
X1654513Y1711667D03*
X1658513Y1714817D03*
X1654513Y1726817D03*
Y1718667D03*
Y1733817D03*
X1663610Y400185D03*
X1674921Y1401949D03*
X1668424Y1409704D03*
X1664424D03*
X1689000Y231483D03*
X1688504Y404543D03*
X1690154Y431668D03*
X1682290Y1384173D03*
X1686172Y1383918D03*
X1681000Y1442983D03*
Y1436483D03*
X1684012Y1669224D03*
X1689513Y1711667D03*
Y1718667D03*
X1693000Y231483D03*
X1694314Y431638D03*
X1695529Y1548251D03*
X1711798Y65262D03*
X1716558D03*
X1721344Y65439D03*
X1716931Y78738D03*
X1711798Y78750D03*
X1713418Y128150D03*
X1710426Y410646D03*
X1715072Y1384273D03*
X1718949D03*
X1707703Y1402049D03*
X1726608Y108867D03*
X1730202Y1599076D03*
X1726202D03*
X1725423Y1690139D03*
X1735463Y1691948D03*
X1729436Y1690148D03*
X1728633Y1715173D03*
Y1723323D03*
X1732633Y1726473D03*
X1728633Y1730323D03*
X1750918Y128150D03*
X1751983Y261120D03*
X1737914Y1566190D03*
X1747963Y1647848D03*
X1740463Y1691948D03*
X1745463D03*
X1757322Y128154D03*
X1766606Y1566046D03*
X1760051Y1583315D03*
X1757963Y1650948D03*
X1752963Y1647848D03*
X1762963Y1650948D03*
X1767638Y72599D03*
X1767891Y100303D03*
X1771891D03*
X1773657Y1566690D03*
X1790738Y77970D03*
X1793444Y183627D03*
X1797011D03*
X1789811D03*
X1795794Y1583015D03*
X1811711Y180527D03*
X1800511Y183627D03*
X1804111D03*
X1807711D03*
X1802349Y1565746D03*
X1819705Y159855D03*
X1816308Y205012D03*
G54D73*
X97477Y1577854D03*
Y1592224D03*
X166600Y1552015D03*
Y1566385D03*
X1174473Y1585015D03*
Y1599385D03*
X1715780Y170079D03*
Y184449D03*
X1779981Y1618865D03*
Y1633235D03*
G54D238*
X733380Y1582361D03*
X785577Y1582363D03*
X827577D03*
X869577D03*
X911577D03*
G54D148*
G01X50631Y1540246D02*
X51519D01*
X53658Y1538107D01*
X55756D01*
G01X50696Y1544294D02*
X53196Y1541794D01*
Y1541069D01*
X54386Y1539879D01*
X55756D01*
G01X60715Y526729D02*
X54317D01*
G01X55370Y1551351D02*
Y1547585D01*
X59080Y1543875D01*
Y1543808D01*
X59142Y1543746D01*
Y1542339D01*
G01X61605Y1546833D02*
Y1545659D01*
X62685Y1544579D01*
Y1542339D01*
G01X72768Y1550371D02*
X68768D01*
G01X88245Y1531047D02*
X87794Y1530596D01*
X86374D01*
G01Y1533746D02*
X87960D01*
X88778Y1534564D01*
X91499D01*
G01X91511Y1552296D02*
X90937Y1551722D01*
Y1547509D01*
X94885Y1543561D01*
Y1542339D01*
G01X98428D02*
Y1544165D01*
G01X88771Y1549369D02*
Y1552036D01*
X88511Y1552296D01*
G01X93113Y1542339D02*
Y1543166D01*
X88771Y1547508D01*
Y1549369D01*
G01X96966Y155807D02*
X99754D01*
G01X101679Y153691D02*
X101532Y153838D01*
X96966D01*
G01X98101Y1377112D02*
X98223D01*
X100469Y1374866D01*
Y1373225D01*
X101465Y1372229D01*
X103152D01*
G01Y1368686D02*
X101743D01*
X99669Y1366612D01*
X98101D01*
G01X103152Y1370457D02*
X100590D01*
X99488Y1371559D01*
X98101D01*
G01X104766Y1376461D02*
Y1377212D01*
X101995Y1379983D01*
Y1382593D01*
G01X104863Y1380085D02*
Y1379616D01*
X106538Y1377941D01*
Y1376461D01*
G01X108817Y1380530D02*
Y1379463D01*
X109614Y1378666D01*
X110081Y1377538D01*
Y1376461D01*
G01X111555Y1379562D02*
X111853Y1379264D01*
Y1376461D01*
G01X130701Y1377112D02*
X130823D01*
X133069Y1374866D01*
Y1373225D01*
X134065Y1372229D01*
X135752D01*
G01Y1368686D02*
X133643D01*
X131569Y1366612D01*
X130701D01*
G01X135752Y1370457D02*
X133190D01*
X132088Y1371559D01*
X130701D01*
G01X137366Y1376461D02*
Y1377212D01*
X134595Y1379983D01*
Y1382593D01*
G01X139138Y1376461D02*
Y1377941D01*
X137417Y1379662D01*
Y1380085D01*
X137463D01*
G01X141417Y1380530D02*
Y1379463D01*
X142418Y1378462D01*
X142681Y1377827D01*
Y1376461D01*
G01X144155Y1379562D02*
X144453Y1379264D01*
Y1376461D01*
G01X163401Y1377112D02*
X163523D01*
X165769Y1374866D01*
Y1373225D01*
X166765Y1372229D01*
X168452D01*
G01X163401Y1366612D02*
X164269D01*
X166343Y1368686D01*
X168452D01*
G01X163401Y1371559D02*
X164788D01*
X165890Y1370457D01*
X168452D01*
G01X170066Y1376461D02*
Y1377212D01*
X167295Y1379983D01*
Y1382593D01*
G01X171838Y1376461D02*
Y1377941D01*
X170117Y1379662D01*
Y1380085D01*
X170163D01*
G01X174117Y1380530D02*
Y1379463D01*
X175055Y1378525D01*
X175381Y1377738D01*
Y1376461D01*
G01X176855Y1379562D02*
X177153Y1379264D01*
Y1376461D01*
G01X196301Y1377112D02*
X196423D01*
X198329Y1375206D01*
X198669Y1374385D01*
Y1373225D01*
X199665Y1372229D01*
X201352D01*
G01X196301Y1366612D02*
X197169D01*
X199243Y1368686D01*
X201352D01*
G01X196301Y1371559D02*
X197688D01*
X198790Y1370457D01*
X201352D01*
G01X202966Y1376461D02*
Y1377212D01*
X200195Y1379983D01*
Y1382593D01*
G01X204738Y1376461D02*
Y1377941D01*
X203017Y1379662D01*
Y1380085D01*
X203063D01*
G01X207017Y1380530D02*
Y1379463D01*
X207863Y1378617D01*
X208281Y1377607D01*
Y1376461D01*
G01X209755Y1379562D02*
X210053Y1379264D01*
Y1376461D01*
G01X229101Y1366612D02*
X229969D01*
X232043Y1368686D01*
X234152D01*
G01X229101Y1371559D02*
X230488D01*
X231590Y1370457D01*
X234152D01*
G01X229101Y1377112D02*
X229223D01*
X230954Y1375381D01*
X231469Y1374139D01*
Y1373225D01*
X232465Y1372229D01*
X234152D01*
G01X237538Y1376461D02*
Y1377941D01*
X235817Y1379662D01*
Y1380085D01*
X235863D01*
G01X239817Y1380530D02*
Y1379463D01*
X240671Y1378609D01*
X241081Y1377619D01*
Y1376461D01*
G01X242853D02*
Y1379264D01*
X242555Y1379562D01*
G01X235766Y1376461D02*
Y1377212D01*
X232995Y1379983D01*
Y1382593D01*
G01X259203Y653656D02*
X259242Y653617D01*
Y650814D01*
X259501Y650555D01*
G01X272955Y653005D02*
X272833D01*
X270894Y654944D01*
X270587Y655685D01*
Y656892D01*
X269591Y657888D01*
X267904D01*
G01X266193Y650032D02*
Y650380D01*
X264518Y652055D01*
Y653656D01*
G01X260975D02*
Y652672D01*
X261508Y651385D01*
X262239Y650654D01*
Y649587D01*
G01X269061Y647524D02*
Y650134D01*
X266290Y652905D01*
Y653656D01*
G01X267904Y661431D02*
X270013D01*
X272087Y663505D01*
X272955D01*
G01Y658558D02*
X271568D01*
X270466Y659660D01*
X267904D01*
G01X262701Y1330966D02*
X262823D01*
X264714Y1329075D01*
X265069Y1328218D01*
Y1327079D01*
X266065Y1326083D01*
X267752D01*
G01X262701Y1320466D02*
X263569D01*
X265643Y1322540D01*
X267752D01*
G01X262701Y1325413D02*
X264088D01*
X265190Y1324311D01*
X267752D01*
G01X271138Y1330315D02*
Y1331795D01*
X269417Y1333516D01*
Y1333939D01*
X269463D01*
G01X273417Y1334384D02*
Y1333317D01*
X274282Y1332452D01*
X274681Y1331489D01*
Y1330315D01*
G01X266595Y1336447D02*
Y1333837D01*
X269366Y1331066D01*
Y1330315D01*
G01X276453D02*
Y1333118D01*
X276155Y1333416D01*
G01X291765Y153819D02*
X294553D01*
G01X291765Y151850D02*
X296331D01*
X296478Y151703D01*
G01X291765Y155787D02*
X291768Y155790D01*
X293062D01*
X293478Y156206D01*
X296475D01*
X296478Y156203D01*
G01X298923Y684273D02*
Y684742D01*
X297248Y686417D01*
Y687897D01*
G01X294969Y683828D02*
Y684895D01*
X294117Y685747D01*
X293705Y686741D01*
Y687897D01*
G01X291933D02*
Y685094D01*
X292231Y684796D01*
G01X299020Y687897D02*
Y687146D01*
X301791Y684375D01*
Y681765D01*
G01X305685Y687246D02*
X305563D01*
X303714Y689095D01*
X303317Y690053D01*
Y691133D01*
X302321Y692129D01*
X300634D01*
G01X305685Y697746D02*
X304817D01*
X302743Y695672D01*
X300634D01*
G01X305685Y692799D02*
X304298D01*
X303196Y693901D01*
X300634D01*
G01X300648Y1326055D02*
X298961D01*
X297965Y1327051D01*
Y1328328D01*
X297708Y1328949D01*
X295719Y1330938D01*
X295597D01*
G01X300628Y1326035D02*
X300648Y1326055D01*
G01Y1322512D02*
X298539D01*
X296465Y1320438D01*
X295597D01*
G01X300648Y1324283D02*
X298086D01*
X296984Y1325385D01*
X295597D01*
G01X304034Y1330287D02*
Y1331767D01*
X302313Y1333488D01*
Y1333911D01*
X302359D01*
G01X299491Y1336419D02*
Y1333809D01*
X302262Y1331038D01*
Y1330287D01*
G01X306313Y1334356D02*
Y1333289D01*
X307147Y1332455D01*
X307577Y1331417D01*
Y1330287D01*
G01X309349D02*
Y1333090D01*
X309051Y1333388D01*
G01X331790Y708047D02*
Y707296D01*
X334561Y704525D01*
Y701915D01*
G01X338455Y707396D02*
X338333D01*
X336471Y709258D01*
X336087Y710185D01*
Y711283D01*
X335091Y712279D01*
X333404D01*
G01X330018Y708047D02*
Y706654D01*
X331693Y704979D01*
Y704423D01*
G01X338455Y717896D02*
X337587D01*
X335513Y715822D01*
X333404D01*
G01X327739Y703978D02*
Y705045D01*
X326903Y705881D01*
X326475Y706914D01*
Y708047D01*
G01X324703D02*
Y705244D01*
X325001Y704946D01*
G01X338455Y712949D02*
X337068D01*
X335966Y714051D01*
X333404D01*
G01X328501Y1330881D02*
X328623D01*
X330477Y1329027D01*
X330869Y1328080D01*
Y1326994D01*
X331865Y1325998D01*
X333552D01*
G01Y1322455D02*
X331443D01*
X329369Y1320381D01*
X328501D01*
G01Y1325328D02*
X329888D01*
X330990Y1324226D01*
X333552D01*
G01X335263Y1333854D02*
X335217D01*
Y1333431D01*
X336938Y1331710D01*
Y1330230D01*
G01X332395Y1336362D02*
Y1333752D01*
X335166Y1330981D01*
Y1330230D01*
G01X339217Y1334299D02*
Y1333232D01*
X340075Y1332374D01*
X340481Y1331394D01*
Y1330230D01*
G01X342253D02*
Y1333033D01*
X341955Y1333331D01*
G01X362651Y287838D02*
X360664D01*
X359734Y288768D01*
G01X364753Y704155D02*
Y704619D01*
X363078Y706294D01*
Y707779D01*
G01X360799Y703710D02*
Y704777D01*
X360079Y705497D01*
X359535Y706810D01*
Y707779D01*
G01X358061Y704678D02*
X357763Y704976D01*
Y707779D01*
G01X364850D02*
Y707028D01*
X367621Y704257D01*
Y701647D01*
G01X361301Y1331081D02*
X361423D01*
X363204Y1329300D01*
X363669Y1328178D01*
Y1327194D01*
X364665Y1326198D01*
X366352D01*
G01Y1322655D02*
X364243D01*
X362169Y1320581D01*
X361301D01*
G01Y1325528D02*
X362688D01*
X363790Y1324426D01*
X366352D01*
G01X365195Y1336562D02*
Y1333952D01*
X367966Y1331181D01*
Y1330430D01*
G01X371515Y707128D02*
X371393D01*
X369506Y709015D01*
X369147Y709881D01*
Y710907D01*
X368043Y712011D01*
X366464D01*
G01X371515Y717628D02*
X370647D01*
X368573Y715554D01*
X366464D01*
G01Y713783D02*
X369158D01*
X370260Y712681D01*
X371515D01*
G01X369738Y1330430D02*
Y1331910D01*
X368017Y1333631D01*
Y1334054D01*
X368063D01*
G01X372017Y1334499D02*
Y1333432D01*
X372859Y1332590D01*
X373281Y1331571D01*
Y1330430D01*
G01X375053D02*
Y1333233D01*
X374755Y1333531D01*
G01X393839Y703778D02*
Y704845D01*
X393073Y705611D01*
X392575Y706814D01*
Y707847D01*
G01X390803D02*
Y705044D01*
X391101Y704746D01*
G01X398934Y1341986D02*
X396825D01*
X394751Y1339912D01*
X393883D01*
G01Y1350412D02*
X394005D01*
X395895Y1348522D01*
X396251Y1347663D01*
Y1346529D01*
X397251Y1345529D01*
X398934D01*
G01X393883Y1344859D02*
X395270D01*
X396372Y1343757D01*
X398934D01*
G01X397890Y707847D02*
Y707096D01*
X400661Y704325D01*
Y701715D01*
G01X404555Y707196D02*
X404433D01*
X402500Y709129D01*
X402187Y709885D01*
Y711083D01*
X401191Y712079D01*
X399504D01*
G01X396118Y707847D02*
Y706367D01*
X397839Y704646D01*
Y704223D01*
X397793D01*
G01X404555Y717696D02*
X403687D01*
X401613Y715622D01*
X399504D01*
G01X404555Y712749D02*
X403168D01*
X402066Y713851D01*
X399504D01*
G01X400645Y1353385D02*
X400599D01*
Y1352962D01*
X402320Y1351241D01*
Y1349761D01*
G01X404599Y1353830D02*
Y1352763D01*
X405436Y1351926D01*
X405863Y1350895D01*
Y1349761D01*
G01X407635D02*
Y1352564D01*
X407337Y1352862D01*
G01X397777Y1355893D02*
Y1353283D01*
X400548Y1350512D01*
Y1349761D01*
G01X423803Y690047D02*
Y687244D01*
X424101Y686946D01*
G01X430793Y686423D02*
Y686979D01*
X429118Y688654D01*
Y690047D01*
G01X426839Y685978D02*
Y687045D01*
X426003Y687881D01*
X425575Y688914D01*
Y690047D01*
G01X430890D02*
Y689296D01*
X433661Y686525D01*
Y683915D01*
G01X437555Y689396D02*
X437433D01*
X435471Y691358D01*
X435187Y692043D01*
Y693283D01*
X434191Y694279D01*
X432504D01*
G01Y697822D02*
X434613D01*
X436687Y699896D01*
X437555D01*
G01Y694949D02*
X436168D01*
X435066Y696051D01*
X432504D01*
G01X469955Y664796D02*
X469833D01*
X467971Y666658D01*
X467587Y667585D01*
Y668683D01*
X466591Y669679D01*
X464904D01*
G01X466061Y659315D02*
Y661925D01*
X463290Y664696D01*
Y665447D01*
G01X463193Y661823D02*
Y662379D01*
X461518Y664054D01*
Y665447D01*
G01X459239Y661378D02*
Y662445D01*
X458361Y663323D01*
X457975Y664255D01*
Y665447D01*
G01X469955Y670349D02*
X468568D01*
X467466Y671451D01*
X464904D01*
G01X456203Y665447D02*
Y662644D01*
X456501Y662346D01*
G01X469955Y675296D02*
X469087D01*
X467033Y673242D01*
X467032D01*
X467012Y673222D01*
X464904D01*
G01X495890Y638947D02*
Y638196D01*
X498661Y635425D01*
Y632815D01*
G01X495839Y635323D02*
Y635746D01*
X494118Y637467D01*
Y638947D01*
G01X491839Y634878D02*
Y635945D01*
X491003Y636781D01*
X490575Y637814D01*
Y638947D01*
G01X489101Y635846D02*
X488803Y636144D01*
Y638947D01*
G01X502555Y638296D02*
X502433D01*
X500571Y640158D01*
X500187Y641085D01*
Y642183D01*
X499191Y643179D01*
X497504D01*
G01Y646722D02*
X499613D01*
X501687Y648796D01*
X502555D01*
G01Y643849D02*
X501168D01*
X500066Y644951D01*
X497504D01*
G01X531961Y598715D02*
Y601719D01*
X529190Y604490D01*
Y604847D01*
G01X528040Y602745D02*
X527418Y603367D01*
Y604847D01*
G01X524231Y602837D02*
Y603037D01*
X523875Y603393D01*
Y604847D01*
G01X522401Y601746D02*
X522103Y602044D01*
Y604847D01*
G01X535855Y604196D02*
X535733D01*
X533831Y606098D01*
Y607739D01*
X532491Y609079D01*
X530804D01*
G01X534987Y614696D02*
X532913Y612622D01*
X530804D01*
G01Y610851D02*
X533366D01*
G01X535855Y614696D02*
X534987D01*
G01X705657Y1384621D02*
X707274D01*
X709348Y1386695D01*
X710708D01*
G01X705657Y1395121D02*
X705779D01*
X708025Y1392875D01*
Y1391234D01*
X709021Y1390238D01*
X710708D01*
G01X705657Y1389568D02*
X707044D01*
X708165Y1388447D01*
X708184Y1388466D01*
X710708D01*
G01X712419Y1398094D02*
Y1397625D01*
X714094Y1395950D01*
Y1394470D01*
G01X716373Y1398539D02*
Y1397410D01*
X717637Y1396146D01*
Y1394470D01*
G01X719409D02*
Y1397273D01*
X719111Y1397571D01*
G01X712322Y1394470D02*
Y1395221D01*
X709551Y1397992D01*
Y1400602D01*
G01X738439Y1384721D02*
X739307D01*
X741381Y1386795D01*
X743490D01*
G01Y1390338D02*
X741803D01*
G01D02*
X740807Y1391334D01*
Y1392975D01*
X738561Y1395221D01*
X738439D01*
G01X745201Y1398194D02*
Y1397725D01*
X746876Y1396050D01*
Y1394570D01*
G01X749155Y1398639D02*
Y1397438D01*
X750419Y1396174D01*
Y1394570D01*
G01X752191D02*
Y1397373D01*
X751893Y1397671D01*
G01X738439Y1389668D02*
X739826D01*
X740928Y1388566D01*
X743490D01*
G01X745104Y1394570D02*
Y1395321D01*
X742333Y1398092D01*
Y1400702D01*
G01X826615Y147123D02*
X826468Y146976D01*
Y142411D01*
X826467Y142410D01*
G01X1069839Y1377093D02*
X1069961D01*
X1072207Y1374847D01*
Y1373206D01*
X1073203Y1372210D01*
X1074890D01*
G01X1069839Y1366593D02*
X1071280D01*
X1073354Y1368667D01*
X1074890D01*
G01X1069839Y1371540D02*
X1071226D01*
X1072328Y1370438D01*
X1074890D01*
G01X1076504Y1376442D02*
Y1377193D01*
X1073733Y1379964D01*
Y1382574D01*
G01X1078276Y1376442D02*
Y1377922D01*
X1076555Y1379643D01*
Y1380066D01*
X1076601D01*
G01X1081819Y1376442D02*
Y1378094D01*
X1080555Y1379358D01*
Y1380511D01*
G01X1083293Y1379543D02*
X1083591Y1379245D01*
Y1376442D01*
G01X1102439Y1377093D02*
X1102561D01*
X1104807Y1374847D01*
Y1373206D01*
X1105803Y1372210D01*
X1107490D01*
G01X1102439Y1366593D02*
X1103307D01*
X1105381Y1368667D01*
X1107490D01*
G01X1102439Y1371540D02*
X1103826D01*
X1104928Y1370438D01*
X1107490D01*
G01X1109104Y1376442D02*
Y1377193D01*
X1106333Y1379964D01*
Y1382574D01*
G01X1110876Y1376442D02*
Y1377922D01*
X1109155Y1379643D01*
Y1380066D01*
X1109201D01*
G01X1113155Y1380511D02*
Y1379316D01*
X1114419Y1378052D01*
Y1376442D01*
G01X1115893Y1379543D02*
X1116191Y1379245D01*
Y1376442D01*
G01X1124532Y1637591D02*
Y1634915D01*
G01Y1656291D02*
Y1658829D01*
X1124394Y1658967D01*
G01X1120595Y1656291D02*
Y1658967D01*
G01X1116166Y1651862D02*
X1113490D01*
G01X1135139Y1377093D02*
X1135261D01*
X1137507Y1374847D01*
Y1373206D01*
X1138503Y1372210D01*
X1140190D01*
G01Y1368667D02*
X1138081D01*
X1136007Y1366593D01*
X1135139D01*
G01Y1371540D02*
X1136526D01*
X1137628Y1370438D01*
X1140190D01*
G01X1141804Y1376442D02*
Y1377193D01*
X1139033Y1379964D01*
Y1382574D01*
G01X1132406Y1637591D02*
Y1635106D01*
X1132981Y1634531D01*
G01X1134866Y1647925D02*
X1137542D01*
G01X1132406Y1656291D02*
Y1658967D01*
G01X1143576Y1376442D02*
Y1377922D01*
X1141855Y1379643D01*
Y1380066D01*
X1141901D01*
G01X1145855Y1380511D02*
Y1379352D01*
X1147119Y1378088D01*
Y1376442D01*
G01X1148593Y1379543D02*
X1148891Y1379245D01*
Y1376442D01*
G01X1173090Y1368667D02*
X1170981D01*
X1168907Y1366593D01*
X1168039D01*
G01Y1371540D02*
X1169426D01*
X1170528Y1370438D01*
X1173090D01*
G01X1168039Y1377093D02*
X1168161D01*
X1170407Y1374847D01*
Y1373206D01*
X1171403Y1372210D01*
X1173090D01*
G01X1174704Y1376442D02*
Y1377193D01*
X1171933Y1379964D01*
Y1382574D01*
G01X1176476Y1376442D02*
Y1377922D01*
X1174755Y1379643D01*
Y1380066D01*
X1174801D01*
G01X1178755Y1380511D02*
Y1379344D01*
X1180019Y1378080D01*
Y1376442D01*
G01X1181493Y1379543D02*
X1181791Y1379245D01*
Y1376442D01*
G01X1200839Y1377093D02*
X1200961D01*
X1203207Y1374847D01*
Y1373206D01*
X1204203Y1372210D01*
X1205890D01*
G01Y1368667D02*
X1203781D01*
X1201707Y1366593D01*
X1200839D01*
G01X1205890Y1370438D02*
X1203328D01*
X1202226Y1371540D01*
X1200839D01*
G01X1209276Y1376442D02*
Y1377922D01*
X1207555Y1379643D01*
Y1380066D01*
X1207601D01*
G01X1211555Y1380511D02*
Y1379382D01*
X1212819Y1378118D01*
Y1376442D01*
G01X1214591D02*
Y1379245D01*
X1214293Y1379543D01*
G01X1207504Y1376442D02*
Y1377193D01*
X1204733Y1379964D01*
Y1382574D01*
G01X1238830Y1330947D02*
X1238952D01*
X1241198Y1328701D01*
Y1327060D01*
X1242194Y1326064D01*
X1243881D01*
G01X1238830Y1320447D02*
X1239698D01*
X1241772Y1322521D01*
X1243881D01*
G01Y1324292D02*
X1241319D01*
X1240217Y1325394D01*
X1238830D01*
G01X1245495Y1330296D02*
Y1331047D01*
X1242724Y1333818D01*
Y1336428D01*
G01X1247267Y1330296D02*
Y1331776D01*
X1245546Y1333497D01*
Y1333920D01*
X1245592D01*
G01X1249546Y1334365D02*
Y1333236D01*
X1250810Y1331972D01*
Y1330296D01*
G01X1252582D02*
Y1333099D01*
X1252284Y1333397D01*
G01X1271726Y1330919D02*
X1271848D01*
X1274094Y1328673D01*
Y1327032D01*
X1275090Y1326036D01*
X1276777D01*
G01Y1322493D02*
X1274668D01*
X1272594Y1320419D01*
X1271726D01*
G01X1276777Y1324264D02*
X1274215D01*
X1273113Y1325366D01*
X1271726D01*
G01X1290127Y403625D02*
X1289980Y403772D01*
X1285414D01*
G01Y405741D02*
X1288202D01*
G01X1280163Y1330268D02*
Y1331748D01*
X1278442Y1333469D01*
Y1333892D01*
X1278488D01*
G01X1282442Y1334337D02*
Y1333208D01*
X1283706Y1331944D01*
Y1330268D01*
G01X1285478D02*
Y1333071D01*
X1285180Y1333369D01*
G01X1278391Y1330268D02*
Y1331019D01*
X1275620Y1333790D01*
Y1336400D01*
G01X1304630Y1330862D02*
X1304752D01*
X1306998Y1328616D01*
Y1326975D01*
X1307994Y1325979D01*
X1309681D01*
G01Y1322436D02*
X1307572D01*
X1305498Y1320362D01*
X1304630D01*
G01Y1325309D02*
X1306017D01*
X1307119Y1324207D01*
X1309681D01*
G01X1313067Y1330211D02*
Y1331691D01*
X1311346Y1333412D01*
Y1333835D01*
X1311392D01*
G01X1315346Y1334280D02*
Y1333151D01*
X1316610Y1331887D01*
Y1330211D01*
G01X1318382D02*
Y1333014D01*
X1318084Y1333312D01*
G01X1311295Y1330211D02*
Y1330962D01*
X1308524Y1333733D01*
Y1336343D01*
G01X1337430Y1331062D02*
X1337552D01*
X1339798Y1328816D01*
Y1327175D01*
X1340794Y1326179D01*
X1342481D01*
G01Y1322636D02*
X1340372D01*
X1338298Y1320562D01*
X1337430D01*
G01Y1325509D02*
X1338817D01*
X1339919Y1324407D01*
X1342481D01*
G01X1345867Y1330411D02*
Y1331891D01*
X1344146Y1333612D01*
Y1334035D01*
X1344192D01*
G01X1348146Y1334480D02*
Y1333351D01*
X1349410Y1332087D01*
Y1330411D01*
G01X1344095D02*
Y1331162D01*
X1341324Y1333933D01*
Y1336543D01*
G01X1351182Y1330411D02*
Y1333214D01*
X1350884Y1333512D01*
G01X1383507Y622339D02*
X1383385D01*
X1381399Y624325D01*
X1381139Y624952D01*
Y626226D01*
X1380143Y627222D01*
X1378456D01*
G01X1375070Y622990D02*
Y621510D01*
X1376757Y619823D01*
Y619497D01*
G01X1372791Y618921D02*
Y619988D01*
X1372002Y620777D01*
X1371527Y621924D01*
Y622990D01*
G01X1369755D02*
Y620187D01*
X1370053Y619889D01*
G01X1376842Y622990D02*
Y622523D01*
X1379613Y619752D01*
Y616858D01*
G01X1383507Y632839D02*
X1382639D01*
X1380585Y630785D01*
Y630775D01*
X1380575Y630765D01*
X1378456D01*
G01X1383507Y627892D02*
X1382120D01*
X1381018Y628994D01*
X1378456D01*
G01X1375063Y1341967D02*
X1372954D01*
X1370880Y1339893D01*
X1370012D01*
G01Y1350393D02*
X1370134D01*
X1372380Y1348147D01*
Y1346510D01*
X1373380Y1345510D01*
X1375063D01*
G01X1378449Y1349742D02*
Y1351222D01*
X1376728Y1352943D01*
Y1353366D01*
X1376774D01*
G01X1370012Y1344840D02*
X1371399D01*
X1372501Y1343738D01*
X1375063D01*
G01X1376677Y1349742D02*
Y1350493D01*
X1373906Y1353264D01*
Y1355874D01*
G01X1380728Y1353811D02*
Y1352682D01*
X1381992Y1351418D01*
Y1349742D01*
G01X1383764D02*
Y1352545D01*
X1383466Y1352843D01*
G01X1407770Y655890D02*
Y654410D01*
X1409491Y652689D01*
Y652266D01*
X1409445D01*
G01X1404227Y655890D02*
Y654849D01*
X1404720Y653659D01*
X1405491Y652888D01*
Y651821D01*
G01X1402753Y652789D02*
X1402455Y653087D01*
Y655890D01*
G01X1416207Y655239D02*
X1416085D01*
X1414150Y657174D01*
X1413839Y657925D01*
Y659126D01*
X1412843Y660122D01*
X1411156D01*
G01X1409542Y655890D02*
Y655139D01*
X1412313Y652368D01*
Y649758D01*
G01X1416207Y665739D02*
X1415339D01*
X1413265Y663665D01*
X1411156D01*
G01X1416207Y660792D02*
X1414820D01*
X1413718Y661894D01*
X1411156D01*
G01X1436827Y688470D02*
Y687377D01*
X1437283Y686276D01*
X1438091Y685468D01*
Y684401D01*
G01X1435055Y688470D02*
Y685667D01*
X1435353Y685369D01*
G01X1442091Y684846D02*
Y685269D01*
X1440370Y686990D01*
Y688470D01*
G01X1442142D02*
Y687719D01*
X1444913Y684948D01*
Y682338D01*
G01X1448807Y687819D02*
X1448685D01*
X1446819Y689685D01*
X1446439Y690602D01*
Y691706D01*
X1445443Y692702D01*
X1443756D01*
G01X1448807Y698319D02*
X1447939D01*
X1445865Y696245D01*
X1443756D01*
G01X1448807Y693372D02*
X1447420D01*
X1446318Y694474D01*
X1443756D01*
G01X1467973Y708047D02*
Y705244D01*
X1468271Y704946D01*
G01X1475060Y708047D02*
Y707605D01*
X1477831Y704834D01*
Y701915D01*
G01X1481725Y707396D02*
X1481603D01*
X1479712Y709287D01*
X1479357Y710144D01*
Y711283D01*
X1478361Y712279D01*
X1476674D01*
G01X1475009Y704488D02*
Y704956D01*
X1473288Y706677D01*
Y708047D01*
G01X1481725Y717896D02*
X1480857D01*
X1478783Y715822D01*
X1476674D01*
G01X1469745Y708047D02*
Y706941D01*
X1470192Y705862D01*
X1471009Y705045D01*
Y703978D01*
G01X1481725Y712949D02*
X1480338D01*
X1479236Y714051D01*
X1476674D01*
G01X1510913Y704525D02*
Y701915D01*
G01X1514807Y707396D02*
X1514685D01*
X1512729Y709352D01*
X1512439Y710052D01*
Y711283D01*
X1511275Y712447D01*
X1509756D01*
G01X1508045Y704423D02*
Y705060D01*
X1506370Y706735D01*
Y708215D01*
G01X1514807Y717896D02*
X1513939D01*
X1512033Y715990D01*
X1509756D01*
G01X1502827Y708215D02*
Y706977D01*
X1503300Y705836D01*
X1504091Y705045D01*
Y703978D01*
G01X1501055Y708215D02*
Y705244D01*
X1501353Y704946D01*
G01X1514807Y712949D02*
X1513420D01*
X1512150Y714219D01*
X1509756D01*
G01X1547607Y707396D02*
X1547485D01*
X1545622Y709259D01*
X1545239Y710184D01*
Y711283D01*
X1544243Y712279D01*
X1542556D01*
G01X1539170Y708047D02*
Y706567D01*
X1540891Y704846D01*
Y704423D01*
X1540845D01*
G01X1547607Y717896D02*
X1546739D01*
X1544665Y715822D01*
X1542556D01*
G01X1535627Y708047D02*
Y706928D01*
X1536065Y705871D01*
X1536891Y705045D01*
Y703978D01*
G01X1547607Y712949D02*
X1546220D01*
X1545118Y714051D01*
X1542556D01*
G01X1533855Y708047D02*
Y705244D01*
X1534153Y704946D01*
G01X1540942Y708047D02*
Y707296D01*
X1543713Y704525D01*
Y701915D01*
G01X1561729Y299432D02*
X1564517D01*
G01X1566442Y297316D02*
X1566295Y297463D01*
X1561729D01*
G01X1572300Y686107D02*
Y684627D01*
X1574021Y682906D01*
Y682483D01*
X1573975D01*
G01X1568757Y686107D02*
Y685001D01*
X1569204Y683922D01*
X1570021Y683105D01*
Y682038D01*
G01X1566985Y686107D02*
Y683304D01*
X1567283Y683006D01*
G01X1575686Y690339D02*
X1577010D01*
X1578319Y689030D01*
Y687598D01*
X1580461Y685456D01*
X1580737D01*
G01X1576843Y679975D02*
Y682585D01*
X1574072Y685356D01*
Y686107D01*
G01X1575686Y693882D02*
X1577795D01*
X1579869Y695956D01*
X1580737D01*
G01X1575686Y692111D02*
X1578225D01*
X1579327Y691009D01*
X1580737D01*
G01D02*
Y688606D01*
G01X1601527Y652338D02*
Y651150D01*
X1601916Y650211D01*
X1602791Y649336D01*
Y648269D01*
G01X1600053Y649237D02*
X1599755Y649535D01*
Y652338D01*
G01X1613507Y651687D02*
X1613385D01*
X1611456Y653616D01*
X1611139Y654380D01*
Y655670D01*
X1610239Y656570D01*
X1608456D01*
G01X1609613Y646206D02*
Y648816D01*
X1606842Y651587D01*
Y652338D01*
G01X1605070D02*
Y650858D01*
X1606791Y649137D01*
Y648714D01*
X1606745D01*
G01X1608456Y658342D02*
X1611018D01*
X1612120Y657240D01*
X1613507D01*
G01X1608456Y654798D02*
X1608957Y654297D01*
Y653168D01*
X1609734Y652391D01*
G01X1613507Y662187D02*
X1612639D01*
X1610565Y660113D01*
X1608456D01*
G01X1642613Y627206D02*
Y629816D01*
X1639842Y632587D01*
Y633338D01*
G01X1646507Y632687D02*
X1646385D01*
X1644503Y634569D01*
X1644139Y635448D01*
Y636554D01*
X1643123Y637570D01*
G01D02*
X1641456D01*
G01X1646507Y643187D02*
X1645116D01*
X1643042Y641113D01*
X1641456D01*
G01X1638070Y633338D02*
Y631854D01*
X1639745Y630179D01*
Y629714D01*
G01X1634527Y633338D02*
Y632194D01*
X1634947Y631180D01*
X1635791Y630336D01*
Y629269D01*
G01X1632755Y633338D02*
Y630535D01*
X1633053Y630237D01*
G01X1641456Y639342D02*
X1644018D01*
X1645120Y638240D01*
X1646507D01*
G01X1653390Y1383910D02*
X1654990D01*
X1657064Y1385984D01*
X1658441D01*
G01X1653390Y1388857D02*
X1654777D01*
X1655898Y1387736D01*
X1655917Y1387755D01*
X1658441D01*
G01X1656754Y1389527D02*
X1658441D01*
G01X1653390Y1394410D02*
X1653512D01*
X1655242Y1392680D01*
X1655758Y1391435D01*
Y1390523D01*
X1656754Y1389527D01*
G01X1661827Y1393759D02*
Y1395239D01*
X1660152Y1396914D01*
Y1397383D01*
G01X1660055Y1393759D02*
Y1394510D01*
X1657284Y1397281D01*
Y1399891D01*
G01X1664106Y1397828D02*
Y1396761D01*
X1665045Y1395822D01*
X1665370Y1395038D01*
Y1393759D01*
G01X1667142D02*
Y1396562D01*
X1666844Y1396860D01*
G01X1686172Y1384010D02*
X1687040D01*
X1689114Y1386084D01*
X1691223D01*
G01Y1387855D02*
X1688661D01*
X1687559Y1388957D01*
X1686172D01*
G01X1689536Y1389627D02*
X1688540Y1390623D01*
Y1392264D01*
X1686294Y1394510D01*
X1686172D01*
G01X1691223Y1389627D02*
X1689536D01*
G01X1692837Y1393859D02*
Y1394610D01*
X1690066Y1397381D01*
Y1399991D01*
G01X1691952Y1696422D02*
X1692026Y1696348D01*
Y1691757D01*
G01X1687883Y1696427D02*
X1688089Y1696221D01*
Y1691757D01*
G01X1692934Y1397483D02*
Y1397014D01*
X1694609Y1395339D01*
Y1393859D01*
G01X1696888Y1397928D02*
Y1396861D01*
X1697876Y1395873D01*
X1698152Y1395207D01*
Y1393859D01*
G01X1699924D02*
Y1396662D01*
X1699626Y1396960D01*
G01X1737914Y1573282D02*
X1738802D01*
X1740941Y1571143D01*
X1743039D01*
G01X1746425Y1575375D02*
Y1576782D01*
X1746363Y1576844D01*
Y1576911D01*
X1745729Y1577545D01*
Y1579418D01*
X1742279Y1582868D01*
G01X1746779Y1583378D02*
X1749088Y1581069D01*
Y1578495D01*
X1749968Y1577615D01*
Y1575375D01*
G01X1737979Y1577330D02*
X1740479Y1574830D01*
Y1574105D01*
X1741669Y1572915D01*
X1743039D01*
G01X1743979Y1576876D02*
X1744653Y1576202D01*
Y1575375D01*
G01X1760051Y1583407D02*
X1756051D01*
G01X1775528Y1564083D02*
X1775077Y1563632D01*
X1773657D01*
G01X1778782Y1567600D02*
X1776061D01*
X1775243Y1566782D01*
X1773657D01*
G01X1782168Y1575375D02*
Y1576597D01*
X1778220Y1580545D01*
Y1584758D01*
X1778794Y1585332D01*
G01X1780396Y1575375D02*
Y1576202D01*
X1776054Y1580544D01*
Y1582405D01*
G01D02*
Y1585072D01*
X1775794Y1585332D01*
G01X1785711Y1577531D02*
Y1575375D01*
X318333Y78520D03*
X316364D03*
X314395D03*
X312427D03*
X310459D03*
X308490D03*
X306521D03*
X318333Y80489D03*
X316364D03*
X314395D03*
X312427D03*
X310459D03*
X308490D03*
X306521D03*
X318333Y82457D03*
X316364D03*
X314395D03*
X312427D03*
X310459D03*
X308490D03*
X306521D03*
X318333Y84426D03*
X316364D03*
X314395D03*
X312427D03*
X310459D03*
X308490D03*
X306521D03*
X354139Y232608D03*
X356108D03*
X358077D03*
X360045D03*
X362013D03*
X363982D03*
X354139Y230639D03*
X356108D03*
X358077D03*
X360045D03*
X362013D03*
X363982D03*
X354139Y228671D03*
X356108D03*
X358077D03*
X360045D03*
X362013D03*
X363982D03*
X354139Y226702D03*
X356108D03*
X358077D03*
X360045D03*
X362013D03*
X363982D03*
X365951Y232608D03*
Y230639D03*
Y228671D03*
Y226702D03*
X750940Y98005D03*
X748971D03*
X747003D03*
X745035D03*
X743066D03*
X741097D03*
X750940Y99974D03*
X748971D03*
X747003D03*
X745035D03*
X743066D03*
X741097D03*
X750940Y101942D03*
X748971D03*
X747003D03*
X745035D03*
X743066D03*
X741097D03*
X750940Y103911D03*
X748971D03*
X747003D03*
X745035D03*
X743066D03*
X741097D03*
X752909Y98005D03*
Y99974D03*
Y101942D03*
Y103911D03*
X871345Y276064D03*
X869376D03*
X867407D03*
X871345Y278033D03*
X869376D03*
X867407D03*
X871345Y280001D03*
X869376D03*
X867407D03*
X871345Y281970D03*
X869376D03*
X867407D03*
X879219Y276064D03*
X877250D03*
X875281D03*
X873313D03*
X879219Y278033D03*
X877250D03*
X875281D03*
X873313D03*
X879219Y280001D03*
X877250D03*
X875281D03*
X873313D03*
X879219Y281970D03*
X877250D03*
X875281D03*
X873313D03*
X992452Y159667D03*
Y161636D03*
Y163605D03*
Y165573D03*
X994421Y159667D03*
Y161636D03*
Y163605D03*
Y165573D03*
X996389Y159667D03*
Y161636D03*
Y163605D03*
Y165573D03*
X998358Y159667D03*
Y161636D03*
Y163605D03*
Y165573D03*
X992452Y167541D03*
Y169510D03*
Y171479D03*
X994421Y167541D03*
Y169510D03*
Y171479D03*
X996389Y167541D03*
Y169510D03*
Y171479D03*
X998358Y167541D03*
Y169510D03*
Y171479D03*
X1697161Y408769D03*
Y410738D03*
Y412707D03*
Y414675D03*
Y416643D03*
Y418612D03*
X1699130Y408769D03*
Y410738D03*
Y412707D03*
Y414675D03*
Y416643D03*
Y418612D03*
X1701098Y408769D03*
Y410738D03*
Y412707D03*
Y414675D03*
Y416643D03*
Y418612D03*
X1703067Y408769D03*
Y410738D03*
Y412707D03*
Y414675D03*
Y416643D03*
Y418612D03*
X1697161Y420581D03*
X1699130D03*
X1701098D03*
X1703067D03*
X1779516Y79644D03*
X1777548D03*
X1775580D03*
X1773611D03*
X1771642D03*
X1779516Y81613D03*
X1777548D03*
X1775580D03*
X1773611D03*
X1771642D03*
X1779516Y83581D03*
X1777548D03*
X1775580D03*
X1773611D03*
X1771642D03*
X1779516Y85550D03*
X1777548D03*
X1775580D03*
X1773611D03*
X1771642D03*
X1783454Y79644D03*
X1781485D03*
X1783454Y81613D03*
X1781485D03*
X1783454Y83581D03*
X1781485D03*
X1783454Y85550D03*
X1781485D03*
G54D139*
X269887Y600916D03*
Y598554D03*
X280123D03*
G54D292*
X1108894Y1627567D03*
Y1620087D03*
X1110000Y1689260D03*
Y1696740D03*
G54D82*
X102529Y1701386D03*
Y1698827D03*
Y1703946D03*
Y1706505D03*
X102583Y1718438D03*
Y1720997D03*
Y1723557D03*
Y1726116D03*
X120107Y1701386D03*
Y1698827D03*
Y1706505D03*
Y1703946D03*
X120161Y1720997D03*
Y1723557D03*
Y1726116D03*
Y1718438D03*
X1128889Y1679853D03*
Y1677293D03*
Y1674734D03*
Y1682412D03*
X1146467D03*
Y1679853D03*
Y1677293D03*
Y1674734D03*
G54D175*
X428899Y222253D03*
Y240953D03*
X451931Y222253D03*
Y240953D03*
X506945Y224930D03*
Y243630D03*
X529977Y224930D03*
Y243630D03*
G54D283*
X989227Y378999D03*
X986668D03*
Y401047D03*
X989227D03*
X1004582Y378999D03*
X1002023D03*
X999464D03*
X996905D03*
X994345D03*
X991786D03*
Y401047D03*
X994345D03*
X996905D03*
X999464D03*
X1002023D03*
X1004582D03*
X1438312Y134818D03*
Y156866D03*
X1453667Y134818D03*
X1451108D03*
X1448549D03*
X1445989D03*
X1443430D03*
X1440871D03*
Y156866D03*
X1443430D03*
X1445989D03*
X1448549D03*
X1451108D03*
X1453667D03*
X1456226Y134818D03*
Y156866D03*
G54D166*
X394824Y1634154D03*
X389824D03*
X384824D03*
Y1655020D03*
X389824D03*
X394824D03*
X399824Y1634154D03*
Y1655020D03*
X1440579Y1640337D03*
X1445579D03*
X1450579D03*
X1440579Y1661203D03*
X1450579D03*
X1445579D03*
X1455579Y1640337D03*
Y1661203D03*
G54D157*
X362651Y283902D03*
Y285870D03*
Y287838D03*
X370525Y283902D03*
Y287838D03*
Y285870D03*
X777703Y275290D03*
Y273322D03*
Y271354D03*
X769829D03*
Y273322D03*
Y275290D03*
G54D64*
X57966Y1668833D03*
Y1670801D03*
Y1660959D03*
Y1662927D03*
Y1666864D03*
Y1664896D03*
X72926Y1666864D03*
Y1664896D03*
Y1660959D03*
Y1662927D03*
Y1668833D03*
Y1670801D03*
G54D46*
X61057Y64434D03*
Y62334D03*
X64657Y64434D03*
Y62334D03*
X72057Y70434D03*
Y68334D03*
X75657Y70434D03*
Y68334D03*
X86657Y64434D03*
Y62334D03*
X94057Y70434D03*
Y68334D03*
X83057Y64434D03*
Y62334D03*
X105057Y64434D03*
Y62334D03*
X108657Y64434D03*
Y62334D03*
X97657Y70434D03*
Y68334D03*
X127057Y64434D03*
Y62334D03*
X119657Y70434D03*
Y68334D03*
X116057Y70434D03*
Y68334D03*
X138057Y70434D03*
Y68334D03*
X130657Y64434D03*
Y62334D03*
X141657Y70434D03*
Y68334D03*
X152657Y64434D03*
Y62334D03*
X149057Y64434D03*
Y62334D03*
X164861Y70434D03*
Y68334D03*
X161261Y70434D03*
Y68334D03*
X169251Y1467595D03*
Y1469695D03*
X171433Y1521331D03*
Y1526631D03*
Y1528731D03*
Y1523431D03*
X159000Y1535950D03*
Y1532650D03*
Y1530550D03*
Y1538050D03*
Y1543450D03*
Y1541350D03*
X183261Y70434D03*
Y68334D03*
X175861Y64434D03*
Y62334D03*
X172261Y64434D03*
Y62334D03*
X175951Y1457895D03*
Y1459995D03*
X179551Y1457895D03*
Y1459995D03*
X172851Y1467595D03*
Y1469695D03*
X194261Y64434D03*
Y62334D03*
X197861Y64434D03*
Y62334D03*
X186861Y70434D03*
Y68334D03*
X189351Y1477295D03*
X192951D03*
X199651Y1467595D03*
Y1469695D03*
X196051Y1467595D03*
Y1469695D03*
X189351Y1479395D03*
X192951D03*
X200126Y1607286D03*
Y1609386D03*
X188066Y1607286D03*
Y1609386D03*
X191666Y1607286D03*
Y1609386D03*
X205395Y70434D03*
Y68334D03*
X216395Y64434D03*
Y62334D03*
X208995Y70434D03*
Y68334D03*
X206351Y1457895D03*
Y1459995D03*
X202751Y1457895D03*
Y1459995D03*
X216151Y1477295D03*
Y1479395D03*
X212186Y1607286D03*
Y1609386D03*
X215786Y1607286D03*
Y1609386D03*
X203726Y1607286D03*
Y1609386D03*
X230995Y70434D03*
Y68334D03*
X227395Y70434D03*
Y68334D03*
X219995Y64434D03*
Y62334D03*
X229551Y1457895D03*
Y1459995D03*
X219751Y1477295D03*
X222851Y1467595D03*
Y1469695D03*
X226451Y1467595D03*
Y1469695D03*
X219751Y1479395D03*
X224246Y1607286D03*
Y1609386D03*
X227846Y1607286D03*
Y1609386D03*
X233151Y1457895D03*
Y1459995D03*
X242951Y1477295D03*
Y1479395D03*
X236306Y1607286D03*
Y1609386D03*
X239906Y1607286D03*
Y1609386D03*
X256351Y1457895D03*
Y1459995D03*
X259951Y1457895D03*
Y1459995D03*
X249651Y1467595D03*
Y1469695D03*
X246551Y1477295D03*
X253251Y1467595D03*
Y1469695D03*
X246551Y1479395D03*
X254470Y1555340D03*
Y1553240D03*
X260426Y1607286D03*
Y1609386D03*
X248366Y1607286D03*
Y1609386D03*
X251966Y1607286D03*
Y1609386D03*
X273351Y1457895D03*
Y1459995D03*
X269751Y1457895D03*
Y1459995D03*
X271580Y1552250D03*
X268380Y1551550D03*
X271580Y1554350D03*
X261530Y1553220D03*
Y1555320D03*
X268380Y1558650D03*
Y1556550D03*
Y1553650D03*
X276086Y1607286D03*
Y1609386D03*
X272486Y1607286D03*
Y1609386D03*
X264026Y1607286D03*
Y1609386D03*
X283000Y1516750D03*
Y1518850D03*
X286200Y1516750D03*
Y1518850D03*
X283000Y1521750D03*
X286200D03*
X283000Y1523850D03*
X286200D03*
X284546Y1607286D03*
Y1609386D03*
X288146Y1607286D03*
Y1609386D03*
X304013Y1457895D03*
Y1459995D03*
X297313Y1467595D03*
Y1469695D03*
X300913Y1467595D03*
Y1469695D03*
X299495Y1521331D03*
Y1526631D03*
Y1528731D03*
Y1523431D03*
X303999Y1550788D03*
X300199Y1553688D03*
Y1555788D03*
X303999Y1552888D03*
Y1557888D03*
Y1555788D03*
X296606Y1607286D03*
Y1609386D03*
X300206Y1607286D03*
Y1609386D03*
X307613Y1457895D03*
Y1459995D03*
X317413Y1477295D03*
Y1479395D03*
X307199Y1550788D03*
X311476Y1557039D03*
Y1554939D03*
Y1562039D03*
Y1559939D03*
X307199Y1552888D03*
Y1557888D03*
Y1555788D03*
X320726Y1607286D03*
Y1609386D03*
X308666Y1607286D03*
Y1609386D03*
X312266Y1607286D03*
Y1609386D03*
X330813Y1457895D03*
Y1459995D03*
X334413Y1457895D03*
Y1459995D03*
X324113Y1467595D03*
Y1469695D03*
X321013Y1477295D03*
X327713Y1467595D03*
Y1469695D03*
X321013Y1479395D03*
X332786Y1607286D03*
Y1609386D03*
X324326Y1607286D03*
Y1609386D03*
X347813Y1477295D03*
X344213D03*
X347813Y1479395D03*
X344213D03*
X344846Y1607286D03*
Y1609386D03*
X348446Y1607286D03*
Y1609386D03*
X336386Y1607286D03*
Y1609386D03*
X361213Y1457895D03*
Y1459995D03*
X357613Y1457895D03*
Y1459995D03*
X350913Y1467595D03*
Y1469695D03*
X354513Y1467595D03*
Y1469695D03*
X356906Y1607286D03*
Y1609386D03*
X360506Y1607286D03*
Y1609386D03*
X377713Y1467595D03*
Y1469695D03*
X374613Y1477295D03*
X371013D03*
X374613Y1479395D03*
X371013D03*
X368966Y1607286D03*
Y1609386D03*
X372566Y1607286D03*
Y1609386D03*
X388013Y1457895D03*
Y1459995D03*
X384413Y1457895D03*
Y1459995D03*
X381313Y1467595D03*
Y1469695D03*
X390082Y1551550D03*
Y1553650D03*
Y1558650D03*
Y1556550D03*
X395009Y1587339D03*
Y1585239D03*
X384457Y1593936D03*
Y1591836D03*
X406243Y112951D03*
Y110851D03*
Y116351D03*
Y118451D03*
X409443Y126201D03*
Y124101D03*
Y129601D03*
Y131701D03*
X401413Y1457895D03*
Y1459995D03*
X397813Y1457895D03*
Y1459995D03*
X399642Y1551550D03*
X396442D03*
X404200Y1560750D03*
Y1562850D03*
X407600Y1560750D03*
Y1562850D03*
X399642Y1553650D03*
X396442Y1558650D03*
Y1556550D03*
Y1553650D03*
X402983Y1552879D03*
Y1554979D03*
X406086Y1552840D03*
Y1554940D03*
X411062Y1521750D03*
X414262D03*
X411062Y1516750D03*
Y1518850D03*
X414262Y1516750D03*
Y1518850D03*
X411062Y1523850D03*
X414262D03*
X411320Y1555250D03*
Y1553150D03*
X440124Y1457895D03*
Y1459995D03*
X433424Y1467595D03*
Y1469695D03*
X437024Y1467595D03*
Y1469695D03*
X435606Y1521331D03*
Y1526631D03*
Y1528731D03*
Y1523431D03*
X435513Y1531694D03*
Y1533794D03*
X426600Y1562070D03*
Y1564170D03*
X430000Y1562070D03*
Y1564170D03*
X429963Y1557147D03*
Y1559247D03*
X426850Y1557096D03*
Y1559196D03*
X443724Y1457895D03*
Y1459995D03*
X453524Y1477295D03*
Y1479395D03*
X443810Y1550788D03*
X440610D03*
X449597Y1557039D03*
Y1554939D03*
X443810Y1552888D03*
X446240Y1557908D03*
Y1555808D03*
X440610Y1552888D03*
X443040Y1557908D03*
Y1555808D03*
X450749Y1571104D03*
Y1573204D03*
X446218Y1590517D03*
Y1588417D03*
X452239Y1607286D03*
Y1609386D03*
X466924Y1457895D03*
Y1459995D03*
X463824Y1467595D03*
Y1469695D03*
X460224Y1467595D03*
Y1469695D03*
X457124Y1477295D03*
Y1479395D03*
X457317Y1557509D03*
Y1555409D03*
X464299Y1607286D03*
Y1609386D03*
X467899Y1607286D03*
Y1609386D03*
X455839Y1607286D03*
Y1609386D03*
X470524Y1457895D03*
Y1459995D03*
X483924Y1477295D03*
X480324D03*
X483924Y1479395D03*
X480324D03*
X476359Y1607286D03*
Y1609386D03*
X479959Y1607286D03*
Y1609386D03*
X493724Y1457895D03*
Y1459995D03*
X497324Y1457895D03*
Y1459995D03*
X487024Y1467595D03*
Y1469695D03*
X490624Y1467595D03*
Y1469695D03*
X488419Y1607286D03*
Y1609386D03*
X492019Y1607286D03*
Y1609386D03*
X513770Y105220D03*
Y107320D03*
D03*
Y109420D03*
X513824Y1467595D03*
Y1469695D03*
X510724Y1477295D03*
X507124D03*
X510724Y1479395D03*
X507124D03*
X512539Y1607286D03*
Y1609386D03*
X504079Y1607286D03*
Y1609386D03*
X500479Y1607286D03*
Y1609386D03*
X518270Y105220D03*
Y107320D03*
D03*
Y109420D03*
X520524Y1457895D03*
Y1459995D03*
X524124Y1457895D03*
Y1459995D03*
X517424Y1467595D03*
Y1469695D03*
X528470Y1551500D03*
X526193Y1558650D03*
Y1556550D03*
X528470Y1553600D03*
X528199Y1607286D03*
Y1609386D03*
X524599Y1607286D03*
Y1609386D03*
X516139Y1607286D03*
Y1609386D03*
X532920Y115280D03*
Y113180D03*
X537420Y115280D03*
Y113180D03*
Y111080D03*
Y113180D03*
X532920Y111080D03*
Y113180D03*
X537524Y1457895D03*
Y1459995D03*
X533924Y1457895D03*
Y1459995D03*
X544100Y1531540D03*
Y1533640D03*
X531580Y1551520D03*
X532553Y1558650D03*
Y1556550D03*
X531580Y1553620D03*
X540259Y1607286D03*
Y1609386D03*
X536659Y1607286D03*
Y1609386D03*
X547173Y1521750D03*
Y1516750D03*
Y1518850D03*
X550373Y1521750D03*
Y1516750D03*
Y1518850D03*
X547173Y1523850D03*
X550373D03*
X552319Y1607286D03*
Y1609386D03*
X548719Y1607286D03*
Y1609386D03*
X571786Y1457895D03*
Y1459995D03*
X568186Y1457895D03*
Y1459995D03*
X561486Y1467595D03*
Y1469695D03*
X565086Y1467595D03*
Y1469695D03*
X563668Y1521331D03*
Y1526631D03*
Y1528731D03*
Y1523431D03*
X571372Y1550788D03*
X568172D03*
X571372Y1552888D03*
Y1557888D03*
Y1555788D03*
X564372Y1553688D03*
Y1555788D03*
X568172Y1552888D03*
Y1557888D03*
Y1555788D03*
X572839Y1607286D03*
Y1609386D03*
X564379Y1607286D03*
Y1609386D03*
X560779Y1607286D03*
Y1609386D03*
X588286Y1467595D03*
Y1469695D03*
X585186Y1477295D03*
X581586D03*
X585186Y1479395D03*
X581586D03*
X575649Y1557039D03*
Y1554939D03*
Y1562039D03*
Y1559939D03*
X588499Y1607286D03*
Y1609386D03*
X584899Y1607286D03*
Y1609386D03*
X576439Y1607286D03*
Y1609386D03*
X594986Y1457895D03*
Y1459995D03*
X598586Y1457895D03*
Y1459995D03*
X591886Y1467595D03*
Y1469695D03*
X600559Y1607286D03*
Y1609386D03*
X596959Y1607286D03*
Y1609386D03*
X608386Y1477295D03*
X611986D03*
X618686Y1467595D03*
Y1469695D03*
X615086Y1467595D03*
Y1469695D03*
X608386Y1479395D03*
X611986D03*
X612619Y1607286D03*
Y1609386D03*
X609019Y1607286D03*
Y1609386D03*
X630147Y77961D03*
Y80061D03*
X633293Y77961D03*
Y80061D03*
X625386Y1457895D03*
Y1459995D03*
X621786Y1457895D03*
Y1459995D03*
X633139Y1607286D03*
Y1609386D03*
X624679Y1607286D03*
Y1609386D03*
X621079Y1607286D03*
Y1609386D03*
X648586Y1457895D03*
Y1459995D03*
X638786Y1477295D03*
X635186D03*
X645486Y1467595D03*
Y1469695D03*
X641886Y1467595D03*
Y1469695D03*
X638786Y1479395D03*
X635186D03*
X636739Y1607286D03*
Y1609386D03*
X639800Y1648750D03*
Y1650850D03*
X644549Y1648750D03*
Y1650850D03*
X661986Y1457895D03*
Y1459995D03*
X652186Y1457895D03*
Y1459995D03*
X660615Y1551550D03*
X654255D03*
X660615Y1558650D03*
Y1556550D03*
Y1553650D03*
X654255Y1558650D03*
Y1556550D03*
Y1553650D03*
X663439Y1640404D03*
X663003Y1649150D03*
Y1651250D03*
X663439Y1642504D03*
X665586Y1457895D03*
Y1459995D03*
X668206Y1505139D03*
Y1503039D03*
X663815Y1551550D03*
Y1553650D03*
X666729Y1640404D03*
X667985Y1649014D03*
Y1651114D03*
X666729Y1642504D03*
X1138331Y1565295D03*
X1137320Y1554012D03*
Y1556112D03*
X1138480Y1574096D03*
Y1571996D03*
X1138331Y1567395D03*
X1152186Y1565424D03*
X1146689Y1568275D03*
Y1570375D03*
X1142959Y1568294D03*
Y1570394D03*
X1152186Y1567524D03*
X1166873Y1565650D03*
Y1563550D03*
Y1576450D03*
Y1574350D03*
Y1568950D03*
Y1571050D03*
X1162615Y1591163D03*
Y1593263D03*
X1163688Y1661052D03*
Y1663152D03*
X1159688Y1661052D03*
Y1663152D03*
X1183824Y1490895D03*
X1177124Y1500595D03*
Y1502695D03*
X1180724Y1500595D03*
Y1502695D03*
X1183824Y1492995D03*
X1179306Y1559631D03*
Y1561731D03*
Y1556431D03*
Y1554331D03*
X1187424Y1490895D03*
Y1492995D03*
X1197224Y1510295D03*
Y1512395D03*
X1199539Y1640286D03*
X1195939D03*
X1199539Y1642386D03*
X1195939D03*
X1190334Y1666276D03*
Y1664176D03*
X1185676Y1692980D03*
Y1695080D03*
X1210624Y1490895D03*
X1214224D03*
X1203924Y1500595D03*
Y1502695D03*
X1210624Y1492995D03*
X1214224D03*
X1207524Y1500595D03*
Y1502695D03*
X1200824Y1510295D03*
Y1512395D03*
X1211599Y1640286D03*
X1207999D03*
X1211599Y1642386D03*
X1207999D03*
X1224024Y1510295D03*
Y1512395D03*
X1227624Y1510295D03*
Y1512395D03*
X1223659Y1640286D03*
X1220059D03*
X1223659Y1642386D03*
X1220059D03*
X1241024Y1490895D03*
X1237424D03*
X1241024Y1492995D03*
X1237424D03*
X1230724Y1500595D03*
Y1502695D03*
X1234324Y1500595D03*
Y1502695D03*
X1244179Y1640286D03*
X1235719D03*
X1232119D03*
X1244179Y1642386D03*
X1235719D03*
X1232119D03*
X1257524Y1500595D03*
Y1502695D03*
X1250824Y1510295D03*
Y1512395D03*
X1254424Y1510295D03*
Y1512395D03*
X1259839Y1640286D03*
X1256239D03*
X1247779D03*
X1259839Y1642386D03*
X1256239D03*
X1247779D03*
X1264224Y1490895D03*
X1267824D03*
X1264224Y1492995D03*
X1261124Y1500595D03*
Y1502695D03*
X1267824Y1492995D03*
X1262253Y1588300D03*
Y1586200D03*
X1269153Y1586410D03*
Y1588510D03*
X1271899Y1640286D03*
X1268299D03*
X1271899Y1642386D03*
X1268299D03*
X1277624Y1490895D03*
X1281224D03*
X1277624Y1492995D03*
X1281224D03*
X1276253Y1591650D03*
Y1589550D03*
Y1586650D03*
Y1584550D03*
X1279453Y1587350D03*
Y1585250D03*
X1283959Y1640286D03*
X1280359D03*
X1283959Y1642386D03*
X1280359D03*
X1290873Y1549750D03*
Y1551850D03*
X1294073Y1549750D03*
Y1551850D03*
X1290873Y1554750D03*
Y1556850D03*
X1294073Y1554750D03*
Y1556850D03*
X1304479Y1640286D03*
X1296019D03*
X1292419D03*
X1304479Y1642386D03*
X1296019D03*
X1292419D03*
X1311886Y1490895D03*
X1315486D03*
X1311886Y1492995D03*
X1305186Y1500595D03*
Y1502695D03*
X1308786Y1500595D03*
Y1502695D03*
X1315486Y1492995D03*
X1307368Y1559631D03*
Y1561731D03*
Y1556431D03*
Y1554331D03*
X1319349Y1590039D03*
Y1587939D03*
Y1595039D03*
Y1592939D03*
X1315072Y1585888D03*
Y1583788D03*
Y1590888D03*
Y1588788D03*
X1308072Y1586688D03*
Y1588788D03*
X1311872Y1585888D03*
Y1583788D03*
Y1590888D03*
Y1588788D03*
X1316539Y1640286D03*
X1308079D03*
X1316539Y1642386D03*
X1308079D03*
X1331986Y1500595D03*
Y1502695D03*
X1325286Y1510295D03*
Y1512395D03*
X1328886Y1510295D03*
Y1512395D03*
X1332199Y1640286D03*
X1328599D03*
X1320139D03*
X1332199Y1642386D03*
X1328599D03*
X1320139D03*
X1342286Y1490895D03*
X1338686D03*
X1335586Y1500595D03*
Y1502695D03*
X1342286Y1492995D03*
X1338686D03*
X1344259Y1640286D03*
X1340659D03*
X1344259Y1642386D03*
X1340659D03*
X1358786Y1500595D03*
Y1502695D03*
X1362386Y1500595D03*
Y1502695D03*
X1355686Y1510295D03*
Y1512395D03*
X1352086Y1510295D03*
Y1512395D03*
X1356319Y1640286D03*
X1352719D03*
X1356319Y1642386D03*
X1352719D03*
X1369086Y1490895D03*
X1365486D03*
X1369086Y1492995D03*
X1365486D03*
X1378886Y1510295D03*
Y1512395D03*
X1376839Y1640286D03*
X1368379D03*
X1364779D03*
X1376839Y1642386D03*
X1368379D03*
X1364779D03*
X1392286Y1490895D03*
X1385586Y1500595D03*
Y1502695D03*
X1392286Y1492995D03*
X1389186Y1500595D03*
Y1502695D03*
X1382486Y1510295D03*
Y1512395D03*
X1383800Y1604750D03*
Y1606850D03*
X1387000Y1604750D03*
Y1606850D03*
X1390200Y1604750D03*
Y1606850D03*
X1393400Y1604750D03*
Y1606850D03*
X1380439Y1640286D03*
Y1642386D03*
X1405686Y1490895D03*
X1395886D03*
X1405686Y1492995D03*
X1395886D03*
X1404315Y1591650D03*
Y1589550D03*
Y1586650D03*
Y1584550D03*
X1397955Y1591650D03*
Y1589550D03*
X1407515Y1586650D03*
Y1584550D03*
X1397955Y1586650D03*
Y1584550D03*
X1409286Y1490895D03*
Y1492995D03*
X1418935Y1549750D03*
Y1551850D03*
X1422135Y1549750D03*
Y1551850D03*
X1418935Y1554750D03*
Y1556850D03*
X1422135Y1554750D03*
Y1556850D03*
X1451598Y1490895D03*
X1447998D03*
X1441298Y1500595D03*
Y1502695D03*
X1444898Y1500595D03*
Y1502695D03*
X1451598Y1492995D03*
X1447998D03*
X1443480Y1559631D03*
Y1561731D03*
Y1556431D03*
Y1554331D03*
X1451184Y1585888D03*
Y1583788D03*
Y1590888D03*
Y1588788D03*
X1444184Y1586688D03*
Y1588788D03*
X1447984Y1585888D03*
Y1583788D03*
Y1590888D03*
Y1588788D03*
X1468098Y1500595D03*
Y1502695D03*
X1464998Y1510295D03*
Y1512395D03*
X1461398Y1510295D03*
Y1512395D03*
X1455461Y1590039D03*
Y1587939D03*
Y1595039D03*
Y1592939D03*
X1459713Y1631377D03*
Y1633477D03*
X1463313Y1631377D03*
Y1633477D03*
X1465500Y1668450D03*
Y1670550D03*
X1478398Y1490895D03*
X1474798D03*
X1478398Y1492995D03*
X1474798D03*
X1471698Y1500595D03*
Y1502695D03*
X1475773Y1640286D03*
X1472173D03*
X1475773Y1642386D03*
X1472173D03*
X1481000Y1684050D03*
Y1681950D03*
X1494898Y1500595D03*
Y1502695D03*
X1498498Y1500595D03*
Y1502695D03*
X1491798Y1510295D03*
Y1512395D03*
X1488198Y1510295D03*
Y1512395D03*
X1496293Y1640286D03*
X1487833D03*
X1484233D03*
X1496293Y1642386D03*
X1487833D03*
X1484233D03*
X1505198Y1490895D03*
X1501598D03*
X1505198Y1492995D03*
X1501598D03*
X1511953Y1640286D03*
X1508353D03*
X1499893D03*
X1511953Y1642386D03*
X1508353D03*
X1499893D03*
X1528398Y1490895D03*
Y1492995D03*
X1521698Y1500595D03*
Y1502695D03*
X1525298Y1500595D03*
Y1502695D03*
X1518598Y1510295D03*
Y1512395D03*
X1514998Y1510295D03*
Y1512395D03*
X1524013Y1640286D03*
X1520413D03*
X1524013Y1642386D03*
X1520413D03*
X1539062Y64437D03*
Y62337D03*
X1535462Y64437D03*
Y62337D03*
X1541798Y1490895D03*
X1531998D03*
X1541798Y1492995D03*
X1531998D03*
X1540427Y1591650D03*
Y1589550D03*
Y1586650D03*
Y1584550D03*
X1534067Y1591650D03*
Y1589550D03*
Y1586650D03*
Y1584550D03*
X1536073Y1640286D03*
X1532473D03*
X1536073Y1642386D03*
X1532473D03*
X1550062Y70437D03*
Y68337D03*
X1557462Y64437D03*
Y62337D03*
X1546462Y70437D03*
Y68337D03*
X1545398Y1490895D03*
Y1492995D03*
X1555047Y1549750D03*
Y1551850D03*
X1558247Y1549750D03*
Y1551850D03*
X1555047Y1554750D03*
Y1556850D03*
X1558247Y1554750D03*
Y1556850D03*
X1543627Y1587350D03*
Y1585250D03*
X1556593Y1640286D03*
X1548133D03*
X1544533D03*
X1556593Y1642386D03*
X1548133D03*
X1544533D03*
X1568462Y70437D03*
Y68337D03*
X1572062Y70437D03*
Y68337D03*
X1561062Y64437D03*
Y62337D03*
X1569360Y1500595D03*
Y1502695D03*
X1572960Y1500595D03*
Y1502695D03*
X1571542Y1559631D03*
Y1561731D03*
Y1556431D03*
Y1554331D03*
X1572246Y1586688D03*
Y1588788D03*
X1572253Y1640286D03*
X1568653D03*
X1560193D03*
X1572253Y1642386D03*
X1568653D03*
X1560193D03*
X1583062Y64437D03*
Y62337D03*
X1579462Y64437D03*
Y62337D03*
X1579660Y1490895D03*
X1576060D03*
X1579660Y1492995D03*
X1576060D03*
X1583523Y1590039D03*
Y1587939D03*
Y1595039D03*
Y1592939D03*
X1579246Y1585888D03*
Y1583788D03*
Y1590888D03*
Y1588788D03*
X1576046Y1585888D03*
Y1583788D03*
Y1590888D03*
Y1588788D03*
X1584313Y1640286D03*
X1580713D03*
X1584313Y1642386D03*
X1580713D03*
X1590462Y70437D03*
Y68337D03*
X1601462Y64437D03*
Y62337D03*
X1594062Y70437D03*
Y68337D03*
X1602860Y1490895D03*
Y1492995D03*
X1596160Y1500595D03*
Y1502695D03*
X1599760Y1500595D03*
Y1502695D03*
X1593060Y1510295D03*
Y1512395D03*
X1589460Y1510295D03*
Y1512395D03*
X1596373Y1640286D03*
X1592773D03*
X1596373Y1642386D03*
X1592773D03*
X1616062Y70437D03*
Y68337D03*
X1605062Y64437D03*
Y62337D03*
X1612462Y70437D03*
Y68337D03*
X1606460Y1490895D03*
Y1492995D03*
X1616260Y1510295D03*
Y1512395D03*
X1616893Y1640286D03*
X1608433D03*
X1604833D03*
X1616893Y1642386D03*
X1608433D03*
X1604833D03*
X1623462Y64437D03*
Y62337D03*
X1627062Y64437D03*
Y62337D03*
X1629660Y1490895D03*
Y1492995D03*
X1622960Y1500595D03*
Y1502695D03*
X1626560Y1500595D03*
Y1502695D03*
X1619860Y1510295D03*
Y1512395D03*
X1632553Y1640286D03*
X1628953D03*
X1620493D03*
X1632553Y1642386D03*
X1628953D03*
X1620493D03*
X1639266Y70437D03*
Y68337D03*
X1635666Y70437D03*
Y68337D03*
X1646666Y64437D03*
Y62337D03*
X1633260Y1490895D03*
Y1492995D03*
X1646660Y1510295D03*
Y1512395D03*
X1643060Y1510295D03*
Y1512395D03*
X1644613Y1640286D03*
X1641013D03*
X1644613Y1642386D03*
X1641013D03*
X1650266Y64437D03*
Y62337D03*
X1661266Y70437D03*
Y68337D03*
X1657666Y70437D03*
Y68337D03*
X1660060Y1490895D03*
X1656460D03*
X1649760Y1500595D03*
Y1502695D03*
X1653360Y1500595D03*
Y1502695D03*
X1660060Y1492995D03*
X1656460D03*
X1662129Y1591650D03*
Y1589550D03*
Y1586650D03*
Y1584550D03*
X1651146Y1667366D03*
Y1669466D03*
X1656136Y1667236D03*
Y1669336D03*
X1668666Y64437D03*
Y62337D03*
X1672266Y64437D03*
Y62337D03*
X1669860Y1490895D03*
X1673460D03*
X1669860Y1492995D03*
X1673460D03*
X1676345Y1535704D03*
Y1533604D03*
X1668489Y1591650D03*
Y1589550D03*
Y1586650D03*
Y1584550D03*
X1671689Y1586650D03*
Y1584550D03*
X1671400Y1665250D03*
Y1667350D03*
X1674600Y1658950D03*
Y1661050D03*
X1671400Y1658950D03*
Y1661050D03*
X1679800Y70437D03*
Y68337D03*
X1690800Y64437D03*
Y62337D03*
X1683400Y70437D03*
Y68337D03*
X1690650Y1579742D03*
Y1577642D03*
X1681000Y1658950D03*
Y1661050D03*
X1677800Y1658950D03*
Y1661050D03*
X1701800Y70437D03*
Y68337D03*
X1694400Y64437D03*
Y62337D03*
X1705400Y70437D03*
Y68337D03*
X1693850Y1579742D03*
Y1577642D03*
G54D229*
X723082Y651187D03*
Y646147D03*
X717176Y651187D03*
Y646147D03*
X1148190Y1558549D03*
Y1553509D03*
X1142284Y1558549D03*
Y1553509D03*
X1470006Y1676881D03*
Y1681921D03*
X1475912Y1676881D03*
Y1681921D03*
G54D319*
X1787943Y192193D03*
X1806547D03*
G54D37*
X50380Y520331D03*
X48412D03*
Y535095D03*
X50380D03*
X58254Y520331D03*
X56286D03*
X54317D03*
X52349D03*
Y535095D03*
X54317D03*
X56286D03*
X58254D03*
X411403Y1603375D03*
X413372D03*
X415340D03*
X417309D03*
X419277D03*
X421246D03*
X423214D03*
X411403Y1622075D03*
X413372D03*
X415340D03*
X417309D03*
X419277D03*
X421246D03*
X423214D03*
X425183Y1603375D03*
Y1622075D03*
X1124532Y1637591D03*
X1122563D03*
X1120595D03*
X1118626D03*
X1124532Y1656291D03*
X1122563D03*
X1120595D03*
X1118626D03*
X1132406Y1637591D03*
X1130437D03*
X1128469D03*
X1126500D03*
X1132406Y1656291D03*
X1130437D03*
X1128469D03*
X1126500D03*
G54D247*
X776718Y1575473D03*
Y1589253D03*
X794436Y1575473D03*
Y1589253D03*
X818718Y1575473D03*
Y1589253D03*
X836436Y1575473D03*
Y1589253D03*
X860718Y1575473D03*
Y1589253D03*
X878436Y1575473D03*
Y1589253D03*
X902718Y1575473D03*
Y1589253D03*
X920436Y1575473D03*
Y1589253D03*
G54D274*
X928740Y321654D03*
G54D28*
X34296Y517025D03*
X34580Y1497914D03*
Y1502214D03*
X39849Y282916D03*
Y277798D03*
X37984Y288500D03*
X39849Y312916D03*
Y307798D03*
X46984Y303500D03*
X41117Y1622896D03*
Y1626896D03*
X38411Y1668587D03*
Y1663587D03*
X62709Y268223D03*
X62839Y280357D03*
Y276357D03*
Y272357D03*
X67484Y290000D03*
X62839Y310357D03*
X53984Y303500D03*
X64680Y1552869D03*
X77238Y157191D03*
Y161191D03*
Y165191D03*
X68592Y423746D03*
X75117Y521613D03*
Y525513D03*
Y543213D03*
Y539313D03*
X81680Y1549369D03*
X85085Y140950D03*
X84858Y386502D03*
X84875Y376026D03*
X90039Y1307499D03*
X90059Y1311619D03*
X89984Y1440000D03*
Y1444500D03*
Y1448500D03*
X86967Y1663138D03*
X86926Y1667127D03*
X88404Y1698511D03*
Y1702511D03*
X88241Y1724331D03*
Y1720331D03*
X104738Y153691D03*
Y158191D03*
X108949Y1385562D03*
X109984Y1414500D03*
X98984Y1412500D03*
Y1408000D03*
Y1417000D03*
Y1421500D03*
Y1444500D03*
Y1448500D03*
X98495Y1552796D03*
X107577Y1597797D03*
X115837Y1670313D03*
Y1674313D03*
X117484Y1712450D03*
X137961Y679290D03*
Y675290D03*
X130401Y1382305D03*
X141549Y1385562D03*
X132552Y1709346D03*
X139802Y1709166D03*
X144476Y526997D03*
X147984Y1433500D03*
Y1429500D03*
Y1437500D03*
X152837Y1670087D03*
X146837Y1682587D03*
X142751Y1718241D03*
X171344Y400560D03*
X163101Y1382305D03*
X165799Y1726500D03*
X177584Y412350D03*
X174249Y1385562D03*
X174984Y1715000D03*
Y1721000D03*
X195904Y144962D03*
X196984Y149000D03*
X197484Y156500D03*
X196001Y1382305D03*
X207149Y1385562D03*
X213557Y1419187D03*
X208984Y1707000D03*
X209299Y1723000D03*
X223964Y120662D03*
Y124662D03*
X225336Y148750D03*
X220984Y156500D03*
X227504Y206820D03*
X228801Y1382305D03*
X245204Y71862D03*
X232117Y571129D03*
X235770Y711602D03*
X239949Y1385562D03*
X250281Y111743D03*
X259645Y140882D03*
X250524Y224370D03*
X251111Y640909D03*
X274940Y74536D03*
X270034Y142892D03*
X262795Y144882D03*
X270037Y159203D03*
Y155203D03*
X263194Y207660D03*
X272984Y215000D03*
X264984Y221500D03*
X270903Y611172D03*
X265075Y644555D03*
X274482Y676901D03*
X273549Y1339416D03*
X276751Y99183D03*
X279884Y136962D03*
X279984Y207000D03*
Y211000D03*
X286775Y570398D03*
X279885Y585178D03*
X285341Y674150D03*
X298431Y75673D03*
X301150Y71128D03*
X299537Y156203D03*
Y151703D03*
X297805Y678796D03*
X295297Y1336131D03*
X320041Y91803D03*
X318984Y263000D03*
X317127Y694525D03*
X307212Y711142D03*
X306445Y1339388D03*
X325526Y69863D03*
X328875Y545521D03*
X331713Y566086D03*
X330575Y698946D03*
X328201Y1336074D03*
X337398Y165170D03*
X346200Y225070D03*
X341984Y285000D03*
X339982Y731292D03*
X339349Y1339331D03*
X355399Y215325D03*
X355417Y211407D03*
X360984Y307500D03*
X359091Y550415D03*
X356641Y562415D03*
Y566415D03*
Y570415D03*
Y574415D03*
X363635Y698678D03*
X361001Y1336274D03*
X366680Y130165D03*
X373947Y158028D03*
X368799Y211361D03*
Y219361D03*
X376529Y225145D03*
X368799Y215361D03*
X376529Y228645D03*
X377039Y243615D03*
X367616Y617438D03*
X373042Y731024D03*
X372149Y1339531D03*
X374246Y1387697D03*
X389477Y142937D03*
X384072Y280370D03*
Y294370D03*
X394484Y311500D03*
X398890Y134980D03*
X395780Y138980D03*
X408625Y148300D03*
X396984Y304000D03*
X402855Y551915D03*
X396675Y698746D03*
X406082Y731092D03*
X404731Y1358862D03*
X407490Y1631219D03*
X408984Y1645500D03*
Y1653500D03*
X422477Y59935D03*
X422321Y71665D03*
Y66865D03*
X423285Y99148D03*
X419735Y104148D03*
X415625Y144300D03*
Y148300D03*
X417424Y235442D03*
X418199Y250165D03*
Y258165D03*
Y266165D03*
X418650Y1006123D03*
Y1009864D03*
Y1013604D03*
Y1028564D03*
Y1021084D03*
Y1024824D03*
Y1017344D03*
X411984Y1637000D03*
X416984Y1657500D03*
X429675Y680946D03*
X439082Y713292D03*
X428100Y1014766D03*
X437929Y1014745D03*
X437925Y1018879D03*
X428082D03*
X437925Y1023013D03*
X428082D03*
X452389Y270911D03*
X446783Y1014745D03*
Y1018879D03*
Y1023013D03*
X441484Y1604200D03*
Y1600200D03*
X444984Y1622700D03*
Y1618700D03*
X465712Y70016D03*
X468880Y239764D03*
Y227764D03*
Y231764D03*
Y247764D03*
X462075Y656346D03*
X457019Y1014745D03*
Y1018879D03*
Y1023013D03*
X467984Y1668000D03*
Y1659500D03*
Y1676000D03*
X468484Y1697000D03*
X475337Y60029D03*
X475267Y55135D03*
X475337Y64975D03*
X476609Y90574D03*
Y105574D03*
Y100574D03*
Y95574D03*
X476674Y119644D03*
Y115644D03*
X476609Y110574D03*
X476674Y123644D03*
X476412Y284738D03*
Y280858D03*
X484949Y578572D03*
X471482Y688692D03*
X475484Y1655500D03*
Y1672000D03*
X472984Y1680000D03*
X475484Y1701000D03*
Y1706500D03*
Y1714500D03*
X492981Y171625D03*
X492166Y193516D03*
Y189516D03*
X486237Y206827D03*
X489168Y233000D03*
X497518Y238119D03*
X494675Y629846D03*
X500716Y193516D03*
Y185516D03*
X508991D03*
X500716Y189516D03*
X504260Y205285D03*
X511260Y202404D03*
X504082Y662192D03*
X529484Y432500D03*
X527975Y595746D03*
X544680Y195256D03*
X539484Y445500D03*
X537382Y628092D03*
X554320Y152742D03*
X559062Y193541D03*
X546472Y218441D03*
Y230441D03*
Y239566D03*
X556157Y399586D03*
Y414274D03*
Y423949D03*
X553484Y451000D03*
X547221Y663689D03*
X574220Y235821D03*
X563412Y293738D03*
Y289858D03*
X563484Y451000D03*
X572984Y471500D03*
X561984Y477500D03*
X572984Y475500D03*
X586687Y164356D03*
Y169415D03*
X578521Y193516D03*
X578536Y197481D03*
X581008Y261171D03*
X586107Y411846D03*
Y423949D03*
Y435949D03*
X574984Y462000D03*
X586690Y454242D03*
X574984Y466000D03*
X579984Y475500D03*
Y479500D03*
X603251Y136408D03*
X603254Y132270D03*
X603253Y141640D03*
X594007Y208991D03*
X594013Y221277D03*
Y217277D03*
Y225277D03*
Y229277D03*
X593294Y400287D03*
Y404287D03*
X593611Y458461D03*
X593690Y454242D03*
X593487Y468893D03*
X593505Y479631D03*
X596984Y493500D03*
X603255Y1266598D03*
Y1262598D03*
X605984Y412000D03*
X614984Y440000D03*
X623513Y221777D03*
Y226277D03*
X632905Y474020D03*
X630386Y1357114D03*
X622343Y1367166D03*
X622261Y1386732D03*
X646145Y473905D03*
X644884Y1728000D03*
Y1722138D03*
Y1717138D03*
Y1733000D03*
X649298Y166053D03*
Y161862D03*
X649350Y174201D03*
X649298Y170053D03*
X655484Y390000D03*
X659424Y461818D03*
X659407Y457755D03*
X653549Y486941D03*
X658720Y1371199D03*
X658652Y1378931D03*
X658686Y1375061D03*
X656284Y1698400D03*
Y1712084D03*
X651884Y1728000D03*
Y1717138D03*
Y1722138D03*
Y1733000D03*
X675529Y401567D03*
Y409320D03*
Y405488D03*
X675484Y457862D03*
Y453862D03*
Y461862D03*
Y477862D03*
Y465862D03*
X675400Y474268D03*
X675484Y482862D03*
X664439Y486941D03*
X664301Y495126D03*
X669770Y504895D03*
X677770D03*
X668484Y529500D03*
X674084Y1308002D03*
X665484Y1708184D03*
X683437Y115868D03*
X683261Y1530526D03*
Y1526526D03*
X680777Y1639704D03*
Y1643904D03*
X705124Y1560573D03*
X705094Y1580523D03*
X704984Y1608500D03*
Y1600500D03*
X705625Y1616656D03*
X699901Y1670408D03*
X699939Y1674429D03*
X699823Y1678474D03*
X709907Y103308D03*
X713184Y157762D03*
X732977Y90998D03*
X733007Y95158D03*
X738139Y1400414D03*
X728345Y1614743D03*
X748719Y142050D03*
X751184Y167537D03*
X760102Y89348D03*
X754617Y111288D03*
X759751Y276322D03*
X766727Y299279D03*
X755094Y1576023D03*
Y1589023D03*
Y1584023D03*
X766134Y1591733D03*
X760146Y1693369D03*
X777773Y158026D03*
X777787Y153728D03*
X780527Y299279D03*
X781984Y371000D03*
Y364000D03*
X774984D03*
X778153Y419464D03*
X778136Y455344D03*
Y463344D03*
Y459344D03*
Y476344D03*
Y472344D03*
Y487344D03*
Y491344D03*
Y499344D03*
Y495344D03*
X791250Y267822D03*
Y281822D03*
X792586Y415344D03*
X792484Y407500D03*
X792636Y439344D03*
Y451344D03*
Y463344D03*
Y459344D03*
Y455344D03*
Y471344D03*
X792805Y467646D03*
X793146Y483458D03*
X793363Y479511D03*
X792984Y507000D03*
X795330Y1328662D03*
X808543Y386791D03*
X808550Y381020D03*
Y376753D03*
X801484Y392500D03*
X809559Y422687D03*
X809370Y431344D03*
X809286Y463578D03*
X809198Y449802D03*
X809417Y471344D03*
X809530Y476159D03*
X809417Y487344D03*
X809486Y491344D03*
X809530Y480159D03*
X809484Y504000D03*
X809603Y495344D03*
X809484Y512000D03*
Y516000D03*
X811484Y534500D03*
X811192Y541448D03*
X807348Y1340762D03*
Y1336334D03*
X802484Y1330000D03*
X807755Y1351988D03*
X810895Y1364193D03*
X807634Y1574633D03*
Y1590633D03*
Y1598633D03*
Y1606633D03*
X823903Y415344D03*
Y419344D03*
X823895Y423099D03*
X823903Y455344D03*
X823842Y463578D03*
Y471344D03*
Y467568D03*
X834446Y58632D03*
X831204Y166862D03*
Y176362D03*
X838984Y393000D03*
X830167Y405347D03*
X834984Y471000D03*
X830652Y497912D03*
X851804Y162762D03*
X843685Y490567D03*
X843721Y486478D03*
X843684Y482128D03*
X849241Y507106D03*
X843570Y494661D03*
X856003Y494585D03*
X855809Y503154D03*
X856075Y498861D03*
X849634Y1574633D03*
Y1590633D03*
Y1598633D03*
Y1606633D03*
X859287Y269057D03*
X859317Y273217D03*
X859205Y384030D03*
X861984Y395500D03*
X871504Y418720D03*
X874204Y166362D03*
X882204Y171362D03*
Y176862D03*
X884209Y187449D03*
X884199Y183169D03*
X886912Y267407D03*
X880899Y289439D03*
X887984Y326000D03*
X888966Y1056033D03*
X891634Y1574633D03*
Y1590633D03*
Y1598633D03*
Y1606633D03*
X905265Y606915D03*
X919940Y570706D03*
X933634Y1582233D03*
Y1578233D03*
Y1586233D03*
X961109Y198171D03*
X948027Y585200D03*
X948715Y614150D03*
X947540Y628662D03*
X961961Y1498695D03*
X984608Y189347D03*
X987939Y260781D03*
Y271443D03*
X987568Y295641D03*
X991540Y516014D03*
Y521014D03*
Y526074D03*
Y531074D03*
X985327Y1498695D03*
X997396Y221233D03*
Y225233D03*
X1003818Y446175D03*
Y457175D03*
Y451675D03*
Y462675D03*
Y468175D03*
Y479175D03*
Y473675D03*
Y494175D03*
Y490175D03*
Y484675D03*
Y499675D03*
X1012794Y153868D03*
X1016704Y198999D03*
X1016679Y207423D03*
X1016604Y203099D03*
X1016679Y214423D03*
Y222423D03*
Y218423D03*
Y226423D03*
X1018318Y287311D03*
Y298311D03*
X1010186Y433426D03*
X1017041Y420902D03*
X1014248Y484155D03*
X1011690Y510304D03*
X1015984Y560500D03*
X1008693Y1498695D03*
X1024443Y397726D03*
X1024484Y566000D03*
X1032059Y1498695D03*
X1045586Y1646205D03*
X1045454Y1652082D03*
X1058001Y406560D03*
X1058964Y490037D03*
X1060630Y1311203D03*
Y1307203D03*
X1055425Y1498695D03*
X1068730Y445499D03*
X1068780Y457959D03*
X1068748Y453655D03*
Y449655D03*
X1068778Y462525D03*
X1077694Y457959D03*
X1068778Y467000D03*
Y471500D03*
X1068748Y479655D03*
X1080687Y1385543D03*
X1078791Y1498695D03*
X1093422Y446105D03*
Y440605D03*
Y462605D03*
Y457105D03*
Y451605D03*
Y468105D03*
X1086422Y472105D03*
X1093422Y489641D03*
Y484605D03*
Y494641D03*
X1094323Y1633726D03*
X1094365Y1629945D03*
X1101932Y479355D03*
X1102139Y1382286D03*
X1102157Y1498695D03*
X1102507Y1634400D03*
X1102700Y1630123D03*
X1101984Y1639000D03*
X1113287Y1385543D03*
X1129717Y52651D03*
X1136890Y52599D03*
X1136122Y56512D03*
X1136389Y380533D03*
Y385698D03*
X1127393Y398020D03*
X1134839Y1382286D03*
X1150302Y74738D03*
X1155177Y204835D03*
Y209835D03*
X1147722Y489819D03*
X1145987Y1385543D03*
X1150367Y1436579D03*
X1160622Y461691D03*
Y457691D03*
Y449691D03*
Y453691D03*
Y465691D03*
Y469691D03*
Y481691D03*
X1167739Y1382286D03*
X1174913Y89556D03*
Y93556D03*
X1182675Y95864D03*
X1172016Y580602D03*
X1172076Y584622D03*
X1178887Y1385543D03*
X1184084Y1433000D03*
X1195771Y61515D03*
X1195871Y57015D03*
X1195791Y52815D03*
X1188972Y87125D03*
Y91125D03*
X1195186Y164987D03*
Y160987D03*
X1191411Y436202D03*
Y444202D03*
Y452202D03*
X1200599Y1382088D03*
X1199984Y1396500D03*
Y1401000D03*
Y1410000D03*
Y1405500D03*
Y1424000D03*
X1191084Y1428500D03*
Y1433000D03*
X1199984Y1437500D03*
Y1447500D03*
Y1442500D03*
X1192839Y1673050D03*
X1192521Y1697850D03*
X1199521D03*
X1213065Y94846D03*
X1205240Y133866D03*
Y128748D03*
X1205496Y177187D03*
Y181187D03*
X1205527Y188942D03*
X1202911Y460202D03*
X1202971Y465272D03*
X1203047Y470376D03*
X1211687Y1385543D03*
X1210984Y1401000D03*
X1208181Y1673059D03*
X1207863Y1697859D03*
X1214863D03*
X1244677Y145239D03*
X1239938Y447255D03*
Y443255D03*
X1244801Y1418462D03*
X1244843Y1422362D03*
X1257931Y464372D03*
X1248811Y468152D03*
X1258984Y765000D03*
X1249678Y1339397D03*
X1261091Y155730D03*
Y164051D03*
Y160051D03*
Y176051D03*
Y180551D03*
Y168051D03*
Y172051D03*
Y185051D03*
X1273533Y390884D03*
X1265484Y390500D03*
X1265686Y411125D03*
Y407125D03*
Y415125D03*
X1271426Y1336112D03*
X1275595Y150030D03*
X1289591Y162051D03*
Y166051D03*
Y171551D03*
Y184051D03*
X1282574Y1339369D03*
X1284584Y1430000D03*
Y1434000D03*
X1298177Y133739D03*
Y125739D03*
Y129739D03*
Y145739D03*
X1293186Y403625D03*
Y408125D03*
X1296240Y552147D03*
X1294850Y597013D03*
X1304330Y1336055D03*
X1307126Y537299D03*
X1307242Y556545D03*
X1315478Y1339312D03*
X1346244Y674443D03*
X1337130Y1336255D03*
X1348278Y1339512D03*
X1371168Y100509D03*
X1375627Y613889D03*
X1369890Y1355715D03*
X1385034Y646235D03*
X1380860Y1358843D03*
X1391977Y1670391D03*
X1384977Y1674391D03*
X1387529Y1704038D03*
X1385288Y1733118D03*
X1399741Y642765D03*
X1408327Y646789D03*
X1394792Y1009863D03*
Y1013603D03*
X1404224Y1014744D03*
X1394792Y1006122D03*
X1404224Y1018878D03*
Y1023012D03*
X1394792Y1017343D03*
Y1028563D03*
Y1024823D03*
Y1021083D03*
X1408117Y1622167D03*
X1401117Y1626167D03*
X1404967Y1630167D03*
X1417734Y679135D03*
X1422925Y1014744D03*
X1414071D03*
X1422925Y1023012D03*
X1414067Y1018878D03*
X1422925D03*
X1414067Y1023012D03*
X1421799Y1642967D03*
X1435103Y244450D03*
X1433741Y675765D03*
X1433161Y1014744D03*
Y1023012D03*
Y1018878D03*
X1435793Y1609966D03*
X1426781Y1619504D03*
Y1613966D03*
X1435981Y1619566D03*
X1448103Y244450D03*
X1440927Y679369D03*
X1450334Y711715D03*
X1467889Y61563D03*
X1458726Y128242D03*
X1461741Y564977D03*
X1465241Y695265D03*
X1474889Y61563D03*
X1469741Y548977D03*
Y552977D03*
Y544977D03*
Y556977D03*
Y560977D03*
Y564977D03*
X1473845Y698946D03*
X1483252Y731292D03*
X1513741Y543977D03*
X1506927Y698946D03*
X1526803Y201250D03*
X1516334Y731292D03*
X1542001Y300816D03*
Y308816D03*
Y304816D03*
X1539727Y698946D03*
X1549848Y284575D03*
X1549134Y731292D03*
X1550158Y1266271D03*
X1550161Y1282188D03*
Y1278188D03*
Y1286188D03*
X1569501Y297316D03*
Y301816D03*
X1573127Y531220D03*
X1572857Y677006D03*
X1564972Y1273445D03*
X1582264Y709352D03*
X1584756Y1302278D03*
X1598937Y225250D03*
X1613603Y542733D03*
X1605627Y643237D03*
X1615034Y675583D03*
X1625426Y282728D03*
Y278520D03*
X1625393Y286742D03*
X1618793Y530739D03*
X1632733Y1420450D03*
X1632651Y1444016D03*
Y1440016D03*
X1645672Y627206D03*
X1638627Y624237D03*
X1637817Y1306874D03*
X1640974Y1410398D03*
X1642651Y1442228D03*
X1658009Y141762D03*
Y146762D03*
Y151762D03*
Y161762D03*
X1648034Y656583D03*
X1659650Y696318D03*
X1669240Y1432215D03*
X1669274Y1428345D03*
X1669308Y1424483D03*
X1669326Y1420567D03*
X1685872Y1399703D03*
X1691135Y1559526D03*
Y1563526D03*
X1704778Y373773D03*
Y369773D03*
X1702868Y401485D03*
X1695011Y1696422D03*
X1717674Y364962D03*
X1712818Y666238D03*
Y662238D03*
X1725402Y112867D03*
X1733063Y1530950D03*
Y1535250D03*
X1729947Y1663465D03*
Y1667965D03*
Y1658965D03*
Y1672465D03*
X1739793Y85339D03*
X1751872Y100307D03*
X1749094Y305106D03*
X1742981Y1435005D03*
X1751963Y1585905D03*
X1741947Y1653965D03*
X1738413Y1649456D03*
X1763552Y76797D03*
X1763522Y72637D03*
X1756420Y85407D03*
X1754204Y372452D03*
X1781559Y190799D03*
X1768963Y1582405D03*
X1771412Y1666984D03*
X1771373Y1670514D03*
X1770947Y1685465D03*
X1771292Y1674057D03*
X1770947Y1681702D03*
Y1678172D03*
Y1689965D03*
X1790647Y70987D03*
X1785162Y92927D03*
X1792874Y146834D03*
Y151834D03*
Y165834D03*
X1795255Y367866D03*
X1787783Y403932D03*
X1795255Y390411D03*
X1787783Y410432D03*
Y418932D03*
Y425432D03*
X1785778Y1585832D03*
X1825064Y147834D03*
X1818064Y151834D03*
X1820216Y371329D03*
X1826153Y383952D03*
Y379552D03*
X1820053Y395552D03*
X1819283Y407932D03*
X1818783Y421432D03*
Y427432D03*
X1818776Y431678D03*
X1827216Y371329D03*
Y367359D03*
X1847775Y161834D03*
G54D193*
X478794Y304928D03*
X565794Y313928D03*
G54D328*
X1900275Y-39973D03*
Y572227D03*
X1898799Y1198198D03*
Y1810398D03*
X1910275Y-39973D03*
Y572227D03*
X1908799Y1198198D03*
Y1810398D03*
X1921395Y-39963D03*
X1931395D03*
Y572237D03*
X1921395D03*
X1931395D03*
X1921395D03*
Y1184437D03*
X1931395D03*
X1929766Y1198160D03*
X1919766D03*
Y1810360D03*
X1929766D03*
X1942395Y-39783D03*
Y572417D03*
D03*
X1940886Y1198170D03*
X1942395Y1184617D03*
X1940886Y1810370D03*
X1952395Y-39783D03*
X1963362Y-39821D03*
Y572379D03*
X1952395Y572417D03*
D03*
X1963362Y572379D03*
X1950886Y1198170D03*
X1952395Y1184617D03*
X1963362Y1184579D03*
X1961856Y1198170D03*
X1950886Y1810370D03*
X1961856D03*
X1973362Y-39821D03*
Y572379D03*
D03*
Y1184579D03*
X1971856Y1198170D03*
Y1810370D03*
X1984482Y-39811D03*
Y572389D03*
D03*
Y1184589D03*
X1982856Y1198350D03*
X1992856D03*
Y1810550D03*
X1982856D03*
X1994482Y-39811D03*
X2005452D03*
Y572389D03*
X1994482D03*
D03*
X2005452D03*
X1994482Y1184589D03*
X2005452D03*
X2003823Y1198312D03*
Y1810512D03*
X2015452Y-39811D03*
Y572389D03*
D03*
Y1184589D03*
X2013823Y1198312D03*
Y1810512D03*
X2036452Y-39631D03*
X2026452D03*
Y572569D03*
X2036452D03*
X2026452D03*
X2036452D03*
Y1184769D03*
X2026452D03*
X2047419Y-39669D03*
Y572531D03*
D03*
Y1184731D03*
X2057419Y-39669D03*
Y572531D03*
D03*
Y1184731D03*
X2068539Y572541D03*
X2078539D03*
Y1184741D03*
X2068539D03*
G54D91*
X134853Y1672087D03*
G54D265*
X876098Y1092807D03*
X897358D03*
X966577Y1092258D03*
X987837D03*
G54D55*
X55756Y1531020D03*
Y1532792D03*
Y1534564D03*
Y1536335D03*
Y1538107D03*
Y1539879D03*
X96966Y159744D03*
Y157775D03*
Y155807D03*
Y153838D03*
X85942D03*
Y155807D03*
Y157775D03*
Y159744D03*
X91499Y1531020D03*
Y1532792D03*
Y1534564D03*
Y1536335D03*
Y1538107D03*
Y1539879D03*
X103152Y1370457D03*
Y1368686D03*
Y1366914D03*
Y1365142D03*
Y1372229D03*
Y1374001D03*
X135752Y1370457D03*
Y1368686D03*
Y1366914D03*
Y1365142D03*
Y1372229D03*
Y1374001D03*
X168452Y1370457D03*
Y1368686D03*
Y1366914D03*
Y1365142D03*
Y1372229D03*
Y1374001D03*
X201352Y1370457D03*
Y1368686D03*
Y1366914D03*
Y1365142D03*
Y1372229D03*
Y1374001D03*
X234152Y1370457D03*
Y1368686D03*
Y1366914D03*
Y1365142D03*
Y1372229D03*
Y1374001D03*
X267904Y656116D03*
Y664975D03*
Y663203D03*
Y661431D03*
Y659660D03*
Y657888D03*
X267752Y1327855D03*
Y1324311D03*
Y1322540D03*
Y1320768D03*
Y1318996D03*
Y1326083D03*
X280741Y151850D03*
Y153819D03*
Y155787D03*
Y157756D03*
X291765D03*
Y155787D03*
Y153819D03*
Y151850D03*
X300634Y699216D03*
Y697444D03*
Y695672D03*
Y693901D03*
Y692129D03*
Y690357D03*
X300648Y1327827D03*
Y1324283D03*
Y1322512D03*
Y1320740D03*
Y1318968D03*
Y1326055D03*
X333404Y715822D03*
Y714051D03*
Y712279D03*
Y710507D03*
Y719366D03*
Y717594D03*
X333552Y1327770D03*
Y1324226D03*
Y1322455D03*
Y1320683D03*
Y1318911D03*
Y1325998D03*
X366464Y717326D03*
Y715554D03*
Y713783D03*
Y712011D03*
Y710239D03*
Y719098D03*
X366352Y1327970D03*
Y1324426D03*
Y1322655D03*
Y1320883D03*
Y1319111D03*
Y1326198D03*
X399504Y717394D03*
Y715622D03*
Y713851D03*
Y712079D03*
Y710307D03*
Y719166D03*
X398934Y1341986D03*
Y1340214D03*
Y1338442D03*
Y1347301D03*
Y1343757D03*
Y1345529D03*
X432504Y701366D03*
Y699594D03*
Y697822D03*
Y696051D03*
Y694279D03*
Y692507D03*
X464904Y671451D03*
Y669679D03*
Y667907D03*
Y676766D03*
Y674994D03*
Y673222D03*
X497504Y641407D03*
Y650266D03*
Y648494D03*
Y646722D03*
Y644951D03*
Y643179D03*
X530804Y612622D03*
Y610851D03*
Y609079D03*
Y607307D03*
Y616166D03*
Y614394D03*
X615741Y223893D03*
Y221924D03*
X604717D03*
Y223893D03*
X615741Y227830D03*
Y225861D03*
X604717D03*
Y227830D03*
X710708Y1386695D03*
Y1384923D03*
Y1383151D03*
Y1392010D03*
Y1388466D03*
Y1390238D03*
X743490Y1386795D03*
Y1385023D03*
Y1383251D03*
Y1392110D03*
Y1388566D03*
Y1390338D03*
X818002Y133945D03*
Y135914D03*
Y137882D03*
Y139851D03*
X829026Y135914D03*
Y133945D03*
Y139851D03*
Y137882D03*
X841967Y211438D03*
Y213407D03*
Y215375D03*
Y217344D03*
X852991D03*
Y215375D03*
Y213407D03*
Y211438D03*
X1074890Y1370438D03*
Y1368667D03*
Y1366895D03*
Y1365123D03*
Y1372210D03*
Y1373982D03*
X1107490Y1370438D03*
Y1368667D03*
Y1366895D03*
Y1365123D03*
Y1372210D03*
Y1373982D03*
X1140190Y1370438D03*
Y1368667D03*
Y1366895D03*
Y1365123D03*
Y1372210D03*
Y1373982D03*
X1173090Y1370438D03*
Y1368667D03*
Y1366895D03*
Y1365123D03*
Y1372210D03*
Y1373982D03*
X1205890Y1370438D03*
Y1368667D03*
Y1366895D03*
Y1365123D03*
Y1372210D03*
Y1373982D03*
X1243881Y1327836D03*
Y1324292D03*
Y1322521D03*
Y1320749D03*
Y1318977D03*
Y1326064D03*
X1274390Y403772D03*
Y405741D03*
Y407709D03*
Y409678D03*
X1285414Y403772D03*
Y409678D03*
Y407709D03*
Y405741D03*
X1276777Y1327808D03*
Y1324264D03*
Y1322493D03*
Y1320721D03*
Y1318949D03*
Y1326036D03*
X1309681Y1327751D03*
Y1324207D03*
Y1322436D03*
Y1320664D03*
Y1318892D03*
Y1325979D03*
X1342481Y1327951D03*
Y1324407D03*
Y1322636D03*
Y1320864D03*
Y1319092D03*
Y1326179D03*
X1378456Y627222D03*
Y625450D03*
Y634309D03*
Y632537D03*
Y630765D03*
Y628994D03*
X1375063Y1341967D03*
Y1340195D03*
Y1338423D03*
Y1347282D03*
Y1343738D03*
Y1345510D03*
X1411156Y667209D03*
Y665437D03*
Y663665D03*
Y661894D03*
Y660122D03*
Y658350D03*
X1443756Y699789D03*
Y698017D03*
Y696245D03*
Y694474D03*
Y692702D03*
Y690930D03*
X1476674Y715822D03*
Y714051D03*
Y712279D03*
Y710507D03*
Y719366D03*
Y717594D03*
X1509756Y715990D03*
Y714219D03*
Y712447D03*
Y710675D03*
Y719534D03*
Y717762D03*
X1542556Y715822D03*
Y714051D03*
Y712279D03*
Y710507D03*
Y719366D03*
Y717594D03*
X1550705Y297463D03*
Y299432D03*
Y301400D03*
Y303369D03*
X1561729Y299432D03*
Y297463D03*
Y303369D03*
Y301400D03*
X1575686Y697426D03*
Y695654D03*
Y693882D03*
Y692111D03*
Y690339D03*
Y688567D03*
X1608456Y656570D03*
Y654798D03*
Y663657D03*
Y661885D03*
Y660113D03*
Y658342D03*
X1641456Y642885D03*
Y641113D03*
Y639342D03*
Y637570D03*
Y635798D03*
Y644657D03*
X1658441Y1387755D03*
Y1385984D03*
Y1384212D03*
Y1382440D03*
Y1391299D03*
Y1389527D03*
X1691223Y1387855D03*
Y1386084D03*
Y1384312D03*
Y1382540D03*
Y1391399D03*
Y1389627D03*
X1683561Y1683292D03*
Y1685261D03*
Y1689198D03*
Y1687229D03*
X1694585Y1683292D03*
Y1685261D03*
Y1689198D03*
Y1687229D03*
X1729480Y367431D03*
Y369400D03*
Y371368D03*
Y373337D03*
X1740504D03*
Y371368D03*
Y369400D03*
Y367431D03*
X1743039Y1564056D03*
Y1565828D03*
Y1567600D03*
Y1569371D03*
Y1571143D03*
Y1572915D03*
X1778782Y1564056D03*
Y1565828D03*
Y1567600D03*
Y1569371D03*
Y1571143D03*
Y1572915D03*
G54D184*
X476412Y288567D03*
X563412Y297567D03*
G54D256*
X804457Y1348236D03*
G54D347*
G01X240246Y781931D02*
X228860D01*
X227186Y780257D01*
X217827D01*
G01X237578Y788624D02*
X227578D01*
X226959Y788005D01*
X224412Y786950D01*
X217827D01*
G01X238860Y805356D02*
X228860D01*
X227186Y803682D01*
X226262D01*
X225863Y804081D01*
Y806670D01*
X225464Y807069D01*
X224712D01*
X224313Y806670D01*
Y804081D01*
X223914Y803682D01*
X217827D01*
G01X237360Y795316D02*
X227360D01*
X226113Y796563D01*
X224566D01*
X222893Y794890D01*
X221169D01*
X219922Y793643D01*
X217827D01*
G01X237360Y798662D02*
X227360D01*
X226110Y797412D01*
X224214D01*
X222541Y795739D01*
X221172D01*
X219922Y796989D01*
X217827D01*
G01X238860Y818742D02*
X228860D01*
X227186Y817068D01*
X217827D01*
G01X238860Y808702D02*
X228860D01*
X227187Y810375D01*
X217827D01*
G01X237578Y825435D02*
X227578D01*
X225904Y823761D01*
X217827D01*
G01X237360Y832127D02*
X227360D01*
X226113Y833374D01*
X224626D01*
X222953Y831701D01*
X221169D01*
X219922Y830454D01*
X217827D01*
G01X237360Y835473D02*
X227360D01*
X226110Y834223D01*
X224274D01*
X222601Y832550D01*
X221172D01*
X219922Y833800D01*
X217827D01*
G01X238860Y842167D02*
X228860D01*
X228844Y842183D01*
X221517D01*
X219827Y840493D01*
X217827D01*
G01X238860Y845513D02*
X228860D01*
X227187Y847186D01*
X217827D01*
G01X238860Y855553D02*
X228860D01*
X227186Y853879D01*
X217827D01*
G01X237578Y862246D02*
X227578D01*
X226959Y861627D01*
X224412Y860572D01*
X217827D01*
G01X238860Y878978D02*
X230232D01*
X228558Y877304D01*
X227419D01*
X227020Y877703D01*
Y879270D01*
X226621Y879669D01*
X225869D01*
X225470Y879270D01*
Y877703D01*
X225071Y877304D01*
X224319D01*
X223920Y877703D01*
Y879270D01*
X223521Y879669D01*
X222769D01*
X222370Y879270D01*
Y877703D01*
X221971Y877304D01*
X217827D01*
G01X237360Y868938D02*
X227360D01*
X226113Y870185D01*
X224518D01*
X222845Y868512D01*
X221169D01*
X219922Y867265D01*
X217827D01*
G01X237360Y872284D02*
X227360D01*
X226110Y871034D01*
X224166D01*
X222493Y869361D01*
X221172D01*
X219922Y870611D01*
X217827D01*
G01X238860Y882324D02*
X228860D01*
X227187Y883997D01*
X217827D01*
G01X238860Y892364D02*
X228860D01*
X227186Y890690D01*
X217827D01*
G01X237578Y899057D02*
X227578D01*
X225904Y897383D01*
X217827D01*
G01X237360Y905750D02*
X227830D01*
X226578Y907002D01*
X225385D01*
X223707Y905324D01*
X221171D01*
X219923Y904076D01*
X217827D01*
G01X237360Y909096D02*
X227792D01*
X226547Y907851D01*
X225033D01*
X223355Y906173D01*
X221196D01*
X219946Y907423D01*
X217827D01*
G01X238860Y915789D02*
X228860D01*
X228853Y915796D01*
X221359D01*
X219678Y914115D01*
X217827D01*
G01X238060Y919795D02*
X237400Y919135D01*
X230640D01*
X228967Y920808D01*
X217827D01*
G01X238860Y929175D02*
X228860D01*
X227186Y927501D01*
X225933D01*
X225534Y927900D01*
Y929510D01*
X225135Y929909D01*
X224383D01*
X223984Y929510D01*
Y927900D01*
X223585Y927501D01*
X217827D01*
G01X237578Y935868D02*
X227578D01*
X225904Y934194D01*
X217827D01*
G01X238860Y952600D02*
X228860D01*
X227186Y950926D01*
X225537D01*
X225077Y951386D01*
Y951899D01*
X224617Y952359D01*
X223966D01*
X223506Y951899D01*
Y951386D01*
X223046Y950926D01*
X217827D01*
G01X237360Y942561D02*
X227830D01*
X226578Y943813D01*
X225457D01*
X223779Y942135D01*
X221171D01*
X219923Y940887D01*
X217827D01*
G01X237360Y945907D02*
X227792D01*
X226547Y944662D01*
X225105D01*
X223427Y942984D01*
X221196D01*
X219946Y944234D01*
X217827D01*
G01X237985Y963299D02*
Y963059D01*
X237565Y962639D01*
X229213D01*
X228860Y962286D01*
G01X238860Y967306D02*
X237539Y965985D01*
X224866D01*
X223193Y964312D01*
X217827D01*
G01X238518Y956636D02*
X237828Y955946D01*
X228860D01*
X224821Y957619D01*
X217827D01*
G01X238242Y980136D02*
X237477Y979371D01*
X228860D01*
X227187Y977698D01*
X217827D01*
G01X238209Y986724D02*
X237549Y986064D01*
X228860D01*
X227187Y984391D01*
X217827D01*
G01X239155Y973909D02*
X237924Y972678D01*
X228860D01*
X227187Y971005D01*
X217827D01*
G01X238324Y993417D02*
X237664Y992757D01*
X228860D01*
X227187Y991084D01*
X217827D01*
G01X238860Y1029568D02*
X228860D01*
X227187Y1031241D01*
X217827D01*
G01X238860Y1036261D02*
X228860D01*
X227187Y1037934D01*
X217827D01*
G01X238860Y1042954D02*
X228860D01*
X227187Y1044627D01*
X217827D01*
G01X238860Y1059686D02*
X238859Y1059687D01*
X228860D01*
X227186Y1058013D01*
X217827D01*
G01X238860Y1049646D02*
X238859Y1049647D01*
X223307D01*
X222887Y1050067D01*
Y1050860D01*
X222427Y1051320D01*
X217827D01*
G01X238764Y1073072D02*
X223633D01*
X221960Y1074745D01*
X217827D01*
G01X239078Y1079766D02*
X238860D01*
X238859Y1079765D01*
X223750D01*
X222077Y1081438D01*
X217827D01*
G01X237745Y1089805D02*
X227830D01*
X226578Y1091057D01*
X225469D01*
X223791Y1089379D01*
X221171D01*
X219923Y1088131D01*
X217827D01*
G01X239078Y1096497D02*
X229059D01*
X227385Y1098171D01*
X217827D01*
G01X239078Y1103190D02*
X229035D01*
X224996Y1104863D01*
X217827D01*
G01X237783Y1093151D02*
X227792D01*
X226547Y1091906D01*
X225117D01*
X223439Y1090228D01*
X221196D01*
X219946Y1091478D01*
X217827D01*
G01X239078Y1109883D02*
X230712D01*
X229039Y1111556D01*
X227473D01*
X227013Y1112016D01*
Y1113166D01*
X226553Y1113626D01*
X225902D01*
X225442Y1113166D01*
Y1110819D01*
X224982Y1110359D01*
X224331D01*
X223871Y1110819D01*
Y1114656D01*
X223411Y1115116D01*
X222760D01*
X222300Y1114656D01*
Y1112016D01*
X221840Y1111556D01*
X217827D01*
G01X239032Y1115867D02*
X238323Y1116576D01*
X227549D01*
X225876Y1118249D01*
X224611D01*
X224212Y1117850D01*
Y1117368D01*
X223813Y1116969D01*
X223061D01*
X222662Y1117368D01*
Y1117850D01*
X222263Y1118249D01*
X217827D01*
G01X239078Y1133308D02*
X229217D01*
X227144Y1135381D01*
Y1136190D01*
X226745Y1136589D01*
X225993D01*
X225594Y1136190D01*
Y1135381D01*
X225195Y1134982D01*
X224443D01*
X224044Y1135381D01*
Y1136190D01*
X223645Y1136589D01*
X222893D01*
X222494Y1136190D01*
Y1135381D01*
X222095Y1134982D01*
X217827D01*
G01X237299Y1126616D02*
X227830D01*
X226578Y1127868D01*
X225541D01*
X223863Y1126190D01*
X221171D01*
X219923Y1124942D01*
X217827D01*
G01X237375Y1129962D02*
X227792D01*
X226547Y1128717D01*
X225189D01*
X223511Y1127039D01*
X221196D01*
X219946Y1128289D01*
X217827D01*
G01X239590Y1147505D02*
X238779Y1146694D01*
X229862D01*
X229463Y1147093D01*
Y1150100D01*
X229064Y1150499D01*
X228312D01*
X227913Y1150100D01*
Y1147093D01*
X227514Y1146694D01*
X226762D01*
X226363Y1147093D01*
Y1150100D01*
X225964Y1150499D01*
X225212D01*
X224813Y1150100D01*
Y1147093D01*
X224414Y1146694D01*
X223641D01*
X221968Y1148367D01*
X217827D01*
G01X238722Y1139341D02*
X238062Y1140001D01*
X228959D01*
X227285Y1141675D01*
X217827D01*
G01X238428Y1152518D02*
X237559Y1153387D01*
X227638D01*
X225965Y1155060D01*
X225033D01*
X224634Y1154661D01*
Y1154058D01*
X224235Y1153659D01*
X223483D01*
X223084Y1154058D01*
Y1154661D01*
X222685Y1155060D01*
X217827D01*
G01X237299Y1163427D02*
X227830D01*
X226578Y1164679D01*
X225453D01*
X223775Y1163001D01*
X221171D01*
X219923Y1161753D01*
X217827D01*
G01X237375Y1166773D02*
X227792D01*
X226547Y1165528D01*
X225101D01*
X223423Y1163850D01*
X221196D01*
X219946Y1165100D01*
X217827D01*
G01X239078Y1169901D02*
X238859Y1170120D01*
X229131D01*
X227458Y1171793D01*
X226667D01*
X226268Y1172192D01*
Y1173200D01*
X225869Y1173599D01*
X225117D01*
X224718Y1173200D01*
Y1172192D01*
X224319Y1171793D01*
X217827D01*
G01X239078Y1176212D02*
X237627Y1176813D01*
X229069D01*
X225030Y1178486D01*
X217827D01*
G01X239078Y1183505D02*
X229829D01*
X228156Y1185178D01*
X227145D01*
X226746Y1184779D01*
Y1183048D01*
X226347Y1182649D01*
X225595D01*
X225196Y1183048D01*
Y1187308D01*
X224797Y1187707D01*
X224045D01*
X223646Y1187308D01*
Y1183048D01*
X223247Y1182649D01*
X222495D01*
X222096Y1183048D01*
Y1184779D01*
X221697Y1185178D01*
X217827D01*
G01X239078Y1190198D02*
X227227D01*
X225554Y1191871D01*
X217827D01*
G01X239078Y1206931D02*
X238860D01*
X238859Y1206930D01*
X229131D01*
X226622Y1209439D01*
X223900D01*
X223065Y1208604D01*
X217827D01*
G01X237299Y1200238D02*
X227830D01*
X226578Y1201490D01*
X225363D01*
X223685Y1199812D01*
X221171D01*
X219923Y1198564D01*
X217827D01*
G01X237375Y1203584D02*
X227792D01*
X226547Y1202339D01*
X225011D01*
X223333Y1200661D01*
X221196D01*
X219946Y1201911D01*
X217827D01*
G01X239078Y1213623D02*
X229131D01*
X227457Y1215297D01*
X217827D01*
G01X239078Y1220316D02*
X227624D01*
X227164Y1220776D01*
Y1221427D01*
X227624Y1221887D01*
X229099D01*
X229559Y1222347D01*
Y1222998D01*
X229099Y1223458D01*
X226053D01*
X225593Y1222998D01*
Y1220776D01*
X225133Y1220316D01*
X224079D01*
X222406Y1221989D01*
X217827D01*
G01X239078Y1227009D02*
X226016D01*
X224343Y1228682D01*
X217827D01*
G01X237299Y1237049D02*
X227830D01*
X226578Y1238301D01*
X225485D01*
X223807Y1236623D01*
X221171D01*
X219923Y1235375D01*
X217827D01*
G01X237375Y1240395D02*
X227792D01*
X226547Y1239150D01*
X225133D01*
X223455Y1237472D01*
X221196D01*
X219946Y1238722D01*
X217827D01*
G01X239078Y1243741D02*
X229131D01*
X227457Y1245415D01*
X217827D01*
G01X239078Y1250434D02*
X229131D01*
X227457Y1252108D01*
X217827D01*
G01X240495Y972139D02*
X237048Y968692D01*
G01X238860Y978844D02*
X238747Y978731D01*
G01X643219Y778584D02*
X657561D01*
X659234Y776911D01*
X663496D01*
G01X643219Y785277D02*
X650774D01*
X659186Y783604D01*
X663496D01*
G01X643963Y791970D02*
X653523D01*
X654773Y790720D01*
X655833D01*
X657507Y792394D01*
X660219D01*
X661468Y793643D01*
X663496D01*
G01X643963Y788624D02*
X653525D01*
X654772Y789871D01*
X656185D01*
X657859Y791545D01*
X660220D01*
X661468Y790297D01*
X663496D01*
G01X643219Y802016D02*
X643226Y802009D01*
X653517D01*
X653977Y802469D01*
Y803312D01*
X654437Y803772D01*
X655087D01*
X655547Y803312D01*
Y800756D01*
X655967Y800336D01*
X656782D01*
X657242Y800796D01*
Y803236D01*
X657702Y803696D01*
X658352D01*
X658812Y803236D01*
Y800796D01*
X659272Y800336D01*
X663496D01*
G01X643219Y808702D02*
X652986D01*
X654659Y807029D01*
X663496D01*
G01X643219Y815395D02*
X657561D01*
X659234Y813722D01*
X663496D01*
G01X643219Y822088D02*
X652311D01*
X653984Y820415D01*
X663496D01*
G01X643069Y838820D02*
X654301D01*
X654755Y839274D01*
Y841835D01*
X655209Y842289D01*
X655851D01*
X656305Y841835D01*
Y839274D01*
X656759Y838820D01*
X658140D01*
X659813Y837147D01*
X663496D01*
G01X643219Y845513D02*
X652986D01*
X654659Y843840D01*
X663496D01*
G01X643219Y852206D02*
X657561D01*
X659234Y850533D01*
X663496D01*
G01X643963Y828781D02*
X653523D01*
X654773Y827531D01*
X655933D01*
X657607Y829205D01*
X660219D01*
X661468Y830454D01*
X663496D01*
G01X643963Y825435D02*
X653525D01*
X654772Y826682D01*
X656285D01*
X657959Y828356D01*
X660220D01*
X661468Y827108D01*
X663496D01*
G01X643219Y858899D02*
X653073D01*
X657112Y857226D01*
X663496D01*
G01X643219Y875631D02*
X654833D01*
X655287Y876085D01*
Y877915D01*
X655741Y878369D01*
X656383D01*
X656837Y877915D01*
Y876085D01*
X657291Y875631D01*
X658140D01*
X659813Y873958D01*
X663496D01*
G01X643963Y865592D02*
X653523D01*
X654773Y864342D01*
X655893D01*
X657567Y866016D01*
X660219D01*
X661468Y867265D01*
X663496D01*
G01X643963Y862246D02*
X653525D01*
X654772Y863493D01*
X656245D01*
X657919Y865167D01*
X660220D01*
X661468Y863919D01*
X663496D01*
G01X643219Y882965D02*
X643860Y882324D01*
X652986D01*
X654659Y880651D01*
X663496D01*
G01X643473Y889677D02*
X644133Y889017D01*
X653543D01*
X653997Y888563D01*
Y887373D01*
X654451Y886919D01*
X655093D01*
X655547Y887373D01*
Y888563D01*
X656001Y889017D01*
X657561D01*
X659234Y887344D01*
X663496D01*
G01X643219Y896087D02*
X644128Y895710D01*
X652720D01*
X656759Y894037D01*
X663496D01*
G01X643963Y902403D02*
X653523D01*
X654773Y901153D01*
X655775D01*
X657449Y902827D01*
X660219D01*
X661468Y904076D01*
X663496D01*
G01X643963Y899057D02*
X653525D01*
X654772Y900304D01*
X656127D01*
X657801Y901978D01*
X660220D01*
X661468Y900730D01*
X663496D01*
G01X641789Y928172D02*
X644133Y925828D01*
X653992D01*
X654446Y925374D01*
Y923693D01*
X654900Y923239D01*
X655542D01*
X655996Y923693D01*
Y925374D01*
X656450Y925828D01*
X658357D01*
X660030Y924155D01*
X663496D01*
G01X643219Y932954D02*
X644265Y932521D01*
X651389D01*
X659799Y930848D01*
X663496D01*
G01X643219Y912442D02*
X658140D01*
X659813Y910769D01*
X663496D01*
G01X643405Y919795D02*
X644065Y919135D01*
X652986D01*
X654659Y917462D01*
X663496D01*
G01X643963Y935868D02*
X653525D01*
X654772Y937115D01*
X656247D01*
X657921Y938789D01*
X660220D01*
X661468Y937541D01*
X663496D01*
G01X643219Y962639D02*
X656323D01*
X657996Y960966D01*
G01X643219Y949253D02*
X658140D01*
X659813Y947580D01*
X663496D01*
G01X643015Y956365D02*
X643434Y955946D01*
X657758D01*
X659431Y954273D01*
X663496D01*
G01X643963Y939214D02*
X653523D01*
X654773Y937964D01*
X655895D01*
X657569Y939638D01*
X660219D01*
X661468Y940887D01*
X663496D01*
G01X643219Y976025D02*
X656186D01*
X657859Y974352D01*
X663496D01*
G01X643396Y980032D02*
X644056Y979372D01*
X655442D01*
X657115Y981045D01*
X663496D01*
G01X643382Y966666D02*
X644062Y965986D01*
X650774D01*
X652447Y967659D01*
X663496D01*
G01X643219Y989411D02*
X653074D01*
X654748Y987737D01*
X663496D01*
G01X642337Y993417D02*
X642997Y992757D01*
X650774D01*
X652447Y994430D01*
X663496D01*
G01X643219Y996104D02*
X651052D01*
X656071Y1001123D01*
X663496D01*
G01X643219Y1039608D02*
X658295D01*
X659968Y1041281D01*
X663496D01*
G01X643219Y1052994D02*
X654067D01*
X655740Y1054667D01*
X663496D01*
G01X643219Y1059542D02*
X643364Y1059687D01*
X653009D01*
X654682Y1061360D01*
X663496D01*
G01X643219Y1075951D02*
X643687Y1076419D01*
X652439D01*
X654112Y1078092D01*
X655673D01*
X656127Y1077638D01*
Y1075753D01*
X656581Y1075299D01*
X657223D01*
X657677Y1075753D01*
Y1077638D01*
X658131Y1078092D01*
X663496D01*
G01X643963Y1086458D02*
X653523D01*
X654773Y1085208D01*
X655941D01*
X657615Y1086882D01*
X660225D01*
X661474Y1088131D01*
X663496D01*
G01X643219Y1099844D02*
X651839D01*
X660250Y1101517D01*
X663496D01*
G01X643219Y1113230D02*
X652439D01*
X654112Y1114903D01*
X663496D01*
G01X643963Y1123269D02*
X653523D01*
X654773Y1122019D01*
X655813D01*
X657487Y1123693D01*
X660225D01*
X661474Y1124942D01*
X663496D01*
G01X643473Y1135995D02*
X644133Y1136655D01*
X650371D01*
X650774Y1136735D01*
X658782Y1138328D01*
X663496D01*
G01X643219Y1149576D02*
X643684Y1150041D01*
X650575D01*
X652248Y1151714D01*
X653355D01*
X653809Y1151260D01*
Y1149963D01*
X654263Y1149509D01*
X654905D01*
X655359Y1149963D01*
Y1151260D01*
X655813Y1151714D01*
X656455D01*
X656909Y1151260D01*
Y1149963D01*
X657363Y1149509D01*
X658005D01*
X658459Y1149963D01*
Y1151260D01*
X658913Y1151714D01*
X663496D01*
G01X643219Y1173466D02*
X658299D01*
X659972Y1175139D01*
X663496D01*
G01X643219Y1186852D02*
X650575D01*
X652248Y1188525D01*
X653731D01*
X654185Y1188979D01*
Y1190325D01*
X654639Y1190779D01*
X655281D01*
X655735Y1190325D01*
Y1188979D01*
X656189Y1188525D01*
X663496D01*
G01X643963Y1160080D02*
X653523D01*
X654773Y1158830D01*
X655943D01*
X657617Y1160504D01*
X660225D01*
X661474Y1161753D01*
X663496D01*
G01X643219Y1210277D02*
X651631D01*
X660042Y1211950D01*
X663496D01*
G01X643963Y1196891D02*
X653523D01*
X654773Y1195641D01*
X655873D01*
X657547Y1197315D01*
X660225D01*
X661474Y1198564D01*
X663496D01*
G01X642947Y1223663D02*
X652439D01*
X654112Y1225336D01*
X663496D01*
G01X643963Y1233702D02*
X653523D01*
X654773Y1232452D01*
X655975D01*
X657649Y1234126D01*
X660225D01*
X661474Y1235375D01*
X663496D01*
G01X643219Y1246940D02*
X643367Y1247088D01*
X651429D01*
X659840Y1248761D01*
X663496D01*
G01X643219Y1032915D02*
X658247D01*
X659920Y1034588D01*
X663496D01*
G01X643219Y1046301D02*
X658061D01*
X659734Y1047974D01*
X663496D01*
G01X643495Y1072433D02*
X644134Y1073072D01*
X654174D01*
X655847Y1071399D01*
X663496D01*
G01X643494Y1065740D02*
X644133Y1066379D01*
X654356D01*
X656029Y1064706D01*
X663496D01*
G01X643219Y1093151D02*
X653501D01*
X655174Y1094824D01*
X656455D01*
X656909Y1095278D01*
Y1097945D01*
X657363Y1098399D01*
X658005D01*
X658459Y1097945D01*
Y1095278D01*
X658913Y1094824D01*
X663496D01*
G01X643963Y1083112D02*
X653525D01*
X654772Y1084359D01*
X656293D01*
X657967Y1086033D01*
X660226D01*
X661474Y1084785D01*
X663496D01*
G01X643219Y1109783D02*
X643319Y1109883D01*
X654542D01*
X654996Y1109429D01*
Y1106833D01*
X655450Y1106379D01*
X656092D01*
X656546Y1106833D01*
Y1109429D01*
X657000Y1109883D01*
X658582D01*
X660255Y1108210D01*
X663496D01*
G01X643963Y1119923D02*
X653525D01*
X654772Y1121170D01*
X656165D01*
X657839Y1122844D01*
X660226D01*
X661474Y1121596D01*
X663496D01*
G01X643219Y1129962D02*
X653501D01*
X655174Y1131635D01*
X663496D01*
G01X643494Y1146055D02*
X644133Y1146694D01*
X657810D01*
X659483Y1145021D01*
X663496D01*
G01X643963Y1156734D02*
X653525D01*
X654772Y1157981D01*
X656295D01*
X657969Y1159655D01*
X660226D01*
X661474Y1158407D01*
X663496D01*
G01X643219Y1166773D02*
X653501D01*
X655174Y1168446D01*
X656195D01*
X656649Y1168900D01*
Y1171315D01*
X657103Y1171769D01*
X657745D01*
X658199Y1171315D01*
Y1168900D01*
X658653Y1168446D01*
X663496D01*
G01X643219Y1183505D02*
X651790D01*
X653463Y1181832D01*
X654342D01*
X654796Y1182286D01*
Y1184245D01*
X655250Y1184699D01*
X655892D01*
X656346Y1184245D01*
Y1182286D01*
X656800Y1181832D01*
X657442D01*
X657896Y1182286D01*
Y1184245D01*
X658350Y1184699D01*
X658992D01*
X659446Y1184245D01*
Y1182286D01*
X659900Y1181832D01*
X663496D01*
G01X643219Y1203584D02*
X653501D01*
X655174Y1205257D01*
X656658D01*
X657112Y1205711D01*
Y1207605D01*
X657566Y1208059D01*
X658208D01*
X658662Y1207605D01*
Y1205711D01*
X659116Y1205257D01*
X663496D01*
G01X643963Y1193545D02*
X653525D01*
X654772Y1194792D01*
X656225D01*
X657899Y1196466D01*
X660226D01*
X661474Y1195218D01*
X663496D01*
G01X643495Y1219677D02*
X644134Y1220316D01*
X651128D01*
X652801Y1218643D01*
X653762D01*
X654216Y1219097D01*
Y1220765D01*
X654670Y1221219D01*
X655312D01*
X655766Y1220765D01*
Y1219097D01*
X656220Y1218643D01*
X656862D01*
X657316Y1219097D01*
Y1220765D01*
X657770Y1221219D01*
X658412D01*
X658866Y1220765D01*
Y1219097D01*
X659320Y1218643D01*
X663496D01*
G01X643219Y1240395D02*
X653501D01*
X655174Y1242068D01*
X663496D01*
G01X643963Y1230356D02*
X653525D01*
X654772Y1231603D01*
X656327D01*
X658001Y1233277D01*
X660226D01*
X661474Y1232029D01*
X663496D01*
G01X1216388Y781930D02*
X1205002D01*
X1203328Y780256D01*
X1193969D01*
G01X1213720Y788623D02*
X1203720D01*
X1203101Y788004D01*
X1200554Y786949D01*
X1193969D01*
G01X1215002Y805355D02*
X1205002D01*
X1203328Y803681D01*
X1202404D01*
X1202005Y804080D01*
Y806669D01*
X1201606Y807068D01*
X1200854D01*
X1200455Y806669D01*
Y804080D01*
X1200056Y803681D01*
X1193969D01*
G01X1213502Y795315D02*
X1203502D01*
X1202255Y796562D01*
X1200708D01*
X1199035Y794889D01*
X1197311D01*
X1196064Y793642D01*
X1193969D01*
G01X1213502Y798661D02*
X1203502D01*
X1202252Y797411D01*
X1200356D01*
X1198683Y795738D01*
X1197314D01*
X1196064Y796988D01*
X1193969D01*
G01X1215002Y818741D02*
X1205002D01*
X1203328Y817067D01*
X1193969D01*
G01X1215002Y808701D02*
X1205002D01*
X1203329Y810374D01*
X1193969D01*
G01X1213720Y825434D02*
X1203720D01*
X1202046Y823760D01*
X1193969D01*
G01X1213502Y832126D02*
X1203502D01*
X1202255Y833373D01*
X1200768D01*
X1199095Y831700D01*
X1197311D01*
X1196064Y830453D01*
X1193969D01*
G01X1213502Y835472D02*
X1203502D01*
X1202252Y834222D01*
X1200416D01*
X1198743Y832549D01*
X1197314D01*
X1196064Y833799D01*
X1193969D01*
G01X1215002Y842166D02*
X1205002D01*
X1204986Y842182D01*
X1197659D01*
X1195969Y840492D01*
X1193969D01*
G01X1215002Y845512D02*
X1205002D01*
X1203329Y847185D01*
X1193969D01*
G01X1215002Y855552D02*
X1205002D01*
X1203328Y853878D01*
X1193969D01*
G01X1213720Y862245D02*
X1203720D01*
X1203101Y861626D01*
X1200554Y860571D01*
X1193969D01*
G01X1215002Y878977D02*
X1206374D01*
X1204700Y877303D01*
X1203561D01*
X1203162Y877702D01*
Y879269D01*
X1202763Y879668D01*
X1202011D01*
X1201612Y879269D01*
Y877702D01*
X1201213Y877303D01*
X1200461D01*
X1200062Y877702D01*
Y879269D01*
X1199663Y879668D01*
X1198911D01*
X1198512Y879269D01*
Y877702D01*
X1198113Y877303D01*
X1193969D01*
G01X1213502Y868937D02*
X1203502D01*
X1202255Y870184D01*
X1200660D01*
X1198987Y868511D01*
X1197311D01*
X1196064Y867264D01*
X1193969D01*
G01X1213502Y872283D02*
X1203502D01*
X1202252Y871033D01*
X1200308D01*
X1198635Y869360D01*
X1197314D01*
X1196064Y870610D01*
X1193969D01*
G01X1215002Y882323D02*
X1205002D01*
X1203329Y883996D01*
X1193969D01*
G01X1215002Y892363D02*
X1205002D01*
X1203328Y890689D01*
X1193969D01*
G01X1213720Y899056D02*
X1203720D01*
X1202046Y897382D01*
X1193969D01*
G01X1213502Y905749D02*
X1203972D01*
X1202720Y907001D01*
X1201527D01*
X1199849Y905323D01*
X1197313D01*
X1196065Y904075D01*
X1193969D01*
G01X1213502Y909095D02*
X1203934D01*
X1202689Y907850D01*
X1201175D01*
X1199497Y906172D01*
X1197338D01*
X1196088Y907422D01*
X1193969D01*
G01X1215002Y915788D02*
X1205002D01*
X1204995Y915795D01*
X1197501D01*
X1195820Y914114D01*
X1193969D01*
G01X1214202Y919794D02*
X1213542Y919134D01*
X1206782D01*
X1205109Y920807D01*
X1193969D01*
G01X1215002Y929174D02*
X1205002D01*
X1203328Y927500D01*
X1202075D01*
X1201676Y927899D01*
Y929509D01*
X1201277Y929908D01*
X1200525D01*
X1200126Y929509D01*
Y927899D01*
X1199727Y927500D01*
X1193969D01*
G01X1213720Y935867D02*
X1203720D01*
X1202046Y934193D01*
X1193969D01*
G01X1215002Y952599D02*
X1205002D01*
X1203328Y950925D01*
X1201679D01*
X1201219Y951385D01*
Y951898D01*
X1200759Y952358D01*
X1200108D01*
X1199648Y951898D01*
Y951385D01*
X1199188Y950925D01*
X1193969D01*
G01X1213502Y942560D02*
X1203972D01*
X1202720Y943812D01*
X1201599D01*
X1199921Y942134D01*
X1197313D01*
X1196065Y940886D01*
X1193969D01*
G01X1213502Y945906D02*
X1203934D01*
X1202689Y944661D01*
X1201247D01*
X1199569Y942983D01*
X1197338D01*
X1196088Y944233D01*
X1193969D01*
G01X1215002Y967305D02*
X1213681Y965984D01*
X1201008D01*
X1199335Y964311D01*
X1193969D01*
G01X1214660Y956635D02*
X1213970Y955945D01*
X1205002D01*
X1200963Y957618D01*
X1193969D01*
G01X1214384Y980135D02*
X1213619Y979370D01*
X1205002D01*
X1203329Y977697D01*
X1193969D01*
G01X1214351Y986723D02*
X1213691Y986063D01*
X1205002D01*
X1203329Y984390D01*
X1193969D01*
G01X1215297Y973908D02*
X1214066Y972677D01*
X1205002D01*
X1203329Y971004D01*
X1193969D01*
G01X1214466Y993416D02*
X1213806Y992756D01*
X1205002D01*
X1203329Y991083D01*
X1193969D01*
G01X1215002Y1029567D02*
X1205002D01*
X1203329Y1031240D01*
X1193969D01*
G01X1215002Y1036260D02*
X1205002D01*
X1203329Y1037933D01*
X1193969D01*
G01X1215002Y1042953D02*
X1205002D01*
X1203329Y1044626D01*
X1193969D01*
G01X1215002Y1059685D02*
X1215001Y1059686D01*
X1205002D01*
X1203328Y1058012D01*
X1193969D01*
G01X1215002Y1049645D02*
X1215001Y1049646D01*
X1199449D01*
X1199029Y1050066D01*
Y1050859D01*
X1198569Y1051319D01*
X1193969D01*
G01X1214906Y1073071D02*
X1199775D01*
X1198102Y1074744D01*
X1193969D01*
G01X1215220Y1079765D02*
X1215002D01*
X1215001Y1079764D01*
X1199892D01*
X1198219Y1081437D01*
X1193969D01*
G01X1213887Y1089804D02*
X1203972D01*
X1202720Y1091056D01*
X1201611D01*
X1199933Y1089378D01*
X1197313D01*
X1196065Y1088130D01*
X1193969D01*
G01X1215220Y1096496D02*
X1205201D01*
X1203527Y1098170D01*
X1193969D01*
G01X1213925Y1093150D02*
X1203934D01*
X1202689Y1091905D01*
X1201259D01*
X1199581Y1090227D01*
X1197338D01*
X1196088Y1091477D01*
X1193969D01*
G01X1215220Y1103189D02*
X1205177D01*
X1201138Y1104862D01*
X1193969D01*
G01X1215220Y1109882D02*
X1206854D01*
X1205181Y1111555D01*
X1203615D01*
X1203155Y1112015D01*
Y1113165D01*
X1202695Y1113625D01*
X1202044D01*
X1201584Y1113165D01*
Y1110818D01*
X1201124Y1110358D01*
X1200473D01*
X1200013Y1110818D01*
Y1114655D01*
X1199553Y1115115D01*
X1198902D01*
X1198442Y1114655D01*
Y1112015D01*
X1197982Y1111555D01*
X1193969D01*
G01X1215174Y1115866D02*
X1214465Y1116575D01*
X1203691D01*
X1202018Y1118248D01*
X1200753D01*
X1200354Y1117849D01*
Y1117367D01*
X1199955Y1116968D01*
X1199203D01*
X1198804Y1117367D01*
Y1117849D01*
X1198405Y1118248D01*
X1193969D01*
G01X1213441Y1126615D02*
X1203972D01*
X1202720Y1127867D01*
X1201683D01*
X1200005Y1126189D01*
X1197313D01*
X1196065Y1124941D01*
X1193969D01*
G01X1213517Y1129961D02*
X1203934D01*
X1202689Y1128716D01*
X1201331D01*
X1199653Y1127038D01*
X1197338D01*
X1196088Y1128288D01*
X1193969D01*
G01X1215732Y1147504D02*
X1214921Y1146693D01*
X1206004D01*
X1205605Y1147092D01*
Y1150099D01*
X1205206Y1150498D01*
X1204454D01*
X1204055Y1150099D01*
Y1147092D01*
X1203656Y1146693D01*
X1202904D01*
X1202505Y1147092D01*
Y1150099D01*
X1202106Y1150498D01*
X1201354D01*
X1200955Y1150099D01*
Y1147092D01*
X1200556Y1146693D01*
X1199783D01*
X1198110Y1148366D01*
X1193969D01*
G01X1215220Y1133307D02*
X1205359D01*
X1203286Y1135380D01*
Y1136189D01*
X1202887Y1136588D01*
X1202135D01*
X1201736Y1136189D01*
Y1135380D01*
X1201337Y1134981D01*
X1200585D01*
X1200186Y1135380D01*
Y1136189D01*
X1199787Y1136588D01*
X1199035D01*
X1198636Y1136189D01*
Y1135380D01*
X1198237Y1134981D01*
X1193969D01*
G01X1214864Y1139340D02*
X1214204Y1140000D01*
X1205101D01*
X1203427Y1141674D01*
X1193969D01*
G01X1214570Y1152517D02*
X1213701Y1153386D01*
X1203780D01*
X1202107Y1155059D01*
X1201175D01*
X1200776Y1154660D01*
Y1154057D01*
X1200377Y1153658D01*
X1199625D01*
X1199226Y1154057D01*
Y1154660D01*
X1198827Y1155059D01*
X1193969D01*
G01X1213441Y1163426D02*
X1203972D01*
X1202720Y1164678D01*
X1201595D01*
X1199917Y1163000D01*
X1197313D01*
X1196065Y1161752D01*
X1193969D01*
G01X1213517Y1166772D02*
X1203934D01*
X1202689Y1165527D01*
X1201243D01*
X1199565Y1163849D01*
X1197338D01*
X1196088Y1165099D01*
X1193969D01*
G01X1215220Y1169900D02*
X1215001Y1170119D01*
X1205273D01*
X1203600Y1171792D01*
X1202809D01*
X1202410Y1172191D01*
Y1173199D01*
X1202011Y1173598D01*
X1201259D01*
X1200860Y1173199D01*
Y1172191D01*
X1200461Y1171792D01*
X1193969D01*
G01X1215220Y1176211D02*
X1213769Y1176812D01*
X1205211D01*
X1201172Y1178485D01*
X1193969D01*
G01X1215220Y1183504D02*
X1205971D01*
X1204298Y1185177D01*
X1203287D01*
X1202888Y1184778D01*
Y1183047D01*
X1202489Y1182648D01*
X1201737D01*
X1201338Y1183047D01*
Y1187307D01*
X1200939Y1187706D01*
X1200187D01*
X1199788Y1187307D01*
Y1183047D01*
X1199389Y1182648D01*
X1198637D01*
X1198238Y1183047D01*
Y1184778D01*
X1197839Y1185177D01*
X1193969D01*
G01X1215220Y1190197D02*
X1203369D01*
X1201696Y1191870D01*
X1193969D01*
G01X1215220Y1206930D02*
X1215002D01*
X1215001Y1206929D01*
X1205273D01*
X1202764Y1209438D01*
X1200042D01*
X1199207Y1208603D01*
X1193969D01*
G01X1213441Y1200237D02*
X1203972D01*
X1202720Y1201489D01*
X1201505D01*
X1199827Y1199811D01*
X1197313D01*
X1196065Y1198563D01*
X1193969D01*
G01X1213517Y1203583D02*
X1203934D01*
X1202689Y1202338D01*
X1201153D01*
X1199475Y1200660D01*
X1197338D01*
X1196088Y1201910D01*
X1193969D01*
G01X1215220Y1213622D02*
X1205273D01*
X1203599Y1215296D01*
X1193969D01*
G01X1215220Y1220315D02*
X1203766D01*
X1203306Y1220775D01*
Y1221426D01*
X1203766Y1221886D01*
X1205241D01*
X1205701Y1222346D01*
Y1222997D01*
X1205241Y1223457D01*
X1202195D01*
X1201735Y1222997D01*
Y1220775D01*
X1201275Y1220315D01*
X1200221D01*
X1198548Y1221988D01*
X1193969D01*
G01X1215220Y1227008D02*
X1202158D01*
X1200485Y1228681D01*
X1193969D01*
G01X1213441Y1237048D02*
X1203972D01*
X1202720Y1238300D01*
X1201627D01*
X1199949Y1236622D01*
X1197313D01*
X1196065Y1235374D01*
X1193969D01*
G01X1213517Y1240394D02*
X1203934D01*
X1202689Y1239149D01*
X1201275D01*
X1199597Y1237471D01*
X1197338D01*
X1196088Y1238721D01*
X1193969D01*
G01X1215220Y1243740D02*
X1205273D01*
X1203599Y1245414D01*
X1193969D01*
G01X1215220Y1250433D02*
X1205273D01*
X1203599Y1252107D01*
X1193969D01*
G01X1214127Y963298D02*
Y963058D01*
X1213707Y962638D01*
X1205355D01*
X1205002Y962285D01*
G01X1216637Y972138D02*
X1213190Y968691D01*
G01X1215002Y978843D02*
X1214889Y978730D01*
G01X1619361Y785276D02*
X1626916D01*
X1635328Y783603D01*
X1639638D01*
G01X1619361Y808701D02*
X1629128D01*
X1630801Y807028D01*
X1639638D01*
G01X1619361Y822087D02*
X1628453D01*
X1630126Y820414D01*
X1639638D01*
G01X1619361Y845512D02*
X1629128D01*
X1630801Y843839D01*
X1639638D01*
G01X1619361Y858898D02*
X1629215D01*
X1633254Y857225D01*
X1639638D01*
G01X1619361Y882964D02*
X1620002Y882323D01*
X1629128D01*
X1630801Y880650D01*
X1639638D01*
G01X1619361Y896086D02*
X1620270Y895709D01*
X1628862D01*
X1632901Y894036D01*
X1639638D01*
G01X1619361Y932953D02*
X1620407Y932520D01*
X1627531D01*
X1635941Y930847D01*
X1639638D01*
G01X1619547Y919794D02*
X1620207Y919134D01*
X1629128D01*
X1630801Y917461D01*
X1639638D01*
G01X1619157Y956364D02*
X1619576Y955945D01*
X1633900D01*
X1635573Y954272D01*
X1639638D01*
G01X1619538Y980031D02*
X1620198Y979371D01*
X1631584D01*
X1633257Y981044D01*
X1639638D01*
G01X1618479Y993416D02*
X1619139Y992756D01*
X1626916D01*
X1628589Y994429D01*
X1639638D01*
G01X1619361Y778583D02*
X1633703D01*
X1635376Y776910D01*
X1639638D01*
G01X1620105Y791969D02*
X1629665D01*
X1630915Y790719D01*
X1631975D01*
X1633649Y792393D01*
X1636361D01*
X1637610Y793642D01*
X1639638D01*
G01X1620105Y788623D02*
X1629667D01*
X1630914Y789870D01*
X1632327D01*
X1634001Y791544D01*
X1636362D01*
X1637610Y790296D01*
X1639638D01*
G01X1619361Y802015D02*
X1619368Y802008D01*
X1629659D01*
X1630119Y802468D01*
Y803311D01*
X1630579Y803771D01*
X1631229D01*
X1631689Y803311D01*
Y800755D01*
X1632109Y800335D01*
X1632924D01*
X1633384Y800795D01*
Y803235D01*
X1633844Y803695D01*
X1634494D01*
X1634954Y803235D01*
Y800795D01*
X1635414Y800335D01*
X1639638D01*
G01X1619361Y815394D02*
X1633703D01*
X1635376Y813721D01*
X1639638D01*
G01X1619211Y838819D02*
X1630443D01*
X1630897Y839273D01*
Y841834D01*
X1631351Y842288D01*
X1631993D01*
X1632447Y841834D01*
Y839273D01*
X1632901Y838819D01*
X1634282D01*
X1635955Y837146D01*
X1639638D01*
G01X1619361Y852205D02*
X1633703D01*
X1635376Y850532D01*
X1639638D01*
G01X1620105Y828780D02*
X1629665D01*
X1630915Y827530D01*
X1632075D01*
X1633749Y829204D01*
X1636361D01*
X1637610Y830453D01*
X1639638D01*
G01X1620105Y825434D02*
X1629667D01*
X1630914Y826681D01*
X1632427D01*
X1634101Y828355D01*
X1636362D01*
X1637610Y827107D01*
X1639638D01*
G01X1619361Y875630D02*
X1630975D01*
X1631429Y876084D01*
Y877914D01*
X1631883Y878368D01*
X1632525D01*
X1632979Y877914D01*
Y876084D01*
X1633433Y875630D01*
X1634282D01*
X1635955Y873957D01*
X1639638D01*
G01X1620105Y865591D02*
X1629665D01*
X1630915Y864341D01*
X1632035D01*
X1633709Y866015D01*
X1636361D01*
X1637610Y867264D01*
X1639638D01*
G01X1620105Y862245D02*
X1629667D01*
X1630914Y863492D01*
X1632387D01*
X1634061Y865166D01*
X1636362D01*
X1637610Y863918D01*
X1639638D01*
G01X1619615Y889676D02*
X1620275Y889016D01*
X1629685D01*
X1630139Y888562D01*
Y887372D01*
X1630593Y886918D01*
X1631235D01*
X1631689Y887372D01*
Y888562D01*
X1632143Y889016D01*
X1633703D01*
X1635376Y887343D01*
X1639638D01*
G01X1620105Y902402D02*
X1629665D01*
X1630915Y901152D01*
X1631917D01*
X1633591Y902826D01*
X1636361D01*
X1637610Y904075D01*
X1639638D01*
G01X1620105Y899056D02*
X1629667D01*
X1630914Y900303D01*
X1632269D01*
X1633943Y901977D01*
X1636362D01*
X1637610Y900729D01*
X1639638D01*
G01X1617931Y928171D02*
X1620275Y925827D01*
X1630134D01*
X1630588Y925373D01*
Y923692D01*
X1631042Y923238D01*
X1631684D01*
X1632138Y923692D01*
Y925373D01*
X1632592Y925827D01*
X1634499D01*
X1636172Y924154D01*
X1639638D01*
G01X1619361Y912441D02*
X1634282D01*
X1635955Y910768D01*
X1639638D01*
G01X1620105Y935867D02*
X1629667D01*
X1630914Y937114D01*
X1632389D01*
X1634063Y938788D01*
X1636362D01*
X1637610Y937540D01*
X1639638D01*
G01X1619361Y962638D02*
X1632465D01*
X1634138Y960965D01*
G01X1619361Y949252D02*
X1634282D01*
X1635955Y947579D01*
X1639638D01*
G01X1620105Y939213D02*
X1629665D01*
X1630915Y937963D01*
X1632037D01*
X1633711Y939637D01*
X1636361D01*
X1637610Y940886D01*
X1639638D01*
G01X1619361Y976024D02*
X1632328D01*
X1634001Y974351D01*
X1639638D01*
G01X1619524Y966665D02*
X1620204Y965985D01*
X1626916D01*
X1628589Y967658D01*
X1639638D01*
G01X1619361Y989410D02*
X1629216D01*
X1630890Y987736D01*
X1639638D01*
G01X1619361Y996103D02*
X1627194D01*
X1632213Y1001122D01*
X1639638D01*
G01X1619361Y1032914D02*
X1634389D01*
X1636062Y1034587D01*
X1639638D01*
G01X1619361Y1039607D02*
X1634437D01*
X1636110Y1041280D01*
X1639638D01*
G01X1619361Y1046300D02*
X1634203D01*
X1635876Y1047973D01*
X1639638D01*
G01X1619361Y1052993D02*
X1630209D01*
X1631882Y1054666D01*
X1639638D01*
G01X1619361Y1059541D02*
X1619506Y1059686D01*
X1629151D01*
X1630824Y1061359D01*
X1639638D01*
G01X1619637Y1072432D02*
X1620276Y1073071D01*
X1630316D01*
X1631989Y1071398D01*
X1639638D01*
G01X1619636Y1065739D02*
X1620275Y1066378D01*
X1630498D01*
X1632171Y1064705D01*
X1639638D01*
G01X1619361Y1093150D02*
X1629643D01*
X1631316Y1094823D01*
X1632597D01*
X1633051Y1095277D01*
Y1097944D01*
X1633505Y1098398D01*
X1634147D01*
X1634601Y1097944D01*
Y1095277D01*
X1635055Y1094823D01*
X1639638D01*
G01X1619361Y1099843D02*
X1627981D01*
X1636392Y1101516D01*
X1639638D01*
G01X1619361Y1075950D02*
X1619829Y1076418D01*
X1628581D01*
X1630254Y1078091D01*
X1631815D01*
X1632269Y1077637D01*
Y1075752D01*
X1632723Y1075298D01*
X1633365D01*
X1633819Y1075752D01*
Y1077637D01*
X1634273Y1078091D01*
X1639638D01*
G01X1620105Y1086457D02*
X1629665D01*
X1630915Y1085207D01*
X1632083D01*
X1633757Y1086881D01*
X1636367D01*
X1637616Y1088130D01*
X1639638D01*
G01X1620105Y1083111D02*
X1629667D01*
X1630914Y1084358D01*
X1632435D01*
X1634109Y1086032D01*
X1636368D01*
X1637616Y1084784D01*
X1639638D01*
G01X1619361Y1109782D02*
X1619461Y1109882D01*
X1630684D01*
X1631138Y1109428D01*
Y1106832D01*
X1631592Y1106378D01*
X1632234D01*
X1632688Y1106832D01*
Y1109428D01*
X1633142Y1109882D01*
X1634724D01*
X1636397Y1108209D01*
X1639638D01*
G01X1619361Y1113229D02*
X1628581D01*
X1630254Y1114902D01*
X1639638D01*
G01X1620105Y1123268D02*
X1629665D01*
X1630915Y1122018D01*
X1631955D01*
X1633629Y1123692D01*
X1636367D01*
X1637616Y1124941D01*
X1639638D01*
G01X1620105Y1119922D02*
X1629667D01*
X1630914Y1121169D01*
X1632307D01*
X1633981Y1122843D01*
X1636368D01*
X1637616Y1121595D01*
X1639638D01*
G01X1619361Y1129961D02*
X1629643D01*
X1631316Y1131634D01*
X1639638D01*
G01X1619615Y1135994D02*
X1620275Y1136654D01*
X1626513D01*
X1626916Y1136734D01*
X1634924Y1138327D01*
X1639638D01*
G01X1619636Y1146054D02*
X1620275Y1146693D01*
X1633952D01*
X1635625Y1145020D01*
X1639638D01*
G01X1619361Y1149575D02*
X1619826Y1150040D01*
X1626717D01*
X1628390Y1151713D01*
X1629497D01*
X1629951Y1151259D01*
Y1149962D01*
X1630405Y1149508D01*
X1631047D01*
X1631501Y1149962D01*
Y1151259D01*
X1631955Y1151713D01*
X1632597D01*
X1633051Y1151259D01*
Y1149962D01*
X1633505Y1149508D01*
X1634147D01*
X1634601Y1149962D01*
Y1151259D01*
X1635055Y1151713D01*
X1639638D01*
G01X1620105Y1160079D02*
X1629665D01*
X1630915Y1158829D01*
X1632085D01*
X1633759Y1160503D01*
X1636367D01*
X1637616Y1161752D01*
X1639638D01*
G01X1620105Y1156733D02*
X1629667D01*
X1630914Y1157980D01*
X1632437D01*
X1634111Y1159654D01*
X1636368D01*
X1637616Y1158406D01*
X1639638D01*
G01X1619361Y1166772D02*
X1629643D01*
X1631316Y1168445D01*
X1632337D01*
X1632791Y1168899D01*
Y1171314D01*
X1633245Y1171768D01*
X1633887D01*
X1634341Y1171314D01*
Y1168899D01*
X1634795Y1168445D01*
X1639638D01*
G01X1619361Y1173465D02*
X1634441D01*
X1636114Y1175138D01*
X1639638D01*
G01X1619361Y1183504D02*
X1627932D01*
X1629605Y1181831D01*
X1630484D01*
X1630938Y1182285D01*
Y1184244D01*
X1631392Y1184698D01*
X1632034D01*
X1632488Y1184244D01*
Y1182285D01*
X1632942Y1181831D01*
X1633584D01*
X1634038Y1182285D01*
Y1184244D01*
X1634492Y1184698D01*
X1635134D01*
X1635588Y1184244D01*
Y1182285D01*
X1636042Y1181831D01*
X1639638D01*
G01X1619361Y1186851D02*
X1626717D01*
X1628390Y1188524D01*
X1629873D01*
X1630327Y1188978D01*
Y1190324D01*
X1630781Y1190778D01*
X1631423D01*
X1631877Y1190324D01*
Y1188978D01*
X1632331Y1188524D01*
X1639638D01*
G01X1619361Y1203583D02*
X1629643D01*
X1631316Y1205256D01*
X1632800D01*
X1633254Y1205710D01*
Y1207604D01*
X1633708Y1208058D01*
X1634350D01*
X1634804Y1207604D01*
Y1205710D01*
X1635258Y1205256D01*
X1639638D01*
G01X1619361Y1210276D02*
X1627773D01*
X1636184Y1211949D01*
X1639638D01*
G01X1620105Y1196890D02*
X1629665D01*
X1630915Y1195640D01*
X1632015D01*
X1633689Y1197314D01*
X1636367D01*
X1637616Y1198563D01*
X1639638D01*
G01X1620105Y1193544D02*
X1629667D01*
X1630914Y1194791D01*
X1632367D01*
X1634041Y1196465D01*
X1636368D01*
X1637616Y1195217D01*
X1639638D01*
G01X1619637Y1219676D02*
X1620276Y1220315D01*
X1627270D01*
X1628943Y1218642D01*
X1629904D01*
X1630358Y1219096D01*
Y1220764D01*
X1630812Y1221218D01*
X1631454D01*
X1631908Y1220764D01*
Y1219096D01*
X1632362Y1218642D01*
X1633004D01*
X1633458Y1219096D01*
Y1220764D01*
X1633912Y1221218D01*
X1634554D01*
X1635008Y1220764D01*
Y1219096D01*
X1635462Y1218642D01*
X1639638D01*
G01X1619089Y1223662D02*
X1628581D01*
X1630254Y1225335D01*
X1639638D01*
G01X1619361Y1240394D02*
X1629643D01*
X1631316Y1242067D01*
X1639638D01*
G01X1620105Y1233701D02*
X1629665D01*
X1630915Y1232451D01*
X1632117D01*
X1633791Y1234125D01*
X1636367D01*
X1637616Y1235374D01*
X1639638D01*
G01X1620105Y1230355D02*
X1629667D01*
X1630914Y1231602D01*
X1632469D01*
X1634143Y1233276D01*
X1636368D01*
X1637616Y1232028D01*
X1639638D01*
G01X1619361Y1246939D02*
X1619509Y1247087D01*
X1627571D01*
X1635982Y1248760D01*
X1639638D01*
G54D338*
G01X105890Y1385562D02*
X106843Y1384609D01*
Y1381137D01*
G01D02*
Y1379526D01*
X108310Y1378059D01*
Y1376461D01*
G01X140910D02*
Y1378059D01*
X139443Y1379526D01*
Y1381137D01*
G01D02*
Y1384609D01*
X138490Y1385562D01*
G01X171190D02*
X172143Y1384609D01*
Y1381249D01*
G01D02*
Y1379526D01*
X173610Y1378059D01*
Y1376461D01*
G01X186105Y1516970D02*
X188155D01*
G01X190829D02*
X192879D01*
G01X195554D02*
X197604D01*
G01X200278D02*
X202328D01*
G01X187680Y1519698D02*
X189730D01*
G01X192404D02*
X194454D01*
G01X197128D02*
X199178D01*
G01X186105Y1530608D02*
X188155D01*
G01X190829D02*
X192879D01*
G01X195554D02*
X197604D01*
G01X200278D02*
X202328D01*
G01X187680Y1533336D02*
X189730D01*
G01X192404D02*
X194454D01*
G01X197128D02*
X199178D01*
G01X206510Y1376461D02*
Y1378059D01*
X205043Y1379526D01*
Y1381144D01*
G01D02*
Y1384609D01*
X204090Y1385562D01*
G01X205002Y1516970D02*
X207052D01*
G01X209727D02*
X211777D01*
G01X214451D02*
X216501D01*
G01X201853Y1519698D02*
X203903D01*
G01X206577D02*
X208627D01*
G01X211302D02*
X213352D01*
G01X205002Y1530608D02*
X207052D01*
G01X209727D02*
X211777D01*
G01X214451D02*
X216501D01*
G01X201853Y1533336D02*
X203903D01*
G01X206577D02*
X208627D01*
G01X211302D02*
X213352D01*
G01X219176Y1516970D02*
X221226D01*
G01X223900D02*
X225950D01*
G01X228624D02*
X230674D01*
G01X216026Y1519698D02*
X218076D01*
G01X220750D02*
X222800D01*
G01X225475D02*
X227525D01*
G01X230199D02*
X232249D01*
G01X219176Y1530608D02*
X221226D01*
G01X223900D02*
X225950D01*
G01X228624D02*
X230674D01*
G01X216026Y1533336D02*
X218076D01*
G01X220750D02*
X222800D01*
G01X225475D02*
X227525D01*
G01X230199D02*
X232249D01*
G01X236890Y1385562D02*
X237843Y1384609D01*
Y1381004D01*
G01D02*
Y1379526D01*
X239310Y1378059D01*
Y1376461D01*
G01X233349Y1516970D02*
X235399D01*
G01X238073D02*
X240123D01*
G01X242798D02*
X244848D01*
G01X234924Y1519698D02*
X236974D01*
G01X239648D02*
X241698D01*
G01X244372D02*
X246422D01*
G01X233349Y1530608D02*
X235399D01*
G01X238073D02*
X240123D01*
G01X242798D02*
X244848D01*
G01X234924Y1533336D02*
X236974D01*
G01X239648D02*
X241698D01*
G01X244372D02*
X246422D01*
G01X247522Y1516970D02*
X249572D01*
G01X252247D02*
X254297D01*
G01X256971D02*
X259021D01*
G01X249097Y1519698D02*
X251147D01*
G01X253821D02*
X255871D01*
G01X258546D02*
X260596D01*
G01X247522Y1530608D02*
X249572D01*
G01X252247D02*
X254297D01*
G01X256971D02*
X259021D01*
G01X249097Y1533336D02*
X251147D01*
G01X253821D02*
X255871D01*
G01X258546D02*
X260596D01*
G01X272910Y1330315D02*
Y1331913D01*
X271443Y1333380D01*
Y1334995D01*
G01D02*
Y1338463D01*
X270490Y1339416D01*
G01X305806Y1330287D02*
Y1331885D01*
X304339Y1333352D01*
Y1334995D01*
G01D02*
Y1338435D01*
X303386Y1339388D01*
G01X314167Y1516970D02*
X316217D01*
G01X318891D02*
X320941D01*
G01X315742Y1519698D02*
X317792D01*
G01X314167Y1530608D02*
X316217D01*
G01X318891D02*
X320941D01*
G01X315742Y1533336D02*
X317792D01*
G01X330666Y698946D02*
X329713Y699899D01*
Y703362D01*
G01D02*
Y704982D01*
X328246Y706449D01*
Y708047D01*
G01X323616Y1516970D02*
X325666D01*
G01X328340D02*
X330390D01*
G01X333064D02*
X335114D01*
G01X320466Y1519698D02*
X322516D01*
G01X325190D02*
X327240D01*
G01X329915D02*
X331965D01*
G01X334639D02*
X336689D01*
G01X323616Y1530608D02*
X325666D01*
G01X328340D02*
X330390D01*
G01X333064D02*
X335114D01*
G01X320466Y1533336D02*
X322516D01*
G01X325190D02*
X327240D01*
G01X329915D02*
X331965D01*
G01X334639D02*
X336689D01*
G01X338710Y1330230D02*
Y1331828D01*
X337243Y1333295D01*
Y1334856D01*
G01D02*
Y1338378D01*
X336290Y1339331D01*
G01X337789Y1516970D02*
X339839D01*
G01X342513D02*
X344563D01*
G01X347238D02*
X349288D01*
G01X339364Y1519698D02*
X341414D01*
G01X344088D02*
X346138D01*
G01X348812D02*
X350862D01*
G01X337789Y1530608D02*
X339839D01*
G01X342513D02*
X344563D01*
G01X347238D02*
X349288D01*
G01X339364Y1533336D02*
X341414D01*
G01X344088D02*
X346138D01*
G01X348812D02*
X350862D01*
G01X363726Y698678D02*
X362773Y699631D01*
Y703129D01*
G01D02*
Y704714D01*
X361306Y706181D01*
Y707779D01*
G01X361411Y1516970D02*
X363461D01*
G01X351962D02*
X354012D01*
G01X356686D02*
X358736D01*
G01X362986Y1519698D02*
X365036D01*
G01X353537D02*
X355587D01*
G01X358261D02*
X360311D01*
G01X361411Y1530608D02*
X363461D01*
G01X351962D02*
X354012D01*
G01X356686D02*
X358736D01*
G01X362986Y1533336D02*
X365036D01*
G01X353537D02*
X355587D01*
G01X358261D02*
X360311D01*
G01X371510Y1330430D02*
Y1332028D01*
X370043Y1333495D01*
Y1335042D01*
G01D02*
Y1338578D01*
X369090Y1339531D01*
G01X366135Y1516970D02*
X368185D01*
G01X370860D02*
X372910D01*
G01X375584D02*
X377634D01*
G01X367710Y1519698D02*
X369760D01*
G01X372434D02*
X374484D01*
G01X377159D02*
X379209D01*
G01X366135Y1530608D02*
X368185D01*
G01X370860D02*
X372910D01*
G01X375584D02*
X377634D01*
G01X367710Y1533336D02*
X369760D01*
G01X372434D02*
X374484D01*
G01X377159D02*
X379209D01*
G01X395813Y703176D02*
Y704782D01*
X394346Y706249D01*
Y707847D01*
G01X380309Y1516970D02*
X382359D01*
G01X385033D02*
X387083D01*
G01X381883Y1519698D02*
X383933D01*
G01X386608D02*
X388658D01*
G01X380309Y1530608D02*
X382359D01*
G01X385033D02*
X387083D01*
G01X381883Y1533336D02*
X383933D01*
G01X386608D02*
X388658D01*
G01X396766Y698746D02*
X395813Y699699D01*
Y703176D01*
G01X404092Y1349761D02*
Y1351359D01*
X402625Y1352826D01*
Y1354338D01*
G01D02*
Y1357909D01*
X401672Y1358862D01*
G01X429766Y680946D02*
X428813Y681899D01*
Y685444D01*
G01D02*
Y686982D01*
X427346Y688449D01*
Y690047D01*
G01X450278Y1516970D02*
X452328D01*
G01X451853Y1519698D02*
X453903D01*
G01X450278Y1530608D02*
X452328D01*
G01X451853Y1533336D02*
X453903D01*
G01X462166Y656346D02*
X461213Y657299D01*
Y660759D01*
G01D02*
Y662382D01*
X459746Y663849D01*
Y665447D01*
G01X455002Y1516970D02*
X457052D01*
G01X459727D02*
X461777D01*
G01X464451D02*
X466501D01*
G01X469175D02*
X471225D01*
G01X456577Y1519698D02*
X458627D01*
G01X461301D02*
X463351D01*
G01X466026D02*
X468076D01*
G01X455002Y1530608D02*
X457052D01*
G01X459727D02*
X461777D01*
G01X464451D02*
X466501D01*
G01X469175D02*
X471225D01*
G01X456577Y1533336D02*
X458627D01*
G01X461301D02*
X463351D01*
G01X466026D02*
X468076D01*
G01X473900Y1516970D02*
X475950D01*
G01X478624D02*
X480674D01*
G01X483349D02*
X485399D01*
G01X470750Y1519698D02*
X472800D01*
G01X475475D02*
X477525D01*
G01X480199D02*
X482249D01*
G01X473900Y1530608D02*
X475950D01*
G01X478624D02*
X480674D01*
G01X483349D02*
X485399D01*
G01X470750Y1533336D02*
X472800D01*
G01X475475D02*
X477525D01*
G01X480199D02*
X482249D01*
G01X493813Y634326D02*
Y635882D01*
X492346Y637349D01*
Y638947D01*
G01X494766Y629846D02*
X493813Y630799D01*
Y634326D01*
G01X497522Y1516970D02*
X499572D01*
G01X488073D02*
X490123D01*
G01X492797D02*
X494847D01*
G01X484923Y1519698D02*
X486973D01*
G01X489648D02*
X491698D01*
G01X494372D02*
X496422D01*
G01X497522Y1530608D02*
X499572D01*
G01X488073D02*
X490123D01*
G01X492797D02*
X494847D01*
G01X484923Y1533336D02*
X486973D01*
G01X489648D02*
X491698D01*
G01X494372D02*
X496422D01*
G01X502246Y1516970D02*
X504296D01*
G01X506971D02*
X509021D01*
G01X511695D02*
X513745D01*
G01X499097Y1519698D02*
X501147D01*
G01X503821D02*
X505871D01*
G01X508545D02*
X510595D01*
G01X513270D02*
X515320D01*
G01X502246Y1530608D02*
X504296D01*
G01X506971D02*
X509021D01*
G01X511695D02*
X513745D01*
G01X499097Y1533336D02*
X501147D01*
G01X503821D02*
X505871D01*
G01X508545D02*
X510595D01*
G01X513270D02*
X515320D01*
G01X528066Y595746D02*
X527113Y596699D01*
Y600085D01*
G01D02*
Y601856D01*
X525646Y603323D01*
Y604847D01*
G01X516420Y1516970D02*
X518470D01*
G01X521144D02*
X523194D01*
G01X517994Y1519698D02*
X520044D01*
G01X522719D02*
X524769D01*
G01X516420Y1530608D02*
X518470D01*
G01X521144D02*
X523194D01*
G01X517994Y1533336D02*
X520044D01*
G01X522719D02*
X524769D01*
G01X578340Y1516970D02*
X580390D01*
G01X583064D02*
X585114D01*
G01X587789D02*
X589839D01*
G01X579915Y1519698D02*
X581965D01*
G01X584639D02*
X586689D01*
G01X578340Y1530608D02*
X580390D01*
G01X583064D02*
X585114D01*
G01X587789D02*
X589839D01*
G01X579915Y1533336D02*
X581965D01*
G01X584639D02*
X586689D01*
G01X592513Y1516970D02*
X594563D01*
G01X597237D02*
X599287D01*
G01X601962D02*
X604012D01*
G01X589363Y1519698D02*
X591413D01*
G01X594088D02*
X596138D01*
G01X598812D02*
X600862D01*
G01X592513Y1530608D02*
X594563D01*
G01X597237D02*
X599287D01*
G01X601962D02*
X604012D01*
G01X589363Y1533336D02*
X591413D01*
G01X594088D02*
X596138D01*
G01X598812D02*
X600862D01*
G01X606686Y1516970D02*
X608736D01*
G01X611411D02*
X613461D01*
G01X616135D02*
X618185D01*
G01X603537Y1519698D02*
X605587D01*
G01X608261D02*
X610311D01*
G01X612985D02*
X615035D01*
G01X617710D02*
X619760D01*
G01X606686Y1530608D02*
X608736D01*
G01X611411D02*
X613461D01*
G01X616135D02*
X618185D01*
G01X603537Y1533336D02*
X605587D01*
G01X608261D02*
X610311D01*
G01X612985D02*
X615035D01*
G01X617710D02*
X619760D01*
G01X625584Y1516970D02*
X627634D01*
G01X630308D02*
X632358D01*
G01X620859D02*
X622909D01*
G01X627159Y1519698D02*
X629209D01*
G01X631883D02*
X633933D01*
G01X622434D02*
X624484D01*
G01X625584Y1530608D02*
X627634D01*
G01X630308D02*
X632358D01*
G01X620859D02*
X622909D01*
G01X627159Y1533336D02*
X629209D01*
G01X631883D02*
X633933D01*
G01X622434D02*
X624484D01*
G01X635033Y1516970D02*
X637083D01*
G01X639757D02*
X641807D01*
G01X644482D02*
X646532D01*
G01X636607Y1519698D02*
X638657D01*
G01X641332D02*
X643382D01*
G01X646056D02*
X648106D01*
G01X635033Y1530608D02*
X637083D01*
G01X639757D02*
X641807D01*
G01X644482D02*
X646532D01*
G01X636607Y1533336D02*
X638657D01*
G01X641332D02*
X643382D01*
G01X646056D02*
X648106D01*
G01X649206Y1516970D02*
X651256D01*
G01X650781Y1519698D02*
X652831D01*
G01X649206Y1530608D02*
X651256D01*
G01X650781Y1533336D02*
X652831D01*
G01X713446Y1403571D02*
X714399Y1402618D01*
Y1399498D01*
G01D02*
Y1397535D01*
X715866Y1396068D01*
Y1394470D01*
G01X748648Y1394570D02*
Y1396168D01*
X747181Y1397635D01*
Y1399598D01*
G01D02*
Y1402718D01*
X746228Y1403671D01*
G01X1080048Y1376442D02*
Y1378040D01*
X1078581Y1379507D01*
Y1381102D01*
G01D02*
Y1384590D01*
X1077628Y1385543D01*
G01X1111181Y1381074D02*
Y1384590D01*
X1110228Y1385543D01*
G01X1112648Y1376442D02*
Y1378040D01*
X1111181Y1379507D01*
Y1381074D01*
G01X1142928Y1385543D02*
X1143881Y1384590D01*
Y1380963D01*
G01D02*
Y1379507D01*
X1145348Y1378040D01*
Y1376442D01*
G01X1178248D02*
Y1378040D01*
X1176781Y1379507D01*
Y1380963D01*
G01D02*
Y1384590D01*
X1175828Y1385543D01*
G01X1193978Y1549970D02*
X1196028D01*
G01X1198702D02*
X1200752D01*
G01X1195553Y1552698D02*
X1197603D01*
G01X1193978Y1563608D02*
X1196028D01*
G01X1198702D02*
X1200752D01*
G01X1195553Y1566336D02*
X1197603D01*
G01X1211048Y1376442D02*
Y1378040D01*
X1209581Y1379507D01*
Y1381149D01*
G01D02*
Y1384590D01*
X1208628Y1385543D01*
G01X1203427Y1549970D02*
X1205477D01*
G01X1208151D02*
X1210201D01*
G01X1212875D02*
X1214925D01*
G01X1200277Y1552698D02*
X1202327D01*
G01X1205001D02*
X1207051D01*
G01X1209726D02*
X1211776D01*
G01X1214450D02*
X1216500D01*
G01X1203427Y1563608D02*
X1205477D01*
G01X1208151D02*
X1210201D01*
G01X1212875D02*
X1214925D01*
G01X1200277Y1566336D02*
X1202327D01*
G01X1205001D02*
X1207051D01*
G01X1209726D02*
X1211776D01*
G01X1214450D02*
X1216500D01*
G01X1217600Y1549970D02*
X1219650D01*
G01X1222324D02*
X1224374D01*
G01X1227049D02*
X1229099D01*
G01X1219175Y1552698D02*
X1221225D01*
G01X1223899D02*
X1225949D01*
G01X1228623D02*
X1230673D01*
G01X1217600Y1563608D02*
X1219650D01*
G01X1222324D02*
X1224374D01*
G01X1227049D02*
X1229099D01*
G01X1219175Y1566336D02*
X1221225D01*
G01X1223899D02*
X1225949D01*
G01X1228623D02*
X1230673D01*
G01X1241222Y1549970D02*
X1243272D01*
G01X1231773D02*
X1233823D01*
G01X1236497D02*
X1238547D01*
G01X1242797Y1552698D02*
X1244847D01*
G01X1233348D02*
X1235398D01*
G01X1238072D02*
X1240122D01*
G01X1241222Y1563608D02*
X1243272D01*
G01X1231773D02*
X1233823D01*
G01X1236497D02*
X1238547D01*
G01X1242797Y1566336D02*
X1244847D01*
G01X1233348D02*
X1235398D01*
G01X1238072D02*
X1240122D01*
G01X1249039Y1330296D02*
Y1331894D01*
X1247572Y1333361D01*
Y1335094D01*
G01D02*
Y1338444D01*
X1246619Y1339397D01*
G01X1245946Y1549970D02*
X1247996D01*
G01X1250671D02*
X1252721D01*
G01X1255395D02*
X1257445D01*
G01X1247521Y1552698D02*
X1249571D01*
G01X1252245D02*
X1254295D01*
G01X1256970D02*
X1259020D01*
G01X1245946Y1563608D02*
X1247996D01*
G01X1250671D02*
X1252721D01*
G01X1255395D02*
X1257445D01*
G01X1247521Y1566336D02*
X1249571D01*
G01X1252245D02*
X1254295D01*
G01X1256970D02*
X1259020D01*
G01X1260120Y1549970D02*
X1262170D01*
G01X1264844D02*
X1266894D01*
G01X1261694Y1552698D02*
X1263744D01*
G01X1266419D02*
X1268469D01*
G01X1260120Y1563608D02*
X1262170D01*
G01X1264844D02*
X1266894D01*
G01X1261694Y1566336D02*
X1263744D01*
G01X1266419D02*
X1268469D01*
G01X1281935Y1330268D02*
Y1331866D01*
X1280468Y1333333D01*
Y1335001D01*
G01D02*
Y1338416D01*
X1279515Y1339369D01*
G01X1314839Y1330211D02*
Y1331809D01*
X1313372Y1333276D01*
Y1334907D01*
G01D02*
Y1338359D01*
X1312419Y1339312D01*
G01X1322040Y1549970D02*
X1324090D01*
G01X1326764D02*
X1328814D01*
G01X1331489D02*
X1333539D01*
G01X1323615Y1552698D02*
X1325665D01*
G01X1328339D02*
X1330389D01*
G01X1333063D02*
X1335113D01*
G01X1322040Y1563608D02*
X1324090D01*
G01X1326764D02*
X1328814D01*
G01X1331489D02*
X1333539D01*
G01X1323615Y1566336D02*
X1325665D01*
G01X1328339D02*
X1330389D01*
G01X1333063D02*
X1335113D01*
G01X1347639Y1330411D02*
Y1332009D01*
X1346172Y1333476D01*
Y1335141D01*
G01D02*
Y1338559D01*
X1345219Y1339512D01*
G01X1336213Y1549970D02*
X1338263D01*
G01X1340937D02*
X1342987D01*
G01X1345662D02*
X1347712D01*
G01X1337788Y1552698D02*
X1339838D01*
G01X1342512D02*
X1344562D01*
G01X1347237D02*
X1349287D01*
G01X1336213Y1563608D02*
X1338263D01*
G01X1340937D02*
X1342987D01*
G01X1345662D02*
X1347712D01*
G01X1337788Y1566336D02*
X1339838D01*
G01X1342512D02*
X1344562D01*
G01X1347237D02*
X1349287D01*
G01X1350386Y1549970D02*
X1352436D01*
G01X1355111D02*
X1357161D01*
G01X1359835D02*
X1361885D01*
G01X1351961Y1552698D02*
X1354011D01*
G01X1356685D02*
X1358735D01*
G01X1361410D02*
X1363460D01*
G01X1350386Y1563608D02*
X1352436D01*
G01X1355111D02*
X1357161D01*
G01X1359835D02*
X1361885D01*
G01X1351961Y1566336D02*
X1354011D01*
G01X1356685D02*
X1358735D01*
G01X1361410D02*
X1363460D01*
G01X1375718Y613889D02*
X1374765Y614842D01*
Y618274D01*
G01D02*
Y619925D01*
X1373298Y621392D01*
Y622990D01*
G01X1380221Y1349742D02*
Y1351340D01*
X1378754Y1352807D01*
Y1354318D01*
G01D02*
Y1357890D01*
X1377801Y1358843D01*
G01X1369284Y1549970D02*
X1371334D01*
G01X1374008D02*
X1376058D01*
G01X1364559D02*
X1366609D01*
G01X1370859Y1552698D02*
X1372909D01*
G01X1375583D02*
X1377633D01*
G01X1366134D02*
X1368184D01*
G01X1369284Y1563608D02*
X1371334D01*
G01X1374008D02*
X1376058D01*
G01X1364559D02*
X1366609D01*
G01X1370859Y1566336D02*
X1372909D01*
G01X1375583D02*
X1377633D01*
G01X1366134D02*
X1368184D01*
G01X1378733Y1549970D02*
X1380783D01*
G01X1383457D02*
X1385507D01*
G01X1388182D02*
X1390232D01*
G01X1392906D02*
X1394956D01*
G01X1380307Y1552698D02*
X1382357D01*
G01X1385032D02*
X1387082D01*
G01X1389756D02*
X1391806D01*
G01X1378733Y1563608D02*
X1380783D01*
G01X1383457D02*
X1385507D01*
G01X1388182D02*
X1390232D01*
G01X1392906D02*
X1394956D01*
G01X1380307Y1566336D02*
X1382357D01*
G01X1385032D02*
X1387082D01*
G01X1389756D02*
X1391806D01*
G01X1408418Y646789D02*
X1407465Y647742D01*
Y651240D01*
G01D02*
Y652825D01*
X1405998Y654292D01*
Y655890D01*
G01X1394481Y1552698D02*
X1396531D01*
G01X1394481Y1566336D02*
X1396531D01*
G01X1441018Y679369D02*
X1440065Y680322D01*
Y683835D01*
G01D02*
Y685405D01*
X1438598Y686872D01*
Y688470D01*
G01X1458152Y1549970D02*
X1460202D01*
G01X1462876D02*
X1464926D01*
G01X1467601D02*
X1469651D01*
G01X1459727Y1552698D02*
X1461777D01*
G01X1464451D02*
X1466501D01*
G01X1458152Y1563608D02*
X1460202D01*
G01X1462876D02*
X1464926D01*
G01X1467601D02*
X1469651D01*
G01X1459727Y1566336D02*
X1461777D01*
G01X1464451D02*
X1466501D01*
G01X1473936Y698946D02*
X1472983Y699899D01*
Y703385D01*
G01D02*
Y704982D01*
X1471516Y706449D01*
Y708047D01*
G01X1477049Y1549970D02*
X1479099D01*
G01X1481774D02*
X1483824D01*
G01X1472325D02*
X1474375D01*
G01X1478624Y1552698D02*
X1480674D01*
G01X1469175D02*
X1471225D01*
G01X1473900D02*
X1475950D01*
G01X1472325Y1563608D02*
X1474375D01*
G01X1477049D02*
X1479099D01*
G01X1481774D02*
X1483824D01*
G01X1469175Y1566336D02*
X1471225D01*
G01X1473900D02*
X1475950D01*
G01X1478624D02*
X1480674D01*
G01X1495947Y1549970D02*
X1497997D01*
G01X1486498D02*
X1488548D01*
G01X1491223D02*
X1493273D01*
G01X1497522Y1552698D02*
X1499572D01*
G01X1483349D02*
X1485399D01*
G01X1488073D02*
X1490123D01*
G01X1492797D02*
X1494847D01*
G01X1486498Y1563608D02*
X1488548D01*
G01X1491223D02*
X1493273D01*
G01X1495947D02*
X1497997D01*
G01X1483349Y1566336D02*
X1485399D01*
G01X1488073D02*
X1490123D01*
G01X1492797D02*
X1494847D01*
G01X1497522D02*
X1499572D01*
G01X1507018Y698946D02*
X1506065Y699899D01*
Y703404D01*
G01X1504598Y706449D02*
X1506065Y704982D01*
Y703404D01*
G01X1505396Y1549970D02*
X1507446D01*
G01X1510120D02*
X1512170D01*
G01X1500671D02*
X1502721D01*
G01X1506971Y1552698D02*
X1509021D01*
G01X1511695D02*
X1513745D01*
G01X1502246D02*
X1504296D01*
G01X1505396Y1563608D02*
X1507446D01*
G01X1510120D02*
X1512170D01*
G01X1500671D02*
X1502721D01*
G01X1506971Y1566336D02*
X1509021D01*
G01X1511695D02*
X1513745D01*
G01X1502246D02*
X1504296D01*
G01X1514845Y1549970D02*
X1516895D01*
G01X1519569D02*
X1521619D01*
G01X1524294D02*
X1526344D01*
G01X1516419Y1552698D02*
X1518469D01*
G01X1521144D02*
X1523194D01*
G01X1525868D02*
X1527918D01*
G01X1514845Y1563608D02*
X1516895D01*
G01X1519569D02*
X1521619D01*
G01X1524294D02*
X1526344D01*
G01X1516419Y1566336D02*
X1518469D01*
G01X1521144D02*
X1523194D01*
G01X1525868D02*
X1527918D01*
G01X1539818Y698946D02*
X1538865Y699899D01*
Y703451D01*
G01D02*
Y704982D01*
X1537398Y706449D01*
Y708047D01*
G01X1529018Y1549970D02*
X1531068D01*
G01X1530593Y1552698D02*
X1532643D01*
G01X1529018Y1563608D02*
X1531068D01*
G01X1530593Y1566336D02*
X1532643D01*
G01X1572948Y677006D02*
X1571995Y677959D01*
Y681501D01*
G01D02*
Y683042D01*
X1570528Y684509D01*
Y686107D01*
G01X1586214Y1549970D02*
X1588264D01*
G01X1586214Y1563608D02*
X1588264D01*
G01X1590938Y1549970D02*
X1592988D01*
G01X1595663D02*
X1597713D01*
G01X1600387D02*
X1602437D01*
G01X1587789Y1552698D02*
X1589839D01*
G01X1592513D02*
X1594563D01*
G01X1597237D02*
X1599287D01*
G01X1601962D02*
X1604012D01*
G01X1590938Y1563608D02*
X1592988D01*
G01X1595663D02*
X1597713D01*
G01X1600387D02*
X1602437D01*
G01X1587789Y1566336D02*
X1589839D01*
G01X1592513D02*
X1594563D01*
G01X1597237D02*
X1599287D01*
G01X1601962D02*
X1604012D01*
G01X1605718Y643237D02*
X1604765Y644190D01*
Y647601D01*
G01X1603298Y652338D02*
Y650740D01*
X1604765Y649273D01*
Y647601D01*
G01X1605111Y1549970D02*
X1607161D01*
G01X1609836D02*
X1611886D01*
G01X1614560D02*
X1616610D01*
G01X1606686Y1552698D02*
X1608736D01*
G01X1611411D02*
X1613461D01*
G01X1616135D02*
X1618185D01*
G01X1605111Y1563608D02*
X1607161D01*
G01X1609836D02*
X1611886D01*
G01X1614560D02*
X1616610D01*
G01X1606686Y1566336D02*
X1608736D01*
G01X1611411D02*
X1613461D01*
G01X1616135D02*
X1618185D01*
G01X1619285Y1549970D02*
X1621335D01*
G01X1624009D02*
X1626059D01*
G01X1628733D02*
X1630783D01*
G01X1620859Y1552698D02*
X1622909D01*
G01X1625584D02*
X1627634D01*
G01X1630308D02*
X1632358D01*
G01X1619285Y1563608D02*
X1621335D01*
G01X1624009D02*
X1626059D01*
G01X1628733D02*
X1630783D01*
G01X1620859Y1566336D02*
X1622909D01*
G01X1625584D02*
X1627634D01*
G01X1630308D02*
X1632358D01*
G01X1638718Y624237D02*
X1637765Y625190D01*
Y628715D01*
G01D02*
Y630273D01*
X1636298Y631740D01*
Y633338D01*
G01X1633458Y1549970D02*
X1635508D01*
G01X1638182D02*
X1640232D01*
G01X1642907D02*
X1644957D01*
G01X1635033Y1552698D02*
X1637083D01*
G01X1639757D02*
X1641807D01*
G01X1644481D02*
X1646531D01*
G01X1633458Y1563608D02*
X1635508D01*
G01X1638182D02*
X1640232D01*
G01X1642907D02*
X1644957D01*
G01X1635033Y1566336D02*
X1637083D01*
G01X1639757D02*
X1641807D01*
G01X1644481D02*
X1646531D01*
G01X1647631Y1549970D02*
X1649681D01*
G01X1652356D02*
X1654406D01*
G01X1657080D02*
X1659130D01*
G01X1649206Y1552698D02*
X1651256D01*
G01X1653930D02*
X1655980D01*
G01X1658655D02*
X1660705D01*
G01X1647631Y1563608D02*
X1649681D01*
G01X1652356D02*
X1654406D01*
G01X1657080D02*
X1659130D01*
G01X1649206Y1566336D02*
X1651256D01*
G01X1653930D02*
X1655980D01*
G01X1658655D02*
X1660705D01*
G54D284*
X999456Y193090D03*
G54D194*
X481550Y303156D03*
X568550Y312156D03*
G54D47*
X69323Y760178D03*
Y756832D03*
Y776911D03*
Y773564D03*
Y770218D03*
Y766871D03*
Y763525D03*
Y790297D03*
Y786950D03*
Y783604D03*
Y780257D03*
Y807029D03*
Y803682D03*
Y800336D03*
Y796989D03*
Y793643D03*
Y820415D03*
Y817068D03*
Y813722D03*
Y810375D03*
Y837147D03*
Y833800D03*
Y830454D03*
Y827108D03*
Y823761D03*
Y850533D03*
Y847186D03*
Y843840D03*
Y840493D03*
Y863919D03*
Y860572D03*
Y857226D03*
Y853879D03*
Y880651D03*
Y877304D03*
Y873958D03*
Y870611D03*
Y867265D03*
Y894037D03*
Y890690D03*
Y887344D03*
Y883997D03*
Y910769D03*
Y907423D03*
Y904076D03*
Y900730D03*
Y897383D03*
Y924155D03*
Y920808D03*
Y917462D03*
Y914115D03*
Y940887D03*
Y937541D03*
Y934194D03*
Y930848D03*
Y927501D03*
Y954273D03*
Y950926D03*
Y947580D03*
Y944234D03*
Y971005D03*
Y967659D03*
Y964312D03*
Y960966D03*
Y957619D03*
Y984391D03*
Y981045D03*
Y977698D03*
Y974352D03*
Y1001123D03*
Y997777D03*
Y994430D03*
Y991084D03*
Y987737D03*
Y1004470D03*
Y1027895D03*
Y1044627D03*
Y1041281D03*
Y1037934D03*
Y1034588D03*
Y1031241D03*
Y1058013D03*
Y1054667D03*
Y1051320D03*
Y1047974D03*
Y1074745D03*
Y1071399D03*
Y1068052D03*
Y1064706D03*
Y1061360D03*
Y1088131D03*
Y1084785D03*
Y1081438D03*
Y1078092D03*
Y1104863D03*
Y1101517D03*
Y1098171D03*
Y1094824D03*
Y1091478D03*
Y1118249D03*
Y1114903D03*
Y1111556D03*
Y1108210D03*
Y1134982D03*
Y1131635D03*
Y1128289D03*
Y1124942D03*
Y1121596D03*
Y1148367D03*
Y1145021D03*
Y1141675D03*
Y1138328D03*
Y1165100D03*
Y1161753D03*
Y1158407D03*
Y1155060D03*
Y1151714D03*
Y1178486D03*
Y1175139D03*
Y1171793D03*
Y1168446D03*
Y1191871D03*
Y1188525D03*
Y1185178D03*
Y1181832D03*
Y1208604D03*
Y1205257D03*
Y1201911D03*
Y1198564D03*
Y1195218D03*
Y1221989D03*
Y1218643D03*
Y1215297D03*
Y1211950D03*
Y1238722D03*
Y1235375D03*
Y1232029D03*
Y1228682D03*
Y1225336D03*
Y1252108D03*
Y1248761D03*
Y1245415D03*
Y1242068D03*
Y1255454D03*
X99024Y760178D03*
Y756832D03*
X85465Y760178D03*
Y756832D03*
X99024Y776911D03*
Y773564D03*
Y770218D03*
Y766871D03*
Y763525D03*
X85465Y776911D03*
Y773564D03*
Y770218D03*
Y766871D03*
Y763525D03*
X99024Y790297D03*
Y786950D03*
Y783604D03*
Y780257D03*
X85465Y790297D03*
Y786950D03*
Y783604D03*
Y780257D03*
X99024Y807029D03*
Y803682D03*
Y800336D03*
Y796989D03*
Y793643D03*
X85465Y807029D03*
Y803682D03*
Y800336D03*
Y796989D03*
Y793643D03*
X99024Y820415D03*
Y817068D03*
Y813722D03*
Y810375D03*
X85465Y820415D03*
Y817068D03*
Y813722D03*
Y810375D03*
X99024Y837147D03*
Y833800D03*
Y830454D03*
Y827108D03*
Y823761D03*
X85465Y837147D03*
Y833800D03*
Y830454D03*
Y827108D03*
Y823761D03*
X99024Y850533D03*
Y847186D03*
Y843840D03*
Y840493D03*
X85465Y850533D03*
Y847186D03*
Y843840D03*
Y840493D03*
X99024Y863919D03*
Y860572D03*
Y857226D03*
Y853879D03*
X85465Y863919D03*
Y860572D03*
Y857226D03*
Y853879D03*
X99024Y880651D03*
Y877304D03*
Y873958D03*
Y870611D03*
Y867265D03*
X85465Y880651D03*
Y877304D03*
Y873958D03*
Y870611D03*
Y867265D03*
X99024Y894037D03*
Y890690D03*
Y887344D03*
Y883997D03*
X85465Y894037D03*
Y890690D03*
Y887344D03*
Y883997D03*
X99024Y910769D03*
Y907423D03*
Y904076D03*
Y900730D03*
Y897383D03*
X85465Y910769D03*
Y907423D03*
Y904076D03*
Y900730D03*
Y897383D03*
X99024Y924155D03*
Y920808D03*
Y917462D03*
Y914115D03*
X85465Y924155D03*
Y920808D03*
Y917462D03*
Y914115D03*
X99024Y940887D03*
Y937541D03*
Y934194D03*
Y930848D03*
Y927501D03*
X85465Y940887D03*
Y937541D03*
Y934194D03*
Y930848D03*
Y927501D03*
X99024Y954273D03*
Y950926D03*
Y947580D03*
Y944234D03*
X85465Y954273D03*
Y950926D03*
Y947580D03*
Y944234D03*
X99024Y971005D03*
Y967659D03*
Y964312D03*
Y960966D03*
Y957619D03*
X85465Y971005D03*
Y967659D03*
Y964312D03*
Y960966D03*
Y957619D03*
X99024Y984391D03*
Y981045D03*
Y977698D03*
Y974352D03*
X85465Y984391D03*
Y981045D03*
Y977698D03*
Y974352D03*
X99024Y1001123D03*
Y997777D03*
Y994430D03*
Y991084D03*
Y987737D03*
X85465Y1001123D03*
Y997777D03*
Y994430D03*
Y991084D03*
Y987737D03*
X99024Y1004470D03*
X85465D03*
X99024Y1027895D03*
X85465D03*
X99024Y1044627D03*
Y1041281D03*
Y1037934D03*
Y1034588D03*
Y1031241D03*
X85465Y1044627D03*
Y1041281D03*
Y1037934D03*
Y1034588D03*
Y1031241D03*
X99024Y1058013D03*
Y1054667D03*
Y1051320D03*
Y1047974D03*
X85465Y1058013D03*
Y1054667D03*
Y1051320D03*
Y1047974D03*
X99024Y1074745D03*
Y1071399D03*
Y1068052D03*
Y1064706D03*
Y1061360D03*
X85465Y1074745D03*
Y1071399D03*
Y1068052D03*
Y1064706D03*
Y1061360D03*
X99024Y1088131D03*
Y1084785D03*
Y1081438D03*
Y1078092D03*
X85465Y1088131D03*
Y1084785D03*
Y1081438D03*
Y1078092D03*
X99024Y1104863D03*
Y1101517D03*
Y1098171D03*
Y1094824D03*
Y1091478D03*
X85465Y1104863D03*
Y1101517D03*
Y1098171D03*
Y1094824D03*
Y1091478D03*
X99024Y1118249D03*
Y1114903D03*
Y1111556D03*
Y1108210D03*
X85465Y1118249D03*
Y1114903D03*
Y1111556D03*
Y1108210D03*
X99024Y1134982D03*
Y1131635D03*
Y1128289D03*
Y1124942D03*
Y1121596D03*
X85465Y1134982D03*
Y1131635D03*
Y1128289D03*
Y1124942D03*
Y1121596D03*
X99024Y1148367D03*
Y1145021D03*
Y1141675D03*
Y1138328D03*
X85465Y1148367D03*
Y1145021D03*
Y1141675D03*
Y1138328D03*
X99024Y1165100D03*
Y1161753D03*
Y1158407D03*
Y1155060D03*
Y1151714D03*
X85465Y1165100D03*
Y1161753D03*
Y1158407D03*
Y1155060D03*
Y1151714D03*
X99024Y1178486D03*
Y1175139D03*
Y1171793D03*
Y1168446D03*
X85465Y1178486D03*
Y1175139D03*
Y1171793D03*
Y1168446D03*
X99024Y1191871D03*
Y1188525D03*
Y1185178D03*
Y1181832D03*
X85465Y1191871D03*
Y1188525D03*
Y1185178D03*
Y1181832D03*
X99024Y1208604D03*
Y1205257D03*
Y1201911D03*
Y1198564D03*
Y1195218D03*
X85465Y1208604D03*
Y1205257D03*
Y1201911D03*
Y1198564D03*
Y1195218D03*
X99024Y1221989D03*
Y1218643D03*
Y1215297D03*
Y1211950D03*
X85465Y1221989D03*
Y1218643D03*
Y1215297D03*
Y1211950D03*
X99024Y1238722D03*
Y1235375D03*
Y1232029D03*
Y1228682D03*
Y1225336D03*
X85465Y1238722D03*
Y1235375D03*
Y1232029D03*
Y1228682D03*
Y1225336D03*
X99024Y1252108D03*
Y1248761D03*
Y1245415D03*
Y1242068D03*
X85465Y1252108D03*
Y1248761D03*
Y1245415D03*
Y1242068D03*
X99024Y1255454D03*
X85465D03*
X128724Y760178D03*
Y756832D03*
X115166Y760178D03*
Y756832D03*
X128724Y776911D03*
Y773564D03*
Y770218D03*
Y766871D03*
Y763525D03*
X115166Y776911D03*
Y773564D03*
Y770218D03*
Y766871D03*
Y763525D03*
X128724Y790297D03*
Y786950D03*
Y783604D03*
Y780257D03*
X115166Y790297D03*
Y786950D03*
Y783604D03*
Y780257D03*
X128724Y807029D03*
Y803682D03*
Y800336D03*
Y796989D03*
Y793643D03*
X115166Y807029D03*
Y803682D03*
Y800336D03*
Y796989D03*
Y793643D03*
X128724Y820415D03*
Y817068D03*
Y813722D03*
Y810375D03*
X115166Y820415D03*
Y817068D03*
Y813722D03*
Y810375D03*
X128724Y837147D03*
Y833800D03*
Y830454D03*
Y827108D03*
Y823761D03*
X115166Y837147D03*
Y833800D03*
Y830454D03*
Y827108D03*
Y823761D03*
X128724Y850533D03*
Y847186D03*
Y843840D03*
Y840493D03*
X115166Y850533D03*
Y847186D03*
Y843840D03*
Y840493D03*
X128724Y863919D03*
Y860572D03*
Y857226D03*
Y853879D03*
X115166Y863919D03*
Y860572D03*
Y857226D03*
Y853879D03*
X128724Y880651D03*
Y877304D03*
Y873958D03*
Y870611D03*
Y867265D03*
X115166Y880651D03*
Y877304D03*
Y873958D03*
Y870611D03*
Y867265D03*
X128724Y894037D03*
Y890690D03*
Y887344D03*
Y883997D03*
X115166Y894037D03*
Y890690D03*
Y887344D03*
Y883997D03*
X128724Y910769D03*
Y907423D03*
Y904076D03*
Y900730D03*
Y897383D03*
X115166Y910769D03*
Y907423D03*
Y904076D03*
Y900730D03*
Y897383D03*
X128724Y924155D03*
Y920808D03*
Y917462D03*
Y914115D03*
X115166Y924155D03*
Y920808D03*
Y917462D03*
Y914115D03*
X128724Y940887D03*
Y937541D03*
Y934194D03*
Y930848D03*
Y927501D03*
X115166Y940887D03*
Y937541D03*
Y934194D03*
Y930848D03*
Y927501D03*
X128724Y954273D03*
Y950926D03*
Y947580D03*
Y944234D03*
X115166Y954273D03*
Y950926D03*
Y947580D03*
Y944234D03*
X128724Y971005D03*
Y967659D03*
Y964312D03*
Y960966D03*
Y957619D03*
X115166Y971005D03*
Y967659D03*
Y964312D03*
Y960966D03*
Y957619D03*
X128724Y984391D03*
Y981045D03*
Y977698D03*
Y974352D03*
X115166Y984391D03*
Y981045D03*
Y977698D03*
Y974352D03*
X128724Y1001123D03*
Y997777D03*
Y994430D03*
Y991084D03*
Y987737D03*
X115166Y1001123D03*
Y997777D03*
Y994430D03*
Y991084D03*
Y987737D03*
X128724Y1004470D03*
X115166D03*
X128724Y1027895D03*
X115166D03*
X128724Y1044627D03*
Y1041281D03*
Y1037934D03*
Y1034588D03*
Y1031241D03*
X115166Y1044627D03*
Y1041281D03*
Y1037934D03*
Y1034588D03*
Y1031241D03*
X128724Y1058013D03*
Y1054667D03*
Y1051320D03*
Y1047974D03*
X115166Y1058013D03*
Y1054667D03*
Y1051320D03*
Y1047974D03*
X128724Y1074745D03*
Y1071399D03*
Y1068052D03*
Y1064706D03*
Y1061360D03*
X115166Y1074745D03*
Y1071399D03*
Y1068052D03*
Y1064706D03*
Y1061360D03*
X128724Y1088131D03*
Y1084785D03*
Y1081438D03*
Y1078092D03*
X115166Y1088131D03*
Y1084785D03*
Y1081438D03*
Y1078092D03*
X128724Y1104863D03*
Y1101517D03*
Y1098171D03*
Y1094824D03*
Y1091478D03*
X115166Y1104863D03*
Y1101517D03*
Y1098171D03*
Y1094824D03*
Y1091478D03*
X128724Y1118249D03*
Y1114903D03*
Y1111556D03*
Y1108210D03*
X115166Y1118249D03*
Y1114903D03*
Y1111556D03*
Y1108210D03*
X128724Y1134982D03*
Y1131635D03*
Y1128289D03*
Y1124942D03*
Y1121596D03*
X115166Y1134982D03*
Y1131635D03*
Y1128289D03*
Y1124942D03*
Y1121596D03*
X128724Y1148367D03*
Y1145021D03*
Y1141675D03*
Y1138328D03*
X115166Y1148367D03*
Y1145021D03*
Y1141675D03*
Y1138328D03*
X128724Y1165100D03*
Y1161753D03*
Y1158407D03*
Y1155060D03*
Y1151714D03*
X115166Y1165100D03*
Y1161753D03*
Y1158407D03*
Y1155060D03*
Y1151714D03*
X128724Y1178486D03*
Y1175139D03*
Y1171793D03*
Y1168446D03*
X115166Y1178486D03*
Y1175139D03*
Y1171793D03*
Y1168446D03*
X128724Y1191871D03*
Y1188525D03*
Y1185178D03*
Y1181832D03*
X115166Y1191871D03*
Y1188525D03*
Y1185178D03*
Y1181832D03*
X128724Y1208604D03*
Y1205257D03*
Y1201911D03*
Y1198564D03*
Y1195218D03*
X115166Y1208604D03*
Y1205257D03*
Y1201911D03*
Y1198564D03*
Y1195218D03*
X128724Y1221989D03*
Y1218643D03*
Y1215297D03*
Y1211950D03*
X115166Y1221989D03*
Y1218643D03*
Y1215297D03*
Y1211950D03*
X128724Y1238722D03*
Y1235375D03*
Y1232029D03*
Y1228682D03*
Y1225336D03*
X115166Y1238722D03*
Y1235375D03*
Y1232029D03*
Y1228682D03*
Y1225336D03*
X128724Y1252108D03*
Y1248761D03*
Y1245415D03*
Y1242068D03*
X115166Y1252108D03*
Y1248761D03*
Y1245415D03*
Y1242068D03*
X128724Y1255454D03*
X115166D03*
X158425Y760178D03*
Y756832D03*
X144866Y760178D03*
Y756832D03*
X158425Y776911D03*
Y773564D03*
Y770218D03*
Y766871D03*
Y763525D03*
X144866Y776911D03*
Y773564D03*
Y770218D03*
Y766871D03*
Y763525D03*
X158425Y790297D03*
Y786950D03*
Y783604D03*
Y780257D03*
X144866Y790297D03*
Y786950D03*
Y783604D03*
Y780257D03*
X158425Y807029D03*
Y803682D03*
Y800336D03*
Y796989D03*
Y793643D03*
X144866Y807029D03*
Y803682D03*
Y800336D03*
Y796989D03*
Y793643D03*
X158425Y820415D03*
Y817068D03*
Y813722D03*
Y810375D03*
X144866Y820415D03*
Y817068D03*
Y813722D03*
Y810375D03*
X158425Y837147D03*
Y833800D03*
Y830454D03*
Y827108D03*
Y823761D03*
X144866Y837147D03*
Y833800D03*
Y830454D03*
Y827108D03*
Y823761D03*
X158425Y850533D03*
Y847186D03*
Y843840D03*
Y840493D03*
X144866Y850533D03*
Y847186D03*
Y843840D03*
Y840493D03*
X158425Y863919D03*
Y860572D03*
Y857226D03*
Y853879D03*
X144866Y863919D03*
Y860572D03*
Y857226D03*
Y853879D03*
X158425Y880651D03*
Y877304D03*
Y873958D03*
Y870611D03*
Y867265D03*
X144866Y880651D03*
Y877304D03*
Y873958D03*
Y870611D03*
Y867265D03*
X158425Y894037D03*
Y890690D03*
Y887344D03*
Y883997D03*
X144866Y894037D03*
Y890690D03*
Y887344D03*
Y883997D03*
X158425Y910769D03*
Y907423D03*
Y904076D03*
Y900730D03*
Y897383D03*
X144866Y910769D03*
Y907423D03*
Y904076D03*
Y900730D03*
Y897383D03*
X158425Y924155D03*
Y920808D03*
Y917462D03*
Y914115D03*
X144866Y924155D03*
Y920808D03*
Y917462D03*
Y914115D03*
X158425Y940887D03*
Y937541D03*
Y934194D03*
Y930848D03*
Y927501D03*
X144866Y940887D03*
Y937541D03*
Y934194D03*
Y930848D03*
Y927501D03*
X158425Y954273D03*
Y950926D03*
Y947580D03*
Y944234D03*
X144866Y954273D03*
Y950926D03*
Y947580D03*
Y944234D03*
X158425Y971005D03*
Y967659D03*
Y964312D03*
Y960966D03*
Y957619D03*
X144866Y971005D03*
Y967659D03*
Y964312D03*
Y960966D03*
Y957619D03*
X158425Y984391D03*
Y981045D03*
Y977698D03*
Y974352D03*
X144866Y984391D03*
Y981045D03*
Y977698D03*
Y974352D03*
X158425Y1001123D03*
Y997777D03*
Y994430D03*
Y991084D03*
Y987737D03*
X144866Y1001123D03*
Y997777D03*
Y994430D03*
Y991084D03*
Y987737D03*
X158425Y1004470D03*
X144866D03*
X158425Y1027895D03*
X144866D03*
X158425Y1044627D03*
Y1041281D03*
Y1037934D03*
Y1034588D03*
Y1031241D03*
X144866Y1044627D03*
Y1041281D03*
Y1037934D03*
Y1034588D03*
Y1031241D03*
X158425Y1058013D03*
Y1054667D03*
Y1051320D03*
Y1047974D03*
X144866Y1058013D03*
Y1054667D03*
Y1051320D03*
Y1047974D03*
X158425Y1074745D03*
Y1071399D03*
Y1068052D03*
Y1064706D03*
Y1061360D03*
X144866Y1074745D03*
Y1071399D03*
Y1068052D03*
Y1064706D03*
Y1061360D03*
X158425Y1088131D03*
Y1084785D03*
Y1081438D03*
Y1078092D03*
X144866Y1088131D03*
Y1084785D03*
Y1081438D03*
Y1078092D03*
X158425Y1104863D03*
Y1101517D03*
Y1098171D03*
Y1094824D03*
Y1091478D03*
X144866Y1104863D03*
Y1101517D03*
Y1098171D03*
Y1094824D03*
Y1091478D03*
X158425Y1118249D03*
Y1114903D03*
Y1111556D03*
Y1108210D03*
X144866Y1118249D03*
Y1114903D03*
Y1111556D03*
Y1108210D03*
X158425Y1134982D03*
Y1131635D03*
Y1128289D03*
Y1124942D03*
Y1121596D03*
X144866Y1134982D03*
Y1131635D03*
Y1128289D03*
Y1124942D03*
Y1121596D03*
X158425Y1148367D03*
Y1145021D03*
Y1141675D03*
Y1138328D03*
X144866Y1148367D03*
Y1145021D03*
Y1141675D03*
Y1138328D03*
X158425Y1165100D03*
Y1161753D03*
Y1158407D03*
Y1155060D03*
Y1151714D03*
X144866Y1165100D03*
Y1161753D03*
Y1158407D03*
Y1155060D03*
Y1151714D03*
X158425Y1178486D03*
Y1175139D03*
Y1171793D03*
Y1168446D03*
X144866Y1178486D03*
Y1175139D03*
Y1171793D03*
Y1168446D03*
X158425Y1191871D03*
Y1188525D03*
Y1185178D03*
Y1181832D03*
X144866Y1191871D03*
Y1188525D03*
Y1185178D03*
Y1181832D03*
X158425Y1208604D03*
Y1205257D03*
Y1201911D03*
Y1198564D03*
Y1195218D03*
X144866Y1208604D03*
Y1205257D03*
Y1201911D03*
Y1198564D03*
Y1195218D03*
X158425Y1221989D03*
Y1218643D03*
Y1215297D03*
Y1211950D03*
X144866Y1221989D03*
Y1218643D03*
Y1215297D03*
Y1211950D03*
X158425Y1238722D03*
Y1235375D03*
Y1232029D03*
Y1228682D03*
Y1225336D03*
X144866Y1238722D03*
Y1235375D03*
Y1232029D03*
Y1228682D03*
Y1225336D03*
X158425Y1252108D03*
Y1248761D03*
Y1245415D03*
Y1242068D03*
X144866Y1252108D03*
Y1248761D03*
Y1245415D03*
Y1242068D03*
X158425Y1255454D03*
X144866D03*
X188126Y760178D03*
Y756832D03*
X174567Y760178D03*
Y756832D03*
X188126Y776911D03*
Y773564D03*
Y770218D03*
Y766871D03*
Y763525D03*
X174567Y776911D03*
Y773564D03*
Y770218D03*
Y766871D03*
Y763525D03*
X188126Y790297D03*
Y786950D03*
Y783604D03*
Y780257D03*
X174567Y790297D03*
Y786950D03*
Y783604D03*
Y780257D03*
X188126Y807029D03*
Y803682D03*
Y800336D03*
Y796989D03*
Y793643D03*
X174567Y807029D03*
Y803682D03*
Y800336D03*
Y796989D03*
Y793643D03*
X188126Y820415D03*
Y817068D03*
Y813722D03*
Y810375D03*
X174567Y820415D03*
Y817068D03*
Y813722D03*
Y810375D03*
X188126Y837147D03*
Y833800D03*
Y830454D03*
Y827108D03*
Y823761D03*
X174567Y837147D03*
Y833800D03*
Y830454D03*
Y827108D03*
Y823761D03*
X188126Y850533D03*
Y847186D03*
Y843840D03*
Y840493D03*
X174567Y850533D03*
Y847186D03*
Y843840D03*
Y840493D03*
X188126Y863919D03*
Y860572D03*
Y857226D03*
Y853879D03*
X174567Y863919D03*
Y860572D03*
Y857226D03*
Y853879D03*
X188126Y880651D03*
Y877304D03*
Y873958D03*
Y870611D03*
Y867265D03*
X174567Y880651D03*
Y877304D03*
Y873958D03*
Y870611D03*
Y867265D03*
X188126Y894037D03*
Y890690D03*
Y887344D03*
Y883997D03*
X174567Y894037D03*
Y890690D03*
Y887344D03*
Y883997D03*
X188126Y910769D03*
Y907423D03*
Y904076D03*
Y900730D03*
Y897383D03*
X174567Y910769D03*
Y907423D03*
Y904076D03*
Y900730D03*
Y897383D03*
X188126Y924155D03*
Y920808D03*
Y917462D03*
Y914115D03*
X174567Y924155D03*
Y920808D03*
Y917462D03*
Y914115D03*
X188126Y940887D03*
Y937541D03*
Y934194D03*
Y930848D03*
Y927501D03*
X174567Y940887D03*
Y937541D03*
Y934194D03*
Y930848D03*
Y927501D03*
X188126Y954273D03*
Y950926D03*
Y947580D03*
Y944234D03*
X174567Y954273D03*
Y950926D03*
Y947580D03*
Y944234D03*
X188126Y971005D03*
Y967659D03*
Y964312D03*
Y960966D03*
Y957619D03*
X174567Y971005D03*
Y967659D03*
Y964312D03*
Y960966D03*
Y957619D03*
X188126Y984391D03*
Y981045D03*
Y977698D03*
Y974352D03*
X174567Y984391D03*
Y981045D03*
Y977698D03*
Y974352D03*
X188126Y1001123D03*
Y997777D03*
Y994430D03*
Y991084D03*
Y987737D03*
X174567Y1001123D03*
Y997777D03*
Y994430D03*
Y991084D03*
Y987737D03*
X188126Y1004470D03*
X174567D03*
X188126Y1027895D03*
X174567D03*
X188126Y1044627D03*
Y1041281D03*
Y1037934D03*
Y1034588D03*
Y1031241D03*
X174567Y1044627D03*
Y1041281D03*
Y1037934D03*
Y1034588D03*
Y1031241D03*
X188126Y1058013D03*
Y1054667D03*
Y1051320D03*
Y1047974D03*
X174567Y1058013D03*
Y1054667D03*
Y1051320D03*
Y1047974D03*
X188126Y1074745D03*
Y1071399D03*
Y1068052D03*
Y1064706D03*
Y1061360D03*
X174567Y1074745D03*
Y1071399D03*
Y1068052D03*
Y1064706D03*
Y1061360D03*
X188126Y1088131D03*
Y1084785D03*
Y1081438D03*
Y1078092D03*
X174567Y1088131D03*
Y1084785D03*
Y1081438D03*
Y1078092D03*
X188126Y1104863D03*
Y1101517D03*
Y1098171D03*
Y1094824D03*
Y1091478D03*
X174567Y1104863D03*
Y1101517D03*
Y1098171D03*
Y1094824D03*
Y1091478D03*
X188126Y1118249D03*
Y1114903D03*
Y1111556D03*
Y1108210D03*
X174567Y1118249D03*
Y1114903D03*
Y1111556D03*
Y1108210D03*
X188126Y1134982D03*
Y1131635D03*
Y1128289D03*
Y1124942D03*
Y1121596D03*
X174567Y1134982D03*
Y1131635D03*
Y1128289D03*
Y1124942D03*
Y1121596D03*
X188126Y1148367D03*
Y1145021D03*
Y1141675D03*
Y1138328D03*
X174567Y1148367D03*
Y1145021D03*
Y1141675D03*
Y1138328D03*
X188126Y1165100D03*
Y1161753D03*
Y1158407D03*
Y1155060D03*
Y1151714D03*
X174567Y1165100D03*
Y1161753D03*
Y1158407D03*
Y1155060D03*
Y1151714D03*
X188126Y1178486D03*
Y1175139D03*
Y1171793D03*
Y1168446D03*
X174567Y1178486D03*
Y1175139D03*
Y1171793D03*
Y1168446D03*
X188126Y1191871D03*
Y1188525D03*
Y1185178D03*
Y1181832D03*
X174567Y1191871D03*
Y1188525D03*
Y1185178D03*
Y1181832D03*
X188126Y1208604D03*
Y1205257D03*
Y1201911D03*
Y1198564D03*
Y1195218D03*
X174567Y1208604D03*
Y1205257D03*
Y1201911D03*
Y1198564D03*
Y1195218D03*
X188126Y1221989D03*
Y1218643D03*
Y1215297D03*
Y1211950D03*
X174567Y1221989D03*
Y1218643D03*
Y1215297D03*
Y1211950D03*
X188126Y1238722D03*
Y1235375D03*
Y1232029D03*
Y1228682D03*
Y1225336D03*
X174567Y1238722D03*
Y1235375D03*
Y1232029D03*
Y1228682D03*
Y1225336D03*
X188126Y1252108D03*
Y1248761D03*
Y1245415D03*
Y1242068D03*
X174567Y1252108D03*
Y1248761D03*
Y1245415D03*
Y1242068D03*
X188126Y1255454D03*
X174567D03*
X217827Y760178D03*
Y756832D03*
X204268Y760178D03*
Y756832D03*
X217827Y776911D03*
Y773564D03*
Y770218D03*
Y766871D03*
Y763525D03*
X204268Y776911D03*
Y773564D03*
Y770218D03*
Y766871D03*
Y763525D03*
X217827Y790297D03*
Y786950D03*
Y783604D03*
Y780257D03*
X204268Y790297D03*
Y786950D03*
Y783604D03*
Y780257D03*
X217827Y807029D03*
Y803682D03*
Y800336D03*
Y796989D03*
Y793643D03*
X204268Y807029D03*
Y803682D03*
Y800336D03*
Y796989D03*
Y793643D03*
X217827Y820415D03*
Y817068D03*
Y813722D03*
Y810375D03*
X204268Y820415D03*
Y817068D03*
Y813722D03*
Y810375D03*
X217827Y837147D03*
Y833800D03*
Y830454D03*
Y827108D03*
Y823761D03*
X204268Y837147D03*
Y833800D03*
Y830454D03*
Y827108D03*
Y823761D03*
X217827Y850533D03*
Y847186D03*
Y843840D03*
Y840493D03*
X204268Y850533D03*
Y847186D03*
Y843840D03*
Y840493D03*
X217827Y863919D03*
Y860572D03*
Y857226D03*
Y853879D03*
X204268Y863919D03*
Y860572D03*
Y857226D03*
Y853879D03*
X217827Y880651D03*
Y877304D03*
Y873958D03*
Y870611D03*
Y867265D03*
X204268Y880651D03*
Y877304D03*
Y873958D03*
Y870611D03*
Y867265D03*
X217827Y894037D03*
Y890690D03*
Y887344D03*
Y883997D03*
X204268Y894037D03*
Y890690D03*
Y887344D03*
Y883997D03*
X217827Y910769D03*
Y907423D03*
Y904076D03*
Y900730D03*
Y897383D03*
X204268Y910769D03*
Y907423D03*
Y904076D03*
Y900730D03*
Y897383D03*
X217827Y924155D03*
Y920808D03*
Y917462D03*
Y914115D03*
X204268Y924155D03*
Y920808D03*
Y917462D03*
Y914115D03*
X217827Y940887D03*
Y937541D03*
Y934194D03*
Y930848D03*
Y927501D03*
X204268Y940887D03*
Y937541D03*
Y934194D03*
Y930848D03*
Y927501D03*
X217827Y954273D03*
Y950926D03*
Y947580D03*
Y944234D03*
X204268Y954273D03*
Y950926D03*
Y947580D03*
Y944234D03*
X217827Y971005D03*
Y967659D03*
Y964312D03*
Y960966D03*
Y957619D03*
X204268Y971005D03*
Y967659D03*
Y964312D03*
Y960966D03*
Y957619D03*
X217827Y984391D03*
Y981045D03*
Y977698D03*
Y974352D03*
X204268Y984391D03*
Y981045D03*
Y977698D03*
Y974352D03*
X217827Y1001123D03*
Y997777D03*
Y994430D03*
Y991084D03*
Y987737D03*
X204268Y1001123D03*
Y997777D03*
Y994430D03*
Y991084D03*
Y987737D03*
X217827Y1004470D03*
X204268D03*
X217827Y1027895D03*
X204268D03*
X217827Y1044627D03*
Y1041281D03*
Y1037934D03*
Y1034588D03*
Y1031241D03*
X204268Y1044627D03*
Y1041281D03*
Y1037934D03*
Y1034588D03*
Y1031241D03*
X217827Y1058013D03*
Y1054667D03*
Y1051320D03*
Y1047974D03*
X204268Y1058013D03*
Y1054667D03*
Y1051320D03*
Y1047974D03*
X217827Y1074745D03*
Y1071399D03*
Y1068052D03*
Y1064706D03*
Y1061360D03*
X204268Y1074745D03*
Y1071399D03*
Y1068052D03*
Y1064706D03*
Y1061360D03*
X217827Y1088131D03*
Y1084785D03*
Y1081438D03*
Y1078092D03*
X204268Y1088131D03*
Y1084785D03*
Y1081438D03*
Y1078092D03*
X217827Y1104863D03*
Y1101517D03*
Y1098171D03*
Y1094824D03*
Y1091478D03*
X204268Y1104863D03*
Y1101517D03*
Y1098171D03*
Y1094824D03*
Y1091478D03*
X217827Y1118249D03*
Y1114903D03*
Y1111556D03*
Y1108210D03*
X204268Y1118249D03*
Y1114903D03*
Y1111556D03*
Y1108210D03*
X217827Y1134982D03*
Y1131635D03*
Y1128289D03*
Y1124942D03*
Y1121596D03*
X204268Y1134982D03*
Y1131635D03*
Y1128289D03*
Y1124942D03*
Y1121596D03*
X217827Y1148367D03*
Y1145021D03*
Y1141675D03*
Y1138328D03*
X204268Y1148367D03*
Y1145021D03*
Y1141675D03*
Y1138328D03*
X217827Y1165100D03*
Y1161753D03*
Y1158407D03*
Y1155060D03*
Y1151714D03*
X204268Y1165100D03*
Y1161753D03*
Y1158407D03*
Y1155060D03*
Y1151714D03*
X217827Y1178486D03*
Y1175139D03*
Y1171793D03*
Y1168446D03*
X204268Y1178486D03*
Y1175139D03*
Y1171793D03*
Y1168446D03*
X217827Y1191871D03*
Y1188525D03*
Y1185178D03*
Y1181832D03*
X204268Y1191871D03*
Y1188525D03*
Y1185178D03*
Y1181832D03*
X217827Y1208604D03*
Y1205257D03*
Y1201911D03*
Y1198564D03*
Y1195218D03*
X204268Y1208604D03*
Y1205257D03*
Y1201911D03*
Y1198564D03*
Y1195218D03*
X217827Y1221989D03*
Y1218643D03*
Y1215297D03*
Y1211950D03*
X204268Y1221989D03*
Y1218643D03*
Y1215297D03*
Y1211950D03*
X217827Y1238722D03*
Y1235375D03*
Y1232029D03*
Y1228682D03*
Y1225336D03*
X204268Y1238722D03*
Y1235375D03*
Y1232029D03*
Y1228682D03*
Y1225336D03*
X217827Y1252108D03*
Y1248761D03*
Y1245415D03*
Y1242068D03*
X204268Y1252108D03*
Y1248761D03*
Y1245415D03*
Y1242068D03*
X217827Y1255454D03*
X204268D03*
X233969Y760178D03*
Y756832D03*
Y776911D03*
Y773564D03*
Y770218D03*
Y766871D03*
Y763525D03*
Y790297D03*
Y786950D03*
Y783604D03*
Y780257D03*
Y807029D03*
Y803682D03*
Y800336D03*
Y796989D03*
Y793643D03*
Y820415D03*
Y817068D03*
Y813722D03*
Y810375D03*
Y837147D03*
Y833800D03*
Y830454D03*
Y827108D03*
Y823761D03*
Y850533D03*
Y847186D03*
Y843840D03*
Y840493D03*
Y863919D03*
Y860572D03*
Y857226D03*
Y853879D03*
Y880651D03*
Y877304D03*
Y873958D03*
Y870611D03*
Y867265D03*
Y894037D03*
Y890690D03*
Y887344D03*
Y883997D03*
Y910769D03*
Y907423D03*
Y904076D03*
Y900730D03*
Y897383D03*
Y924155D03*
Y920808D03*
Y917462D03*
Y914115D03*
Y940887D03*
Y937541D03*
Y934194D03*
Y930848D03*
Y927501D03*
Y954273D03*
Y950926D03*
Y947580D03*
Y944234D03*
Y971005D03*
Y967659D03*
Y964312D03*
Y960966D03*
Y957619D03*
Y984391D03*
Y981045D03*
Y977698D03*
Y974352D03*
Y1001123D03*
Y997777D03*
Y994430D03*
Y991084D03*
Y987737D03*
Y1004470D03*
Y1027895D03*
Y1044627D03*
Y1041281D03*
Y1037934D03*
Y1034588D03*
Y1031241D03*
Y1058013D03*
Y1054667D03*
Y1051320D03*
Y1047974D03*
Y1074745D03*
Y1071399D03*
Y1068052D03*
Y1064706D03*
Y1061360D03*
Y1088131D03*
Y1084785D03*
Y1081438D03*
Y1078092D03*
Y1104863D03*
Y1101517D03*
Y1098171D03*
Y1094824D03*
Y1091478D03*
Y1118249D03*
Y1114903D03*
Y1111556D03*
Y1108210D03*
Y1134982D03*
Y1131635D03*
Y1128289D03*
Y1124942D03*
Y1121596D03*
Y1148367D03*
Y1145021D03*
Y1141675D03*
Y1138328D03*
Y1165100D03*
Y1161753D03*
Y1158407D03*
Y1155060D03*
Y1151714D03*
Y1178486D03*
Y1175139D03*
Y1171793D03*
Y1168446D03*
Y1191871D03*
Y1188525D03*
Y1185178D03*
Y1181832D03*
Y1208604D03*
Y1205257D03*
Y1201911D03*
Y1198564D03*
Y1195218D03*
Y1221989D03*
Y1218643D03*
Y1215297D03*
Y1211950D03*
Y1238722D03*
Y1235375D03*
Y1232029D03*
Y1228682D03*
Y1225336D03*
Y1252108D03*
Y1248761D03*
Y1245415D03*
Y1242068D03*
Y1255454D03*
X647354Y760178D03*
Y756832D03*
Y776911D03*
Y773564D03*
Y770218D03*
Y766871D03*
Y763525D03*
Y790297D03*
Y786950D03*
Y783604D03*
Y780257D03*
Y807029D03*
Y803682D03*
Y800336D03*
Y796989D03*
Y793643D03*
Y820415D03*
Y817068D03*
Y813722D03*
Y810375D03*
Y837147D03*
Y833800D03*
Y830454D03*
Y827108D03*
Y823761D03*
Y850533D03*
Y847186D03*
Y843840D03*
Y840493D03*
Y863919D03*
Y860572D03*
Y857226D03*
Y853879D03*
Y880651D03*
Y877304D03*
Y873958D03*
Y870611D03*
Y867265D03*
Y894037D03*
Y890690D03*
Y887344D03*
Y883997D03*
Y910769D03*
Y907423D03*
Y904076D03*
Y900730D03*
Y897383D03*
Y924155D03*
Y920808D03*
Y917462D03*
Y914115D03*
Y940887D03*
Y937541D03*
Y934194D03*
Y930848D03*
Y927501D03*
Y954273D03*
Y950926D03*
Y947580D03*
Y944234D03*
Y971005D03*
Y967659D03*
Y964312D03*
Y960966D03*
Y957619D03*
Y984391D03*
Y981045D03*
Y977698D03*
Y974352D03*
Y1001123D03*
Y997777D03*
Y994430D03*
Y991084D03*
Y987737D03*
Y1004470D03*
Y1027895D03*
Y1044627D03*
Y1041281D03*
Y1037934D03*
Y1034588D03*
Y1031241D03*
Y1058013D03*
Y1054667D03*
Y1051320D03*
Y1047974D03*
Y1074745D03*
Y1071399D03*
Y1068052D03*
Y1064706D03*
Y1061360D03*
Y1088131D03*
Y1084785D03*
Y1081438D03*
Y1078092D03*
Y1104863D03*
Y1101517D03*
Y1098171D03*
Y1094824D03*
Y1091478D03*
Y1118249D03*
Y1114903D03*
Y1111556D03*
Y1108210D03*
Y1134982D03*
Y1131635D03*
Y1128289D03*
Y1124942D03*
Y1121596D03*
Y1148367D03*
Y1145021D03*
Y1141675D03*
Y1138328D03*
Y1165100D03*
Y1161753D03*
Y1158407D03*
Y1155060D03*
Y1151714D03*
Y1178486D03*
Y1175139D03*
Y1171793D03*
Y1168446D03*
Y1191871D03*
Y1188525D03*
Y1185178D03*
Y1181832D03*
Y1208604D03*
Y1205257D03*
Y1201911D03*
Y1198564D03*
Y1195218D03*
Y1221989D03*
Y1218643D03*
Y1215297D03*
Y1211950D03*
Y1238722D03*
Y1235375D03*
Y1232029D03*
Y1228682D03*
Y1225336D03*
Y1252108D03*
Y1248761D03*
Y1245415D03*
Y1242068D03*
Y1255454D03*
X663496Y760178D03*
Y756832D03*
Y776911D03*
Y773564D03*
Y770218D03*
Y766871D03*
Y763525D03*
Y790297D03*
Y786950D03*
Y783604D03*
Y780257D03*
Y807029D03*
Y803682D03*
Y800336D03*
Y796989D03*
Y793643D03*
Y820415D03*
Y817068D03*
Y813722D03*
Y810375D03*
Y837147D03*
Y833800D03*
Y830454D03*
Y827108D03*
Y823761D03*
Y850533D03*
Y847186D03*
Y843840D03*
Y840493D03*
Y863919D03*
Y860572D03*
Y857226D03*
Y853879D03*
Y880651D03*
Y877304D03*
Y873958D03*
Y870611D03*
Y867265D03*
Y894037D03*
Y890690D03*
Y887344D03*
Y883997D03*
Y910769D03*
Y907423D03*
Y904076D03*
Y900730D03*
Y897383D03*
Y924155D03*
Y920808D03*
Y917462D03*
Y914115D03*
Y940887D03*
Y937541D03*
Y934194D03*
Y930848D03*
Y927501D03*
Y954273D03*
Y950926D03*
Y947580D03*
Y944234D03*
Y971005D03*
Y967659D03*
Y964312D03*
Y960966D03*
Y957619D03*
Y984391D03*
Y981045D03*
Y977698D03*
Y974352D03*
Y1001123D03*
Y997777D03*
Y994430D03*
Y991084D03*
Y987737D03*
Y1004470D03*
Y1027895D03*
Y1044627D03*
Y1041281D03*
Y1037934D03*
Y1034588D03*
Y1031241D03*
Y1058013D03*
Y1054667D03*
Y1051320D03*
Y1047974D03*
Y1074745D03*
Y1071399D03*
Y1068052D03*
Y1064706D03*
Y1061360D03*
Y1088131D03*
Y1084785D03*
Y1081438D03*
Y1078092D03*
Y1104863D03*
Y1101517D03*
Y1098171D03*
Y1094824D03*
Y1091478D03*
Y1118249D03*
Y1114903D03*
Y1111556D03*
Y1108210D03*
Y1134982D03*
Y1131635D03*
Y1128289D03*
Y1124942D03*
Y1121596D03*
Y1148367D03*
Y1145021D03*
Y1141675D03*
Y1138328D03*
Y1165100D03*
Y1161753D03*
Y1158407D03*
Y1155060D03*
Y1151714D03*
Y1178486D03*
Y1175139D03*
Y1171793D03*
Y1168446D03*
Y1191871D03*
Y1188525D03*
Y1185178D03*
Y1181832D03*
Y1208604D03*
Y1205257D03*
Y1201911D03*
Y1198564D03*
Y1195218D03*
Y1221989D03*
Y1218643D03*
Y1215297D03*
Y1211950D03*
Y1238722D03*
Y1235375D03*
Y1232029D03*
Y1228682D03*
Y1225336D03*
Y1252108D03*
Y1248761D03*
Y1245415D03*
Y1242068D03*
Y1255454D03*
X677055Y760178D03*
Y756832D03*
Y776911D03*
Y773564D03*
Y770218D03*
Y766871D03*
Y763525D03*
Y790297D03*
Y786950D03*
Y783604D03*
Y780257D03*
Y807029D03*
Y803682D03*
Y800336D03*
Y796989D03*
Y793643D03*
Y820415D03*
Y817068D03*
Y813722D03*
Y810375D03*
Y837147D03*
Y833800D03*
Y830454D03*
Y827108D03*
Y823761D03*
Y850533D03*
Y847186D03*
Y843840D03*
Y840493D03*
Y863919D03*
Y860572D03*
Y857226D03*
Y853879D03*
Y880651D03*
Y877304D03*
Y873958D03*
Y870611D03*
Y867265D03*
Y894037D03*
Y890690D03*
Y887344D03*
Y883997D03*
Y910769D03*
Y907423D03*
Y904076D03*
Y900730D03*
Y897383D03*
Y924155D03*
Y920808D03*
Y917462D03*
Y914115D03*
Y940887D03*
Y937541D03*
Y934194D03*
Y930848D03*
Y927501D03*
Y954273D03*
Y950926D03*
Y947580D03*
Y944234D03*
Y971005D03*
Y967659D03*
Y964312D03*
Y960966D03*
Y957619D03*
Y984391D03*
Y981045D03*
Y977698D03*
Y974352D03*
Y1001123D03*
Y997777D03*
Y994430D03*
Y991084D03*
Y987737D03*
Y1004470D03*
Y1027895D03*
Y1044627D03*
Y1041281D03*
Y1037934D03*
Y1034588D03*
Y1031241D03*
Y1058013D03*
Y1054667D03*
Y1051320D03*
Y1047974D03*
Y1074745D03*
Y1071399D03*
Y1068052D03*
Y1064706D03*
Y1061360D03*
Y1088131D03*
Y1084785D03*
Y1081438D03*
Y1078092D03*
Y1104863D03*
Y1101517D03*
Y1098171D03*
Y1094824D03*
Y1091478D03*
Y1118249D03*
Y1114903D03*
Y1111556D03*
Y1108210D03*
Y1134982D03*
Y1131635D03*
Y1128289D03*
Y1124942D03*
Y1121596D03*
Y1148367D03*
Y1145021D03*
Y1141675D03*
Y1138328D03*
Y1165100D03*
Y1161753D03*
Y1158407D03*
Y1155060D03*
Y1151714D03*
Y1178486D03*
Y1175139D03*
Y1171793D03*
Y1168446D03*
Y1191871D03*
Y1188525D03*
Y1185178D03*
Y1181832D03*
Y1208604D03*
Y1205257D03*
Y1201911D03*
Y1198564D03*
Y1195218D03*
Y1221989D03*
Y1218643D03*
Y1215297D03*
Y1211950D03*
Y1238722D03*
Y1235375D03*
Y1232029D03*
Y1228682D03*
Y1225336D03*
Y1252108D03*
Y1248761D03*
Y1245415D03*
Y1242068D03*
Y1255454D03*
X693197Y760178D03*
Y756832D03*
Y776911D03*
Y773564D03*
Y770218D03*
Y766871D03*
Y763525D03*
Y790297D03*
Y786950D03*
Y783604D03*
Y780257D03*
Y807029D03*
Y803682D03*
Y800336D03*
Y796989D03*
Y793643D03*
Y820415D03*
Y817068D03*
Y813722D03*
Y810375D03*
Y837147D03*
Y833800D03*
Y830454D03*
Y827108D03*
Y823761D03*
Y850533D03*
Y847186D03*
Y843840D03*
Y840493D03*
Y863919D03*
Y860572D03*
Y857226D03*
Y853879D03*
Y880651D03*
Y877304D03*
Y873958D03*
Y870611D03*
Y867265D03*
Y894037D03*
Y890690D03*
Y887344D03*
Y883997D03*
Y910769D03*
Y907423D03*
Y904076D03*
Y900730D03*
Y897383D03*
Y924155D03*
Y920808D03*
Y917462D03*
Y914115D03*
Y940887D03*
Y937541D03*
Y934194D03*
Y930848D03*
Y927501D03*
Y954273D03*
Y950926D03*
Y947580D03*
Y944234D03*
Y971005D03*
Y967659D03*
Y964312D03*
Y960966D03*
Y957619D03*
Y984391D03*
Y981045D03*
Y977698D03*
Y974352D03*
Y1001123D03*
Y997777D03*
Y994430D03*
Y991084D03*
Y987737D03*
Y1004470D03*
Y1027895D03*
Y1044627D03*
Y1041281D03*
Y1037934D03*
Y1034588D03*
Y1031241D03*
Y1058013D03*
Y1054667D03*
Y1051320D03*
Y1047974D03*
Y1074745D03*
Y1071399D03*
Y1068052D03*
Y1064706D03*
Y1061360D03*
Y1088131D03*
Y1084785D03*
Y1081438D03*
Y1078092D03*
Y1104863D03*
Y1101517D03*
Y1098171D03*
Y1094824D03*
Y1091478D03*
Y1118249D03*
Y1114903D03*
Y1111556D03*
Y1108210D03*
Y1134982D03*
Y1131635D03*
Y1128289D03*
Y1124942D03*
Y1121596D03*
Y1148367D03*
Y1145021D03*
Y1141675D03*
Y1138328D03*
Y1165100D03*
Y1161753D03*
Y1158407D03*
Y1155060D03*
Y1151714D03*
Y1178486D03*
Y1175139D03*
Y1171793D03*
Y1168446D03*
Y1191871D03*
Y1188525D03*
Y1185178D03*
Y1181832D03*
Y1208604D03*
Y1205257D03*
Y1201911D03*
Y1198564D03*
Y1195218D03*
Y1221989D03*
Y1218643D03*
Y1215297D03*
Y1211950D03*
Y1238722D03*
Y1235375D03*
Y1232029D03*
Y1228682D03*
Y1225336D03*
Y1252108D03*
Y1248761D03*
Y1245415D03*
Y1242068D03*
Y1255454D03*
X706756Y760178D03*
Y756832D03*
Y776911D03*
Y773564D03*
Y770218D03*
Y766871D03*
Y763525D03*
Y790297D03*
Y786950D03*
Y783604D03*
Y780257D03*
Y807029D03*
Y803682D03*
Y800336D03*
Y796989D03*
Y793643D03*
Y820415D03*
Y817068D03*
Y813722D03*
Y810375D03*
Y837147D03*
Y833800D03*
Y830454D03*
Y827108D03*
Y823761D03*
Y850533D03*
Y847186D03*
Y843840D03*
Y840493D03*
Y863919D03*
Y860572D03*
Y857226D03*
Y853879D03*
Y880651D03*
Y877304D03*
Y873958D03*
Y870611D03*
Y867265D03*
Y894037D03*
Y890690D03*
Y887344D03*
Y883997D03*
Y910769D03*
Y907423D03*
Y904076D03*
Y900730D03*
Y897383D03*
Y924155D03*
Y920808D03*
Y917462D03*
Y914115D03*
Y940887D03*
Y937541D03*
Y934194D03*
Y930848D03*
Y927501D03*
Y954273D03*
Y950926D03*
Y947580D03*
Y944234D03*
Y971005D03*
Y967659D03*
Y964312D03*
Y960966D03*
Y957619D03*
Y984391D03*
Y981045D03*
Y977698D03*
Y974352D03*
Y1001123D03*
Y997777D03*
Y994430D03*
Y991084D03*
Y987737D03*
Y1004470D03*
Y1027895D03*
Y1044627D03*
Y1041281D03*
Y1037934D03*
Y1034588D03*
Y1031241D03*
Y1058013D03*
Y1054667D03*
Y1051320D03*
Y1047974D03*
Y1074745D03*
Y1071399D03*
Y1068052D03*
Y1064706D03*
Y1061360D03*
Y1088131D03*
Y1084785D03*
Y1081438D03*
Y1078092D03*
Y1104863D03*
Y1101517D03*
Y1098171D03*
Y1094824D03*
Y1091478D03*
Y1118249D03*
Y1114903D03*
Y1111556D03*
Y1108210D03*
Y1134982D03*
Y1131635D03*
Y1128289D03*
Y1124942D03*
Y1121596D03*
Y1148367D03*
Y1145021D03*
Y1141675D03*
Y1138328D03*
Y1165100D03*
Y1161753D03*
Y1158407D03*
Y1155060D03*
Y1151714D03*
Y1178486D03*
Y1175139D03*
Y1171793D03*
Y1168446D03*
Y1191871D03*
Y1188525D03*
Y1185178D03*
Y1181832D03*
Y1208604D03*
Y1205257D03*
Y1201911D03*
Y1198564D03*
Y1195218D03*
Y1221989D03*
Y1218643D03*
Y1215297D03*
Y1211950D03*
Y1238722D03*
Y1235375D03*
Y1232029D03*
Y1228682D03*
Y1225336D03*
Y1252108D03*
Y1248761D03*
Y1245415D03*
Y1242068D03*
Y1255454D03*
X722898Y760178D03*
Y756832D03*
Y776911D03*
Y773564D03*
Y770218D03*
Y766871D03*
Y763525D03*
Y790297D03*
Y786950D03*
Y783604D03*
Y780257D03*
Y807029D03*
Y803682D03*
Y800336D03*
Y796989D03*
Y793643D03*
Y820415D03*
Y817068D03*
Y813722D03*
Y810375D03*
Y837147D03*
Y833800D03*
Y830454D03*
Y827108D03*
Y823761D03*
Y850533D03*
Y847186D03*
Y843840D03*
Y840493D03*
Y863919D03*
Y860572D03*
Y857226D03*
Y853879D03*
Y880651D03*
Y877304D03*
Y873958D03*
Y870611D03*
Y867265D03*
Y894037D03*
Y890690D03*
Y887344D03*
Y883997D03*
Y910769D03*
Y907423D03*
Y904076D03*
Y900730D03*
Y897383D03*
Y924155D03*
Y920808D03*
Y917462D03*
Y914115D03*
Y940887D03*
Y937541D03*
Y934194D03*
Y930848D03*
Y927501D03*
Y954273D03*
Y950926D03*
Y947580D03*
Y944234D03*
Y971005D03*
Y967659D03*
Y964312D03*
Y960966D03*
Y957619D03*
Y984391D03*
Y981045D03*
Y977698D03*
Y974352D03*
Y1001123D03*
Y997777D03*
Y994430D03*
Y991084D03*
Y987737D03*
Y1004470D03*
Y1027895D03*
Y1044627D03*
Y1041281D03*
Y1037934D03*
Y1034588D03*
Y1031241D03*
Y1058013D03*
Y1054667D03*
Y1051320D03*
Y1047974D03*
Y1074745D03*
Y1071399D03*
Y1068052D03*
Y1064706D03*
Y1061360D03*
Y1088131D03*
Y1084785D03*
Y1081438D03*
Y1078092D03*
Y1104863D03*
Y1101517D03*
Y1098171D03*
Y1094824D03*
Y1091478D03*
Y1118249D03*
Y1114903D03*
Y1111556D03*
Y1108210D03*
Y1134982D03*
Y1131635D03*
Y1128289D03*
Y1124942D03*
Y1121596D03*
Y1148367D03*
Y1145021D03*
Y1141675D03*
Y1138328D03*
Y1165100D03*
Y1161753D03*
Y1158407D03*
Y1155060D03*
Y1151714D03*
Y1178486D03*
Y1175139D03*
Y1171793D03*
Y1168446D03*
Y1191871D03*
Y1188525D03*
Y1185178D03*
Y1181832D03*
Y1208604D03*
Y1205257D03*
Y1201911D03*
Y1198564D03*
Y1195218D03*
Y1221989D03*
Y1218643D03*
Y1215297D03*
Y1211950D03*
Y1238722D03*
Y1235375D03*
Y1232029D03*
Y1228682D03*
Y1225336D03*
Y1252108D03*
Y1248761D03*
Y1245415D03*
Y1242068D03*
Y1255454D03*
X736457Y760178D03*
Y756832D03*
Y776911D03*
Y773564D03*
Y770218D03*
Y766871D03*
Y763525D03*
Y790297D03*
Y786950D03*
Y783604D03*
Y780257D03*
Y807029D03*
Y803682D03*
Y800336D03*
Y796989D03*
Y793643D03*
Y820415D03*
Y817068D03*
Y813722D03*
Y810375D03*
Y837147D03*
Y833800D03*
Y830454D03*
Y827108D03*
Y823761D03*
Y850533D03*
Y847186D03*
Y843840D03*
Y840493D03*
Y863919D03*
Y860572D03*
Y857226D03*
Y853879D03*
Y880651D03*
Y877304D03*
Y873958D03*
Y870611D03*
Y867265D03*
Y894037D03*
Y890690D03*
Y887344D03*
Y883997D03*
Y910769D03*
Y907423D03*
Y904076D03*
Y900730D03*
Y897383D03*
Y924155D03*
Y920808D03*
Y917462D03*
Y914115D03*
Y940887D03*
Y937541D03*
Y934194D03*
Y930848D03*
Y927501D03*
Y954273D03*
Y950926D03*
Y947580D03*
Y944234D03*
Y971005D03*
Y967659D03*
Y964312D03*
Y960966D03*
Y957619D03*
Y984391D03*
Y981045D03*
Y977698D03*
Y974352D03*
Y1001123D03*
Y997777D03*
Y994430D03*
Y991084D03*
Y987737D03*
Y1004470D03*
Y1027895D03*
Y1044627D03*
Y1041281D03*
Y1037934D03*
Y1034588D03*
Y1031241D03*
Y1058013D03*
Y1054667D03*
Y1051320D03*
Y1047974D03*
Y1074745D03*
Y1071399D03*
Y1068052D03*
Y1064706D03*
Y1061360D03*
Y1088131D03*
Y1084785D03*
Y1081438D03*
Y1078092D03*
Y1104863D03*
Y1101517D03*
Y1098171D03*
Y1094824D03*
Y1091478D03*
Y1118249D03*
Y1114903D03*
Y1111556D03*
Y1108210D03*
Y1134982D03*
Y1131635D03*
Y1128289D03*
Y1124942D03*
Y1121596D03*
Y1148367D03*
Y1145021D03*
Y1141675D03*
Y1138328D03*
Y1165100D03*
Y1161753D03*
Y1158407D03*
Y1155060D03*
Y1151714D03*
Y1178486D03*
Y1175139D03*
Y1171793D03*
Y1168446D03*
Y1191871D03*
Y1188525D03*
Y1185178D03*
Y1181832D03*
Y1208604D03*
Y1205257D03*
Y1201911D03*
Y1198564D03*
Y1195218D03*
Y1221989D03*
Y1218643D03*
Y1215297D03*
Y1211950D03*
Y1238722D03*
Y1235375D03*
Y1232029D03*
Y1228682D03*
Y1225336D03*
Y1252108D03*
Y1248761D03*
Y1245415D03*
Y1242068D03*
Y1255454D03*
X752599Y760178D03*
Y756832D03*
Y776911D03*
Y773564D03*
Y770218D03*
Y766871D03*
Y763525D03*
Y790297D03*
Y786950D03*
Y783604D03*
Y780257D03*
Y807029D03*
Y803682D03*
Y800336D03*
Y796989D03*
Y793643D03*
Y820415D03*
Y817068D03*
Y813722D03*
Y810375D03*
Y837147D03*
Y833800D03*
Y830454D03*
Y827108D03*
Y823761D03*
Y850533D03*
Y847186D03*
Y843840D03*
Y840493D03*
Y863919D03*
Y860572D03*
Y857226D03*
Y853879D03*
Y880651D03*
Y877304D03*
Y873958D03*
Y870611D03*
Y867265D03*
Y894037D03*
Y890690D03*
Y887344D03*
Y883997D03*
Y910769D03*
Y907423D03*
Y904076D03*
Y900730D03*
Y897383D03*
Y924155D03*
Y920808D03*
Y917462D03*
Y914115D03*
Y940887D03*
Y937541D03*
Y934194D03*
Y930848D03*
Y927501D03*
Y954273D03*
Y950926D03*
Y947580D03*
Y944234D03*
Y971005D03*
Y967659D03*
Y964312D03*
Y960966D03*
Y957619D03*
Y984391D03*
Y981045D03*
Y977698D03*
Y974352D03*
Y1001123D03*
Y997777D03*
Y994430D03*
Y991084D03*
Y987737D03*
Y1004470D03*
Y1027895D03*
Y1044627D03*
Y1041281D03*
Y1037934D03*
Y1034588D03*
Y1031241D03*
Y1058013D03*
Y1054667D03*
Y1051320D03*
Y1047974D03*
Y1074745D03*
Y1071399D03*
Y1068052D03*
Y1064706D03*
Y1061360D03*
Y1088131D03*
Y1084785D03*
Y1081438D03*
Y1078092D03*
Y1104863D03*
Y1101517D03*
Y1098171D03*
Y1094824D03*
Y1091478D03*
Y1118249D03*
Y1114903D03*
Y1111556D03*
Y1108210D03*
Y1134982D03*
Y1131635D03*
Y1128289D03*
Y1124942D03*
Y1121596D03*
Y1148367D03*
Y1145021D03*
Y1141675D03*
Y1138328D03*
Y1165100D03*
Y1161753D03*
Y1158407D03*
Y1155060D03*
Y1151714D03*
Y1178486D03*
Y1175139D03*
Y1171793D03*
Y1168446D03*
Y1191871D03*
Y1188525D03*
Y1185178D03*
Y1181832D03*
Y1208604D03*
Y1205257D03*
Y1201911D03*
Y1198564D03*
Y1195218D03*
Y1221989D03*
Y1218643D03*
Y1215297D03*
Y1211950D03*
Y1238722D03*
Y1235375D03*
Y1232029D03*
Y1228682D03*
Y1225336D03*
Y1252108D03*
Y1248761D03*
Y1245415D03*
Y1242068D03*
Y1255454D03*
X766158Y760178D03*
Y756832D03*
Y776911D03*
Y773564D03*
Y770218D03*
Y766871D03*
Y763525D03*
Y790297D03*
Y786950D03*
Y783604D03*
Y780257D03*
Y807029D03*
Y803682D03*
Y800336D03*
Y796989D03*
Y793643D03*
Y820415D03*
Y817068D03*
Y813722D03*
Y810375D03*
Y837147D03*
Y833800D03*
Y830454D03*
Y827108D03*
Y823761D03*
Y850533D03*
Y847186D03*
Y843840D03*
Y840493D03*
Y863919D03*
Y860572D03*
Y857226D03*
Y853879D03*
Y880651D03*
Y877304D03*
Y873958D03*
Y870611D03*
Y867265D03*
Y894037D03*
Y890690D03*
Y887344D03*
Y883997D03*
Y910769D03*
Y907423D03*
Y904076D03*
Y900730D03*
Y897383D03*
Y924155D03*
Y920808D03*
Y917462D03*
Y914115D03*
Y940887D03*
Y937541D03*
Y934194D03*
Y930848D03*
Y927501D03*
Y954273D03*
Y950926D03*
Y947580D03*
Y944234D03*
Y971005D03*
Y967659D03*
Y964312D03*
Y960966D03*
Y957619D03*
Y984391D03*
Y981045D03*
Y977698D03*
Y974352D03*
Y1001123D03*
Y997777D03*
Y994430D03*
Y991084D03*
Y987737D03*
Y1004470D03*
Y1027895D03*
Y1044627D03*
Y1041281D03*
Y1037934D03*
Y1034588D03*
Y1031241D03*
Y1058013D03*
Y1054667D03*
Y1051320D03*
Y1047974D03*
Y1074745D03*
Y1071399D03*
Y1068052D03*
Y1064706D03*
Y1061360D03*
Y1088131D03*
Y1084785D03*
Y1081438D03*
Y1078092D03*
Y1104863D03*
Y1101517D03*
Y1098171D03*
Y1094824D03*
Y1091478D03*
Y1118249D03*
Y1114903D03*
Y1111556D03*
Y1108210D03*
Y1134982D03*
Y1131635D03*
Y1128289D03*
Y1124942D03*
Y1121596D03*
Y1148367D03*
Y1145021D03*
Y1141675D03*
Y1138328D03*
Y1165100D03*
Y1161753D03*
Y1158407D03*
Y1155060D03*
Y1151714D03*
Y1178486D03*
Y1175139D03*
Y1171793D03*
Y1168446D03*
Y1191871D03*
Y1188525D03*
Y1185178D03*
Y1181832D03*
Y1208604D03*
Y1205257D03*
Y1201911D03*
Y1198564D03*
Y1195218D03*
Y1221989D03*
Y1218643D03*
Y1215297D03*
Y1211950D03*
Y1238722D03*
Y1235375D03*
Y1232029D03*
Y1228682D03*
Y1225336D03*
Y1252108D03*
Y1248761D03*
Y1245415D03*
Y1242068D03*
Y1255454D03*
X782300Y760178D03*
Y756832D03*
Y776911D03*
Y773564D03*
Y770218D03*
Y766871D03*
Y763525D03*
Y790297D03*
Y786950D03*
Y783604D03*
Y780257D03*
Y807029D03*
Y803682D03*
Y800336D03*
Y796989D03*
Y793643D03*
Y820415D03*
Y817068D03*
Y813722D03*
Y810375D03*
Y837147D03*
Y833800D03*
Y830454D03*
Y827108D03*
Y823761D03*
Y850533D03*
Y847186D03*
Y843840D03*
Y840493D03*
Y863919D03*
Y860572D03*
Y857226D03*
Y853879D03*
Y880651D03*
Y877304D03*
Y873958D03*
Y870611D03*
Y867265D03*
Y894037D03*
Y890690D03*
Y887344D03*
Y883997D03*
Y910769D03*
Y907423D03*
Y904076D03*
Y900730D03*
Y897383D03*
Y924155D03*
Y920808D03*
Y917462D03*
Y914115D03*
Y940887D03*
Y937541D03*
Y934194D03*
Y930848D03*
Y927501D03*
Y954273D03*
Y950926D03*
Y947580D03*
Y944234D03*
Y971005D03*
Y967659D03*
Y964312D03*
Y960966D03*
Y957619D03*
Y984391D03*
Y981045D03*
Y977698D03*
Y974352D03*
Y1001123D03*
Y997777D03*
Y994430D03*
Y991084D03*
Y987737D03*
Y1004470D03*
Y1027895D03*
Y1044627D03*
Y1041281D03*
Y1037934D03*
Y1034588D03*
Y1031241D03*
Y1058013D03*
Y1054667D03*
Y1051320D03*
Y1047974D03*
Y1074745D03*
Y1071399D03*
Y1068052D03*
Y1064706D03*
Y1061360D03*
Y1088131D03*
Y1084785D03*
Y1081438D03*
Y1078092D03*
Y1104863D03*
Y1101517D03*
Y1098171D03*
Y1094824D03*
Y1091478D03*
Y1118249D03*
Y1114903D03*
Y1111556D03*
Y1108210D03*
Y1134982D03*
Y1131635D03*
Y1128289D03*
Y1124942D03*
Y1121596D03*
Y1148367D03*
Y1145021D03*
Y1141675D03*
Y1138328D03*
Y1165100D03*
Y1161753D03*
Y1158407D03*
Y1155060D03*
Y1151714D03*
Y1178486D03*
Y1175139D03*
Y1171793D03*
Y1168446D03*
Y1191871D03*
Y1188525D03*
Y1185178D03*
Y1181832D03*
Y1208604D03*
Y1205257D03*
Y1201911D03*
Y1198564D03*
Y1195218D03*
Y1221989D03*
Y1218643D03*
Y1215297D03*
Y1211950D03*
Y1238722D03*
Y1235375D03*
Y1232029D03*
Y1228682D03*
Y1225336D03*
Y1252108D03*
Y1248761D03*
Y1245415D03*
Y1242068D03*
Y1255454D03*
X795858Y760178D03*
Y756832D03*
Y776911D03*
Y773564D03*
Y770218D03*
Y766871D03*
Y763525D03*
Y790297D03*
Y786950D03*
Y783604D03*
Y780257D03*
Y807029D03*
Y803682D03*
Y800336D03*
Y796989D03*
Y793643D03*
Y820415D03*
Y817068D03*
Y813722D03*
Y810375D03*
Y837147D03*
Y833800D03*
Y830454D03*
Y827108D03*
Y823761D03*
Y850533D03*
Y847186D03*
Y843840D03*
Y840493D03*
Y863919D03*
Y860572D03*
Y857226D03*
Y853879D03*
Y880651D03*
Y877304D03*
Y873958D03*
Y870611D03*
Y867265D03*
Y894037D03*
Y890690D03*
Y887344D03*
Y883997D03*
Y910769D03*
Y907423D03*
Y904076D03*
Y900730D03*
Y897383D03*
Y924155D03*
Y920808D03*
Y917462D03*
Y914115D03*
Y940887D03*
Y937541D03*
Y934194D03*
Y930848D03*
Y927501D03*
Y954273D03*
Y950926D03*
Y947580D03*
Y944234D03*
Y971005D03*
Y967659D03*
Y964312D03*
Y960966D03*
Y957619D03*
Y984391D03*
Y981045D03*
Y977698D03*
Y974352D03*
Y1001123D03*
Y997777D03*
Y994430D03*
Y991084D03*
Y987737D03*
Y1004470D03*
Y1027895D03*
Y1044627D03*
Y1041281D03*
Y1037934D03*
Y1034588D03*
Y1031241D03*
Y1058013D03*
Y1054667D03*
Y1051320D03*
Y1047974D03*
Y1074745D03*
Y1071399D03*
Y1068052D03*
Y1064706D03*
Y1061360D03*
Y1088131D03*
Y1084785D03*
Y1081438D03*
Y1078092D03*
Y1104863D03*
Y1101517D03*
Y1098171D03*
Y1094824D03*
Y1091478D03*
Y1118249D03*
Y1114903D03*
Y1111556D03*
Y1108210D03*
Y1134982D03*
Y1131635D03*
Y1128289D03*
Y1124942D03*
Y1121596D03*
Y1148367D03*
Y1145021D03*
Y1141675D03*
Y1138328D03*
Y1165100D03*
Y1161753D03*
Y1158407D03*
Y1155060D03*
Y1151714D03*
Y1178486D03*
Y1175139D03*
Y1171793D03*
Y1168446D03*
Y1191871D03*
Y1188525D03*
Y1185178D03*
Y1181832D03*
Y1208604D03*
Y1205257D03*
Y1201911D03*
Y1198564D03*
Y1195218D03*
Y1221989D03*
Y1218643D03*
Y1215297D03*
Y1211950D03*
Y1238722D03*
Y1235375D03*
Y1232029D03*
Y1228682D03*
Y1225336D03*
Y1252108D03*
Y1248761D03*
Y1245415D03*
Y1242068D03*
Y1255454D03*
X812000Y760178D03*
Y756832D03*
Y776911D03*
Y773564D03*
Y770218D03*
Y766871D03*
Y763525D03*
Y790297D03*
Y786950D03*
Y783604D03*
Y780257D03*
Y807029D03*
Y803682D03*
Y800336D03*
Y796989D03*
Y793643D03*
Y820415D03*
Y817068D03*
Y813722D03*
Y810375D03*
Y837147D03*
Y833800D03*
Y830454D03*
Y827108D03*
Y823761D03*
Y850533D03*
Y847186D03*
Y843840D03*
Y840493D03*
Y863919D03*
Y860572D03*
Y857226D03*
Y853879D03*
Y880651D03*
Y877304D03*
Y873958D03*
Y870611D03*
Y867265D03*
Y894037D03*
Y890690D03*
Y887344D03*
Y883997D03*
Y910769D03*
Y907423D03*
Y904076D03*
Y900730D03*
Y897383D03*
Y924155D03*
Y920808D03*
Y917462D03*
Y914115D03*
Y940887D03*
Y937541D03*
Y934194D03*
Y930848D03*
Y927501D03*
Y954273D03*
Y950926D03*
Y947580D03*
Y944234D03*
Y971005D03*
Y967659D03*
Y964312D03*
Y960966D03*
Y957619D03*
Y984391D03*
Y981045D03*
Y977698D03*
Y974352D03*
Y1001123D03*
Y997777D03*
Y994430D03*
Y991084D03*
Y987737D03*
Y1004470D03*
Y1027895D03*
Y1044627D03*
Y1041281D03*
Y1037934D03*
Y1034588D03*
Y1031241D03*
Y1058013D03*
Y1054667D03*
Y1051320D03*
Y1047974D03*
Y1074745D03*
Y1071399D03*
Y1068052D03*
Y1064706D03*
Y1061360D03*
Y1088131D03*
Y1084785D03*
Y1081438D03*
Y1078092D03*
Y1104863D03*
Y1101517D03*
Y1098171D03*
Y1094824D03*
Y1091478D03*
Y1118249D03*
Y1114903D03*
Y1111556D03*
Y1108210D03*
Y1134982D03*
Y1131635D03*
Y1128289D03*
Y1124942D03*
Y1121596D03*
Y1148367D03*
Y1145021D03*
Y1141675D03*
Y1138328D03*
Y1165100D03*
Y1161753D03*
Y1158407D03*
Y1155060D03*
Y1151714D03*
Y1178486D03*
Y1175139D03*
Y1171793D03*
Y1168446D03*
Y1191871D03*
Y1188525D03*
Y1185178D03*
Y1181832D03*
Y1208604D03*
Y1205257D03*
Y1201911D03*
Y1198564D03*
Y1195218D03*
Y1221989D03*
Y1218643D03*
Y1215297D03*
Y1211950D03*
Y1238722D03*
Y1235375D03*
Y1232029D03*
Y1228682D03*
Y1225336D03*
Y1252108D03*
Y1248761D03*
Y1245415D03*
Y1242068D03*
Y1255454D03*
X1045465Y760177D03*
Y756831D03*
Y776910D03*
Y773563D03*
Y770217D03*
Y766870D03*
Y763524D03*
Y790296D03*
Y786949D03*
Y783603D03*
Y780256D03*
Y807028D03*
Y803681D03*
Y800335D03*
Y796988D03*
Y793642D03*
Y820414D03*
Y817067D03*
Y813721D03*
Y810374D03*
Y837146D03*
Y833799D03*
Y830453D03*
Y827107D03*
Y823760D03*
Y850532D03*
Y847185D03*
Y843839D03*
Y840492D03*
Y863918D03*
Y860571D03*
Y857225D03*
Y853878D03*
Y880650D03*
Y877303D03*
Y873957D03*
Y870610D03*
Y867264D03*
Y894036D03*
Y890689D03*
Y887343D03*
Y883996D03*
Y910768D03*
Y907422D03*
Y904075D03*
Y900729D03*
Y897382D03*
Y924154D03*
Y920807D03*
Y917461D03*
Y914114D03*
Y940886D03*
Y937540D03*
Y934193D03*
Y930847D03*
Y927500D03*
Y954272D03*
Y950925D03*
Y947579D03*
Y944233D03*
Y971004D03*
Y967658D03*
Y964311D03*
Y960965D03*
Y957618D03*
Y984390D03*
Y981044D03*
Y977697D03*
Y974351D03*
Y1001122D03*
Y997776D03*
Y994429D03*
Y991083D03*
Y987736D03*
Y1004469D03*
Y1027894D03*
Y1044626D03*
Y1041280D03*
Y1037933D03*
Y1034587D03*
Y1031240D03*
Y1058012D03*
Y1054666D03*
Y1051319D03*
Y1047973D03*
Y1074744D03*
Y1071398D03*
Y1068051D03*
Y1064705D03*
Y1061359D03*
Y1088130D03*
Y1084784D03*
Y1081437D03*
Y1078091D03*
Y1104862D03*
Y1101516D03*
Y1098170D03*
Y1094823D03*
Y1091477D03*
Y1118248D03*
Y1114902D03*
Y1111555D03*
Y1108209D03*
Y1134981D03*
Y1131634D03*
Y1128288D03*
Y1124941D03*
Y1121595D03*
Y1148366D03*
Y1145020D03*
Y1141674D03*
Y1138327D03*
Y1165099D03*
Y1161752D03*
Y1158406D03*
Y1155059D03*
Y1151713D03*
Y1178485D03*
Y1175138D03*
Y1171792D03*
Y1168445D03*
Y1191870D03*
Y1188524D03*
Y1185177D03*
Y1181831D03*
Y1208603D03*
Y1205256D03*
Y1201910D03*
Y1198563D03*
Y1195217D03*
Y1221988D03*
Y1218642D03*
Y1215296D03*
Y1211949D03*
Y1238721D03*
Y1235374D03*
Y1232028D03*
Y1228681D03*
Y1225335D03*
Y1252107D03*
Y1248760D03*
Y1245414D03*
Y1242067D03*
Y1255453D03*
X1061607Y760177D03*
Y756831D03*
Y776910D03*
Y773563D03*
Y770217D03*
Y766870D03*
Y763524D03*
Y790296D03*
Y786949D03*
Y783603D03*
Y780256D03*
Y807028D03*
Y803681D03*
Y800335D03*
Y796988D03*
Y793642D03*
Y820414D03*
Y817067D03*
Y813721D03*
Y810374D03*
Y837146D03*
Y833799D03*
Y830453D03*
Y827107D03*
Y823760D03*
Y850532D03*
Y847185D03*
Y843839D03*
Y840492D03*
Y863918D03*
Y860571D03*
Y857225D03*
Y853878D03*
Y880650D03*
Y877303D03*
Y873957D03*
Y870610D03*
Y867264D03*
Y894036D03*
Y890689D03*
Y887343D03*
Y883996D03*
Y910768D03*
Y907422D03*
Y904075D03*
Y900729D03*
Y897382D03*
Y924154D03*
Y920807D03*
Y917461D03*
Y914114D03*
Y940886D03*
Y937540D03*
Y934193D03*
Y930847D03*
Y927500D03*
Y954272D03*
Y950925D03*
Y947579D03*
Y944233D03*
Y971004D03*
Y967658D03*
Y964311D03*
Y960965D03*
Y957618D03*
Y984390D03*
Y981044D03*
Y977697D03*
Y974351D03*
Y1001122D03*
Y997776D03*
Y994429D03*
Y991083D03*
Y987736D03*
Y1004469D03*
Y1027894D03*
Y1044626D03*
Y1041280D03*
Y1037933D03*
Y1034587D03*
Y1031240D03*
Y1058012D03*
Y1054666D03*
Y1051319D03*
Y1047973D03*
Y1074744D03*
Y1071398D03*
Y1068051D03*
Y1064705D03*
Y1061359D03*
Y1088130D03*
Y1084784D03*
Y1081437D03*
Y1078091D03*
Y1104862D03*
Y1101516D03*
Y1098170D03*
Y1094823D03*
Y1091477D03*
Y1118248D03*
Y1114902D03*
Y1111555D03*
Y1108209D03*
Y1134981D03*
Y1131634D03*
Y1128288D03*
Y1124941D03*
Y1121595D03*
Y1148366D03*
Y1145020D03*
Y1141674D03*
Y1138327D03*
Y1165099D03*
Y1161752D03*
Y1158406D03*
Y1155059D03*
Y1151713D03*
Y1178485D03*
Y1175138D03*
Y1171792D03*
Y1168445D03*
Y1191870D03*
Y1188524D03*
Y1185177D03*
Y1181831D03*
Y1208603D03*
Y1205256D03*
Y1201910D03*
Y1198563D03*
Y1195217D03*
Y1221988D03*
Y1218642D03*
Y1215296D03*
Y1211949D03*
Y1238721D03*
Y1235374D03*
Y1232028D03*
Y1228681D03*
Y1225335D03*
Y1252107D03*
Y1248760D03*
Y1245414D03*
Y1242067D03*
Y1255453D03*
X1075166Y760177D03*
Y756831D03*
Y776910D03*
Y773563D03*
Y770217D03*
Y766870D03*
Y763524D03*
Y790296D03*
Y786949D03*
Y783603D03*
Y780256D03*
Y807028D03*
Y803681D03*
Y800335D03*
Y796988D03*
Y793642D03*
Y820414D03*
Y817067D03*
Y813721D03*
Y810374D03*
Y837146D03*
Y833799D03*
Y830453D03*
Y827107D03*
Y823760D03*
Y850532D03*
Y847185D03*
Y843839D03*
Y840492D03*
Y863918D03*
Y860571D03*
Y857225D03*
Y853878D03*
Y880650D03*
Y877303D03*
Y873957D03*
Y870610D03*
Y867264D03*
Y894036D03*
Y890689D03*
Y887343D03*
Y883996D03*
Y910768D03*
Y907422D03*
Y904075D03*
Y900729D03*
Y897382D03*
Y924154D03*
Y920807D03*
Y917461D03*
Y914114D03*
Y940886D03*
Y937540D03*
Y934193D03*
Y930847D03*
Y927500D03*
Y954272D03*
Y950925D03*
Y947579D03*
Y944233D03*
Y971004D03*
Y967658D03*
Y964311D03*
Y960965D03*
Y957618D03*
Y984390D03*
Y981044D03*
Y977697D03*
Y974351D03*
Y1001122D03*
Y997776D03*
Y994429D03*
Y991083D03*
Y987736D03*
Y1004469D03*
Y1027894D03*
Y1044626D03*
Y1041280D03*
Y1037933D03*
Y1034587D03*
Y1031240D03*
Y1058012D03*
Y1054666D03*
Y1051319D03*
Y1047973D03*
Y1074744D03*
Y1071398D03*
Y1068051D03*
Y1064705D03*
Y1061359D03*
Y1088130D03*
Y1084784D03*
Y1081437D03*
Y1078091D03*
Y1104862D03*
Y1101516D03*
Y1098170D03*
Y1094823D03*
Y1091477D03*
Y1118248D03*
Y1114902D03*
Y1111555D03*
Y1108209D03*
Y1134981D03*
Y1131634D03*
Y1128288D03*
Y1124941D03*
Y1121595D03*
Y1148366D03*
Y1145020D03*
Y1141674D03*
Y1138327D03*
Y1165099D03*
Y1161752D03*
Y1158406D03*
Y1155059D03*
Y1151713D03*
Y1178485D03*
Y1175138D03*
Y1171792D03*
Y1168445D03*
Y1191870D03*
Y1188524D03*
Y1185177D03*
Y1181831D03*
Y1208603D03*
Y1205256D03*
Y1201910D03*
Y1198563D03*
Y1195217D03*
Y1221988D03*
Y1218642D03*
Y1215296D03*
Y1211949D03*
Y1238721D03*
Y1235374D03*
Y1232028D03*
Y1228681D03*
Y1225335D03*
Y1252107D03*
Y1248760D03*
Y1245414D03*
Y1242067D03*
Y1255453D03*
X1091308Y760177D03*
Y756831D03*
Y776910D03*
Y773563D03*
Y770217D03*
Y766870D03*
Y763524D03*
Y790296D03*
Y786949D03*
Y783603D03*
Y780256D03*
Y807028D03*
Y803681D03*
Y800335D03*
Y796988D03*
Y793642D03*
Y820414D03*
Y817067D03*
Y813721D03*
Y810374D03*
Y837146D03*
Y833799D03*
Y830453D03*
Y827107D03*
Y823760D03*
Y850532D03*
Y847185D03*
Y843839D03*
Y840492D03*
Y863918D03*
Y860571D03*
Y857225D03*
Y853878D03*
Y880650D03*
Y877303D03*
Y873957D03*
Y870610D03*
Y867264D03*
Y894036D03*
Y890689D03*
Y887343D03*
Y883996D03*
Y910768D03*
Y907422D03*
Y904075D03*
Y900729D03*
Y897382D03*
Y924154D03*
Y920807D03*
Y917461D03*
Y914114D03*
Y940886D03*
Y937540D03*
Y934193D03*
Y930847D03*
Y927500D03*
Y954272D03*
Y950925D03*
Y947579D03*
Y944233D03*
Y971004D03*
Y967658D03*
Y964311D03*
Y960965D03*
Y957618D03*
Y984390D03*
Y981044D03*
Y977697D03*
Y974351D03*
Y1001122D03*
Y997776D03*
Y994429D03*
Y991083D03*
Y987736D03*
Y1004469D03*
Y1027894D03*
Y1044626D03*
Y1041280D03*
Y1037933D03*
Y1034587D03*
Y1031240D03*
Y1058012D03*
Y1054666D03*
Y1051319D03*
Y1047973D03*
Y1074744D03*
Y1071398D03*
Y1068051D03*
Y1064705D03*
Y1061359D03*
Y1088130D03*
Y1084784D03*
Y1081437D03*
Y1078091D03*
Y1104862D03*
Y1101516D03*
Y1098170D03*
Y1094823D03*
Y1091477D03*
Y1118248D03*
Y1114902D03*
Y1111555D03*
Y1108209D03*
Y1134981D03*
Y1131634D03*
Y1128288D03*
Y1124941D03*
Y1121595D03*
Y1148366D03*
Y1145020D03*
Y1141674D03*
Y1138327D03*
Y1165099D03*
Y1161752D03*
Y1158406D03*
Y1155059D03*
Y1151713D03*
Y1178485D03*
Y1175138D03*
Y1171792D03*
Y1168445D03*
Y1191870D03*
Y1188524D03*
Y1185177D03*
Y1181831D03*
Y1208603D03*
Y1205256D03*
Y1201910D03*
Y1198563D03*
Y1195217D03*
Y1221988D03*
Y1218642D03*
Y1215296D03*
Y1211949D03*
Y1238721D03*
Y1235374D03*
Y1232028D03*
Y1228681D03*
Y1225335D03*
Y1252107D03*
Y1248760D03*
Y1245414D03*
Y1242067D03*
Y1255453D03*
X1104866Y760177D03*
Y756831D03*
Y776910D03*
Y773563D03*
Y770217D03*
Y766870D03*
Y763524D03*
Y790296D03*
Y786949D03*
Y783603D03*
Y780256D03*
Y807028D03*
Y803681D03*
Y800335D03*
Y796988D03*
Y793642D03*
Y820414D03*
Y817067D03*
Y813721D03*
Y810374D03*
Y837146D03*
Y833799D03*
Y830453D03*
Y827107D03*
Y823760D03*
Y850532D03*
Y847185D03*
Y843839D03*
Y840492D03*
Y863918D03*
Y860571D03*
Y857225D03*
Y853878D03*
Y880650D03*
Y877303D03*
Y873957D03*
Y870610D03*
Y867264D03*
Y894036D03*
Y890689D03*
Y887343D03*
Y883996D03*
Y910768D03*
Y907422D03*
Y904075D03*
Y900729D03*
Y897382D03*
Y924154D03*
Y920807D03*
Y917461D03*
Y914114D03*
Y940886D03*
Y937540D03*
Y934193D03*
Y930847D03*
Y927500D03*
Y954272D03*
Y950925D03*
Y947579D03*
Y944233D03*
Y971004D03*
Y967658D03*
Y964311D03*
Y960965D03*
Y957618D03*
Y984390D03*
Y981044D03*
Y977697D03*
Y974351D03*
Y1001122D03*
Y997776D03*
Y994429D03*
Y991083D03*
Y987736D03*
Y1004469D03*
Y1027894D03*
Y1044626D03*
Y1041280D03*
Y1037933D03*
Y1034587D03*
Y1031240D03*
Y1058012D03*
Y1054666D03*
Y1051319D03*
Y1047973D03*
Y1074744D03*
Y1071398D03*
Y1068051D03*
Y1064705D03*
Y1061359D03*
Y1088130D03*
Y1084784D03*
Y1081437D03*
Y1078091D03*
Y1104862D03*
Y1101516D03*
Y1098170D03*
Y1094823D03*
Y1091477D03*
Y1118248D03*
Y1114902D03*
Y1111555D03*
Y1108209D03*
Y1134981D03*
Y1131634D03*
Y1128288D03*
Y1124941D03*
Y1121595D03*
Y1148366D03*
Y1145020D03*
Y1141674D03*
Y1138327D03*
Y1165099D03*
Y1161752D03*
Y1158406D03*
Y1155059D03*
Y1151713D03*
Y1178485D03*
Y1175138D03*
Y1171792D03*
Y1168445D03*
Y1191870D03*
Y1188524D03*
Y1185177D03*
Y1181831D03*
Y1208603D03*
Y1205256D03*
Y1201910D03*
Y1198563D03*
Y1195217D03*
Y1221988D03*
Y1218642D03*
Y1215296D03*
Y1211949D03*
Y1238721D03*
Y1235374D03*
Y1232028D03*
Y1228681D03*
Y1225335D03*
Y1252107D03*
Y1248760D03*
Y1245414D03*
Y1242067D03*
Y1255453D03*
X1121008Y760177D03*
Y756831D03*
Y776910D03*
Y773563D03*
Y770217D03*
Y766870D03*
Y763524D03*
Y790296D03*
Y786949D03*
Y783603D03*
Y780256D03*
Y807028D03*
Y803681D03*
Y800335D03*
Y796988D03*
Y793642D03*
Y820414D03*
Y817067D03*
Y813721D03*
Y810374D03*
Y837146D03*
Y833799D03*
Y830453D03*
Y827107D03*
Y823760D03*
Y850532D03*
Y847185D03*
Y843839D03*
Y840492D03*
Y863918D03*
Y860571D03*
Y857225D03*
Y853878D03*
Y880650D03*
Y877303D03*
Y873957D03*
Y870610D03*
Y867264D03*
Y894036D03*
Y890689D03*
Y887343D03*
Y883996D03*
Y910768D03*
Y907422D03*
Y904075D03*
Y900729D03*
Y897382D03*
Y924154D03*
Y920807D03*
Y917461D03*
Y914114D03*
Y940886D03*
Y937540D03*
Y934193D03*
Y930847D03*
Y927500D03*
Y954272D03*
Y950925D03*
Y947579D03*
Y944233D03*
Y971004D03*
Y967658D03*
Y964311D03*
Y960965D03*
Y957618D03*
Y984390D03*
Y981044D03*
Y977697D03*
Y974351D03*
Y1001122D03*
Y997776D03*
Y994429D03*
Y991083D03*
Y987736D03*
Y1004469D03*
Y1027894D03*
Y1044626D03*
Y1041280D03*
Y1037933D03*
Y1034587D03*
Y1031240D03*
Y1058012D03*
Y1054666D03*
Y1051319D03*
Y1047973D03*
Y1074744D03*
Y1071398D03*
Y1068051D03*
Y1064705D03*
Y1061359D03*
Y1088130D03*
Y1084784D03*
Y1081437D03*
Y1078091D03*
Y1104862D03*
Y1101516D03*
Y1098170D03*
Y1094823D03*
Y1091477D03*
Y1118248D03*
Y1114902D03*
Y1111555D03*
Y1108209D03*
Y1134981D03*
Y1131634D03*
Y1128288D03*
Y1124941D03*
Y1121595D03*
Y1148366D03*
Y1145020D03*
Y1141674D03*
Y1138327D03*
Y1165099D03*
Y1161752D03*
Y1158406D03*
Y1155059D03*
Y1151713D03*
Y1178485D03*
Y1175138D03*
Y1171792D03*
Y1168445D03*
Y1191870D03*
Y1188524D03*
Y1185177D03*
Y1181831D03*
Y1208603D03*
Y1205256D03*
Y1201910D03*
Y1198563D03*
Y1195217D03*
Y1221988D03*
Y1218642D03*
Y1215296D03*
Y1211949D03*
Y1238721D03*
Y1235374D03*
Y1232028D03*
Y1228681D03*
Y1225335D03*
Y1252107D03*
Y1248760D03*
Y1245414D03*
Y1242067D03*
Y1255453D03*
X1134567Y760177D03*
Y756831D03*
Y776910D03*
Y773563D03*
Y770217D03*
Y766870D03*
Y763524D03*
Y790296D03*
Y786949D03*
Y783603D03*
Y780256D03*
Y807028D03*
Y803681D03*
Y800335D03*
Y796988D03*
Y793642D03*
Y820414D03*
Y817067D03*
Y813721D03*
Y810374D03*
Y837146D03*
Y833799D03*
Y830453D03*
Y827107D03*
Y823760D03*
Y850532D03*
Y847185D03*
Y843839D03*
Y840492D03*
Y863918D03*
Y860571D03*
Y857225D03*
Y853878D03*
Y880650D03*
Y877303D03*
Y873957D03*
Y870610D03*
Y867264D03*
Y894036D03*
Y890689D03*
Y887343D03*
Y883996D03*
Y910768D03*
Y907422D03*
Y904075D03*
Y900729D03*
Y897382D03*
Y924154D03*
Y920807D03*
Y917461D03*
Y914114D03*
Y940886D03*
Y937540D03*
Y934193D03*
Y930847D03*
Y927500D03*
Y954272D03*
Y950925D03*
Y947579D03*
Y944233D03*
Y971004D03*
Y967658D03*
Y964311D03*
Y960965D03*
Y957618D03*
Y984390D03*
Y981044D03*
Y977697D03*
Y974351D03*
Y1001122D03*
Y997776D03*
Y994429D03*
Y991083D03*
Y987736D03*
Y1004469D03*
Y1027894D03*
Y1044626D03*
Y1041280D03*
Y1037933D03*
Y1034587D03*
Y1031240D03*
Y1058012D03*
Y1054666D03*
Y1051319D03*
Y1047973D03*
Y1074744D03*
Y1071398D03*
Y1068051D03*
Y1064705D03*
Y1061359D03*
Y1088130D03*
Y1084784D03*
Y1081437D03*
Y1078091D03*
Y1104862D03*
Y1101516D03*
Y1098170D03*
Y1094823D03*
Y1091477D03*
Y1118248D03*
Y1114902D03*
Y1111555D03*
Y1108209D03*
Y1134981D03*
Y1131634D03*
Y1128288D03*
Y1124941D03*
Y1121595D03*
Y1148366D03*
Y1145020D03*
Y1141674D03*
Y1138327D03*
Y1165099D03*
Y1161752D03*
Y1158406D03*
Y1155059D03*
Y1151713D03*
Y1178485D03*
Y1175138D03*
Y1171792D03*
Y1168445D03*
Y1191870D03*
Y1188524D03*
Y1185177D03*
Y1181831D03*
Y1208603D03*
Y1205256D03*
Y1201910D03*
Y1198563D03*
Y1195217D03*
Y1221988D03*
Y1218642D03*
Y1215296D03*
Y1211949D03*
Y1238721D03*
Y1235374D03*
Y1232028D03*
Y1228681D03*
Y1225335D03*
Y1252107D03*
Y1248760D03*
Y1245414D03*
Y1242067D03*
Y1255453D03*
X1150709Y760177D03*
Y756831D03*
Y776910D03*
Y773563D03*
Y770217D03*
Y766870D03*
Y763524D03*
Y790296D03*
Y786949D03*
Y783603D03*
Y780256D03*
Y807028D03*
Y803681D03*
Y800335D03*
Y796988D03*
Y793642D03*
Y820414D03*
Y817067D03*
Y813721D03*
Y810374D03*
Y837146D03*
Y833799D03*
Y830453D03*
Y827107D03*
Y823760D03*
Y850532D03*
Y847185D03*
Y843839D03*
Y840492D03*
Y863918D03*
Y860571D03*
Y857225D03*
Y853878D03*
Y880650D03*
Y877303D03*
Y873957D03*
Y870610D03*
Y867264D03*
Y894036D03*
Y890689D03*
Y887343D03*
Y883996D03*
Y910768D03*
Y907422D03*
Y904075D03*
Y900729D03*
Y897382D03*
Y924154D03*
Y920807D03*
Y917461D03*
Y914114D03*
Y940886D03*
Y937540D03*
Y934193D03*
Y930847D03*
Y927500D03*
Y954272D03*
Y950925D03*
Y947579D03*
Y944233D03*
Y971004D03*
Y967658D03*
Y964311D03*
Y960965D03*
Y957618D03*
Y984390D03*
Y981044D03*
Y977697D03*
Y974351D03*
Y1001122D03*
Y997776D03*
Y994429D03*
Y991083D03*
Y987736D03*
Y1004469D03*
Y1027894D03*
Y1044626D03*
Y1041280D03*
Y1037933D03*
Y1034587D03*
Y1031240D03*
Y1058012D03*
Y1054666D03*
Y1051319D03*
Y1047973D03*
Y1074744D03*
Y1071398D03*
Y1068051D03*
Y1064705D03*
Y1061359D03*
Y1088130D03*
Y1084784D03*
Y1081437D03*
Y1078091D03*
Y1104862D03*
Y1101516D03*
Y1098170D03*
Y1094823D03*
Y1091477D03*
Y1118248D03*
Y1114902D03*
Y1111555D03*
Y1108209D03*
Y1134981D03*
Y1131634D03*
Y1128288D03*
Y1124941D03*
Y1121595D03*
Y1148366D03*
Y1145020D03*
Y1141674D03*
Y1138327D03*
Y1165099D03*
Y1161752D03*
Y1158406D03*
Y1155059D03*
Y1151713D03*
Y1178485D03*
Y1175138D03*
Y1171792D03*
Y1168445D03*
Y1191870D03*
Y1188524D03*
Y1185177D03*
Y1181831D03*
Y1208603D03*
Y1205256D03*
Y1201910D03*
Y1198563D03*
Y1195217D03*
Y1221988D03*
Y1218642D03*
Y1215296D03*
Y1211949D03*
Y1238721D03*
Y1235374D03*
Y1232028D03*
Y1228681D03*
Y1225335D03*
Y1252107D03*
Y1248760D03*
Y1245414D03*
Y1242067D03*
Y1255453D03*
X1164268Y760177D03*
Y756831D03*
Y776910D03*
Y773563D03*
Y770217D03*
Y766870D03*
Y763524D03*
Y790296D03*
Y786949D03*
Y783603D03*
Y780256D03*
Y807028D03*
Y803681D03*
Y800335D03*
Y796988D03*
Y793642D03*
Y820414D03*
Y817067D03*
Y813721D03*
Y810374D03*
Y837146D03*
Y833799D03*
Y830453D03*
Y827107D03*
Y823760D03*
Y850532D03*
Y847185D03*
Y843839D03*
Y840492D03*
Y863918D03*
Y860571D03*
Y857225D03*
Y853878D03*
Y880650D03*
Y877303D03*
Y873957D03*
Y870610D03*
Y867264D03*
Y894036D03*
Y890689D03*
Y887343D03*
Y883996D03*
Y910768D03*
Y907422D03*
Y904075D03*
Y900729D03*
Y897382D03*
Y924154D03*
Y920807D03*
Y917461D03*
Y914114D03*
Y940886D03*
Y937540D03*
Y934193D03*
Y930847D03*
Y927500D03*
Y954272D03*
Y950925D03*
Y947579D03*
Y944233D03*
Y971004D03*
Y967658D03*
Y964311D03*
Y960965D03*
Y957618D03*
Y984390D03*
Y981044D03*
Y977697D03*
Y974351D03*
Y1001122D03*
Y997776D03*
Y994429D03*
Y991083D03*
Y987736D03*
Y1004469D03*
Y1027894D03*
Y1044626D03*
Y1041280D03*
Y1037933D03*
Y1034587D03*
Y1031240D03*
Y1058012D03*
Y1054666D03*
Y1051319D03*
Y1047973D03*
Y1074744D03*
Y1071398D03*
Y1068051D03*
Y1064705D03*
Y1061359D03*
Y1088130D03*
Y1084784D03*
Y1081437D03*
Y1078091D03*
Y1104862D03*
Y1101516D03*
Y1098170D03*
Y1094823D03*
Y1091477D03*
Y1118248D03*
Y1114902D03*
Y1111555D03*
Y1108209D03*
Y1134981D03*
Y1131634D03*
Y1128288D03*
Y1124941D03*
Y1121595D03*
Y1148366D03*
Y1145020D03*
Y1141674D03*
Y1138327D03*
Y1165099D03*
Y1161752D03*
Y1158406D03*
Y1155059D03*
Y1151713D03*
Y1178485D03*
Y1175138D03*
Y1171792D03*
Y1168445D03*
Y1191870D03*
Y1188524D03*
Y1185177D03*
Y1181831D03*
Y1208603D03*
Y1205256D03*
Y1201910D03*
Y1198563D03*
Y1195217D03*
Y1221988D03*
Y1218642D03*
Y1215296D03*
Y1211949D03*
Y1238721D03*
Y1235374D03*
Y1232028D03*
Y1228681D03*
Y1225335D03*
Y1252107D03*
Y1248760D03*
Y1245414D03*
Y1242067D03*
Y1255453D03*
X1180410Y760177D03*
Y756831D03*
Y776910D03*
Y773563D03*
Y770217D03*
Y766870D03*
Y763524D03*
Y790296D03*
Y786949D03*
Y783603D03*
Y780256D03*
Y807028D03*
Y803681D03*
Y800335D03*
Y796988D03*
Y793642D03*
Y820414D03*
Y817067D03*
Y813721D03*
Y810374D03*
Y837146D03*
Y833799D03*
Y830453D03*
Y827107D03*
Y823760D03*
Y850532D03*
Y847185D03*
Y843839D03*
Y840492D03*
Y863918D03*
Y860571D03*
Y857225D03*
Y853878D03*
Y880650D03*
Y877303D03*
Y873957D03*
Y870610D03*
Y867264D03*
Y894036D03*
Y890689D03*
Y887343D03*
Y883996D03*
Y910768D03*
Y907422D03*
Y904075D03*
Y900729D03*
Y897382D03*
Y924154D03*
Y920807D03*
Y917461D03*
Y914114D03*
Y940886D03*
Y937540D03*
Y934193D03*
Y930847D03*
Y927500D03*
Y954272D03*
Y950925D03*
Y947579D03*
Y944233D03*
Y971004D03*
Y967658D03*
Y964311D03*
Y960965D03*
Y957618D03*
Y984390D03*
Y981044D03*
Y977697D03*
Y974351D03*
Y1001122D03*
Y997776D03*
Y994429D03*
Y991083D03*
Y987736D03*
Y1004469D03*
Y1027894D03*
Y1044626D03*
Y1041280D03*
Y1037933D03*
Y1034587D03*
Y1031240D03*
Y1058012D03*
Y1054666D03*
Y1051319D03*
Y1047973D03*
Y1074744D03*
Y1071398D03*
Y1068051D03*
Y1064705D03*
Y1061359D03*
Y1088130D03*
Y1084784D03*
Y1081437D03*
Y1078091D03*
Y1104862D03*
Y1101516D03*
Y1098170D03*
Y1094823D03*
Y1091477D03*
Y1118248D03*
Y1114902D03*
Y1111555D03*
Y1108209D03*
Y1134981D03*
Y1131634D03*
Y1128288D03*
Y1124941D03*
Y1121595D03*
Y1148366D03*
Y1145020D03*
Y1141674D03*
Y1138327D03*
Y1165099D03*
Y1161752D03*
Y1158406D03*
Y1155059D03*
Y1151713D03*
Y1178485D03*
Y1175138D03*
Y1171792D03*
Y1168445D03*
Y1191870D03*
Y1188524D03*
Y1185177D03*
Y1181831D03*
Y1208603D03*
Y1205256D03*
Y1201910D03*
Y1198563D03*
Y1195217D03*
Y1221988D03*
Y1218642D03*
Y1215296D03*
Y1211949D03*
Y1238721D03*
Y1235374D03*
Y1232028D03*
Y1228681D03*
Y1225335D03*
Y1252107D03*
Y1248760D03*
Y1245414D03*
Y1242067D03*
Y1255453D03*
X1193969Y760177D03*
Y756831D03*
Y776910D03*
Y773563D03*
Y770217D03*
Y766870D03*
Y763524D03*
Y790296D03*
Y786949D03*
Y783603D03*
Y780256D03*
Y807028D03*
Y803681D03*
Y800335D03*
Y796988D03*
Y793642D03*
Y820414D03*
Y817067D03*
Y813721D03*
Y810374D03*
Y837146D03*
Y833799D03*
Y830453D03*
Y827107D03*
Y823760D03*
Y850532D03*
Y847185D03*
Y843839D03*
Y840492D03*
Y863918D03*
Y860571D03*
Y857225D03*
Y853878D03*
Y880650D03*
Y877303D03*
Y873957D03*
Y870610D03*
Y867264D03*
Y894036D03*
Y890689D03*
Y887343D03*
Y883996D03*
Y910768D03*
Y907422D03*
Y904075D03*
Y900729D03*
Y897382D03*
Y924154D03*
Y920807D03*
Y917461D03*
Y914114D03*
Y940886D03*
Y937540D03*
Y934193D03*
Y930847D03*
Y927500D03*
Y954272D03*
Y950925D03*
Y947579D03*
Y944233D03*
Y971004D03*
Y967658D03*
Y964311D03*
Y960965D03*
Y957618D03*
Y984390D03*
Y981044D03*
Y977697D03*
Y974351D03*
Y1001122D03*
Y997776D03*
Y994429D03*
Y991083D03*
Y987736D03*
Y1004469D03*
Y1027894D03*
Y1044626D03*
Y1041280D03*
Y1037933D03*
Y1034587D03*
Y1031240D03*
Y1058012D03*
Y1054666D03*
Y1051319D03*
Y1047973D03*
Y1074744D03*
Y1071398D03*
Y1068051D03*
Y1064705D03*
Y1061359D03*
Y1088130D03*
Y1084784D03*
Y1081437D03*
Y1078091D03*
Y1104862D03*
Y1101516D03*
Y1098170D03*
Y1094823D03*
Y1091477D03*
Y1118248D03*
Y1114902D03*
Y1111555D03*
Y1108209D03*
Y1134981D03*
Y1131634D03*
Y1128288D03*
Y1124941D03*
Y1121595D03*
Y1148366D03*
Y1145020D03*
Y1141674D03*
Y1138327D03*
Y1165099D03*
Y1161752D03*
Y1158406D03*
Y1155059D03*
Y1151713D03*
Y1178485D03*
Y1175138D03*
Y1171792D03*
Y1168445D03*
Y1191870D03*
Y1188524D03*
Y1185177D03*
Y1181831D03*
Y1208603D03*
Y1205256D03*
Y1201910D03*
Y1198563D03*
Y1195217D03*
Y1221988D03*
Y1218642D03*
Y1215296D03*
Y1211949D03*
Y1238721D03*
Y1235374D03*
Y1232028D03*
Y1228681D03*
Y1225335D03*
Y1252107D03*
Y1248760D03*
Y1245414D03*
Y1242067D03*
Y1255453D03*
X1210111Y760177D03*
Y756831D03*
Y776910D03*
Y773563D03*
Y770217D03*
Y766870D03*
Y763524D03*
Y790296D03*
Y786949D03*
Y783603D03*
Y780256D03*
Y807028D03*
Y803681D03*
Y800335D03*
Y796988D03*
Y793642D03*
Y820414D03*
Y817067D03*
Y813721D03*
Y810374D03*
Y837146D03*
Y833799D03*
Y830453D03*
Y827107D03*
Y823760D03*
Y850532D03*
Y847185D03*
Y843839D03*
Y840492D03*
Y863918D03*
Y860571D03*
Y857225D03*
Y853878D03*
Y880650D03*
Y877303D03*
Y873957D03*
Y870610D03*
Y867264D03*
Y894036D03*
Y890689D03*
Y887343D03*
Y883996D03*
Y910768D03*
Y907422D03*
Y904075D03*
Y900729D03*
Y897382D03*
Y924154D03*
Y920807D03*
Y917461D03*
Y914114D03*
Y940886D03*
Y937540D03*
Y934193D03*
Y930847D03*
Y927500D03*
Y954272D03*
Y950925D03*
Y947579D03*
Y944233D03*
Y971004D03*
Y967658D03*
Y964311D03*
Y960965D03*
Y957618D03*
Y984390D03*
Y981044D03*
Y977697D03*
Y974351D03*
Y1001122D03*
Y997776D03*
Y994429D03*
Y991083D03*
Y987736D03*
Y1004469D03*
Y1027894D03*
Y1044626D03*
Y1041280D03*
Y1037933D03*
Y1034587D03*
Y1031240D03*
Y1058012D03*
Y1054666D03*
Y1051319D03*
Y1047973D03*
Y1074744D03*
Y1071398D03*
Y1068051D03*
Y1064705D03*
Y1061359D03*
Y1088130D03*
Y1084784D03*
Y1081437D03*
Y1078091D03*
Y1104862D03*
Y1101516D03*
Y1098170D03*
Y1094823D03*
Y1091477D03*
Y1118248D03*
Y1114902D03*
Y1111555D03*
Y1108209D03*
Y1134981D03*
Y1131634D03*
Y1128288D03*
Y1124941D03*
Y1121595D03*
Y1148366D03*
Y1145020D03*
Y1141674D03*
Y1138327D03*
Y1165099D03*
Y1161752D03*
Y1158406D03*
Y1155059D03*
Y1151713D03*
Y1178485D03*
Y1175138D03*
Y1171792D03*
Y1168445D03*
Y1191870D03*
Y1188524D03*
Y1185177D03*
Y1181831D03*
Y1208603D03*
Y1205256D03*
Y1201910D03*
Y1198563D03*
Y1195217D03*
Y1221988D03*
Y1218642D03*
Y1215296D03*
Y1211949D03*
Y1238721D03*
Y1235374D03*
Y1232028D03*
Y1228681D03*
Y1225335D03*
Y1252107D03*
Y1248760D03*
Y1245414D03*
Y1242067D03*
Y1255453D03*
X1623496Y760177D03*
Y756831D03*
Y776910D03*
Y773563D03*
Y770217D03*
Y766870D03*
Y763524D03*
Y790296D03*
Y786949D03*
Y783603D03*
Y780256D03*
Y807028D03*
Y803681D03*
Y800335D03*
Y796988D03*
Y793642D03*
Y820414D03*
Y817067D03*
Y813721D03*
Y810374D03*
Y837146D03*
Y833799D03*
Y830453D03*
Y827107D03*
Y823760D03*
Y850532D03*
Y847185D03*
Y843839D03*
Y840492D03*
Y863918D03*
Y860571D03*
Y857225D03*
Y853878D03*
Y880650D03*
Y877303D03*
Y873957D03*
Y870610D03*
Y867264D03*
Y894036D03*
Y890689D03*
Y887343D03*
Y883996D03*
Y910768D03*
Y907422D03*
Y904075D03*
Y900729D03*
Y897382D03*
Y924154D03*
Y920807D03*
Y917461D03*
Y914114D03*
Y940886D03*
Y937540D03*
Y934193D03*
Y930847D03*
Y927500D03*
Y954272D03*
Y950925D03*
Y947579D03*
Y944233D03*
Y971004D03*
Y967658D03*
Y964311D03*
Y960965D03*
Y957618D03*
Y984390D03*
Y981044D03*
Y977697D03*
Y974351D03*
Y1001122D03*
Y997776D03*
Y994429D03*
Y991083D03*
Y987736D03*
Y1004469D03*
Y1027894D03*
Y1044626D03*
Y1041280D03*
Y1037933D03*
Y1034587D03*
Y1031240D03*
Y1058012D03*
Y1054666D03*
Y1051319D03*
Y1047973D03*
Y1074744D03*
Y1071398D03*
Y1068051D03*
Y1064705D03*
Y1061359D03*
Y1088130D03*
Y1084784D03*
Y1081437D03*
Y1078091D03*
Y1104862D03*
Y1101516D03*
Y1098170D03*
Y1094823D03*
Y1091477D03*
Y1118248D03*
Y1114902D03*
Y1111555D03*
Y1108209D03*
Y1134981D03*
Y1131634D03*
Y1128288D03*
Y1124941D03*
Y1121595D03*
Y1148366D03*
Y1145020D03*
Y1141674D03*
Y1138327D03*
Y1165099D03*
Y1161752D03*
Y1158406D03*
Y1155059D03*
Y1151713D03*
Y1178485D03*
Y1175138D03*
Y1171792D03*
Y1168445D03*
Y1191870D03*
Y1188524D03*
Y1185177D03*
Y1181831D03*
Y1208603D03*
Y1205256D03*
Y1201910D03*
Y1198563D03*
Y1195217D03*
Y1221988D03*
Y1218642D03*
Y1215296D03*
Y1211949D03*
Y1238721D03*
Y1235374D03*
Y1232028D03*
Y1228681D03*
Y1225335D03*
Y1252107D03*
Y1248760D03*
Y1245414D03*
Y1242067D03*
Y1255453D03*
X1639638Y760177D03*
Y756831D03*
Y776910D03*
Y773563D03*
Y770217D03*
Y766870D03*
Y763524D03*
Y790296D03*
Y786949D03*
Y783603D03*
Y780256D03*
Y807028D03*
Y803681D03*
Y800335D03*
Y796988D03*
Y793642D03*
Y820414D03*
Y817067D03*
Y813721D03*
Y810374D03*
Y837146D03*
Y833799D03*
Y830453D03*
Y827107D03*
Y823760D03*
Y850532D03*
Y847185D03*
Y843839D03*
Y840492D03*
Y863918D03*
Y860571D03*
Y857225D03*
Y853878D03*
Y880650D03*
Y877303D03*
Y873957D03*
Y870610D03*
Y867264D03*
Y894036D03*
Y890689D03*
Y887343D03*
Y883996D03*
Y910768D03*
Y907422D03*
Y904075D03*
Y900729D03*
Y897382D03*
Y924154D03*
Y920807D03*
Y917461D03*
Y914114D03*
Y940886D03*
Y937540D03*
Y934193D03*
Y930847D03*
Y927500D03*
Y954272D03*
Y950925D03*
Y947579D03*
Y944233D03*
Y971004D03*
Y967658D03*
Y964311D03*
Y960965D03*
Y957618D03*
Y984390D03*
Y981044D03*
Y977697D03*
Y974351D03*
Y1001122D03*
Y997776D03*
Y994429D03*
Y991083D03*
Y987736D03*
Y1004469D03*
Y1027894D03*
Y1044626D03*
Y1041280D03*
Y1037933D03*
Y1034587D03*
Y1031240D03*
Y1058012D03*
Y1054666D03*
Y1051319D03*
Y1047973D03*
Y1074744D03*
Y1071398D03*
Y1068051D03*
Y1064705D03*
Y1061359D03*
Y1088130D03*
Y1084784D03*
Y1081437D03*
Y1078091D03*
Y1104862D03*
Y1101516D03*
Y1098170D03*
Y1094823D03*
Y1091477D03*
Y1118248D03*
Y1114902D03*
Y1111555D03*
Y1108209D03*
Y1134981D03*
Y1131634D03*
Y1128288D03*
Y1124941D03*
Y1121595D03*
Y1148366D03*
Y1145020D03*
Y1141674D03*
Y1138327D03*
Y1165099D03*
Y1161752D03*
Y1158406D03*
Y1155059D03*
Y1151713D03*
Y1178485D03*
Y1175138D03*
Y1171792D03*
Y1168445D03*
Y1191870D03*
Y1188524D03*
Y1185177D03*
Y1181831D03*
Y1208603D03*
Y1205256D03*
Y1201910D03*
Y1198563D03*
Y1195217D03*
Y1221988D03*
Y1218642D03*
Y1215296D03*
Y1211949D03*
Y1238721D03*
Y1235374D03*
Y1232028D03*
Y1228681D03*
Y1225335D03*
Y1252107D03*
Y1248760D03*
Y1245414D03*
Y1242067D03*
Y1255453D03*
X1653197Y760177D03*
Y756831D03*
Y776910D03*
Y773563D03*
Y770217D03*
Y766870D03*
Y763524D03*
Y790296D03*
Y786949D03*
Y783603D03*
Y780256D03*
Y807028D03*
Y803681D03*
Y800335D03*
Y796988D03*
Y793642D03*
Y820414D03*
Y817067D03*
Y813721D03*
Y810374D03*
Y837146D03*
Y833799D03*
Y830453D03*
Y827107D03*
Y823760D03*
Y850532D03*
Y847185D03*
Y843839D03*
Y840492D03*
Y863918D03*
Y860571D03*
Y857225D03*
Y853878D03*
Y880650D03*
Y877303D03*
Y873957D03*
Y870610D03*
Y867264D03*
Y894036D03*
Y890689D03*
Y887343D03*
Y883996D03*
Y910768D03*
Y907422D03*
Y904075D03*
Y900729D03*
Y897382D03*
Y924154D03*
Y920807D03*
Y917461D03*
Y914114D03*
Y940886D03*
Y937540D03*
Y934193D03*
Y930847D03*
Y927500D03*
Y954272D03*
Y950925D03*
Y947579D03*
Y944233D03*
Y971004D03*
Y967658D03*
Y964311D03*
Y960965D03*
Y957618D03*
Y984390D03*
Y981044D03*
Y977697D03*
Y974351D03*
Y1001122D03*
Y997776D03*
Y994429D03*
Y991083D03*
Y987736D03*
Y1004469D03*
Y1027894D03*
Y1044626D03*
Y1041280D03*
Y1037933D03*
Y1034587D03*
Y1031240D03*
Y1058012D03*
Y1054666D03*
Y1051319D03*
Y1047973D03*
Y1074744D03*
Y1071398D03*
Y1068051D03*
Y1064705D03*
Y1061359D03*
Y1088130D03*
Y1084784D03*
Y1081437D03*
Y1078091D03*
Y1104862D03*
Y1101516D03*
Y1098170D03*
Y1094823D03*
Y1091477D03*
Y1118248D03*
Y1114902D03*
Y1111555D03*
Y1108209D03*
Y1134981D03*
Y1131634D03*
Y1128288D03*
Y1124941D03*
Y1121595D03*
Y1148366D03*
Y1145020D03*
Y1141674D03*
Y1138327D03*
Y1165099D03*
Y1161752D03*
Y1158406D03*
Y1155059D03*
Y1151713D03*
Y1178485D03*
Y1175138D03*
Y1171792D03*
Y1168445D03*
Y1191870D03*
Y1188524D03*
Y1185177D03*
Y1181831D03*
Y1208603D03*
Y1205256D03*
Y1201910D03*
Y1198563D03*
Y1195217D03*
Y1221988D03*
Y1218642D03*
Y1215296D03*
Y1211949D03*
Y1238721D03*
Y1235374D03*
Y1232028D03*
Y1228681D03*
Y1225335D03*
Y1252107D03*
Y1248760D03*
Y1245414D03*
Y1242067D03*
Y1255453D03*
X1669339Y760177D03*
Y756831D03*
Y776910D03*
Y773563D03*
Y770217D03*
Y766870D03*
Y763524D03*
Y790296D03*
Y786949D03*
Y783603D03*
Y780256D03*
Y807028D03*
Y803681D03*
Y800335D03*
Y796988D03*
Y793642D03*
Y820414D03*
Y817067D03*
Y813721D03*
Y810374D03*
Y837146D03*
Y833799D03*
Y830453D03*
Y827107D03*
Y823760D03*
Y850532D03*
Y847185D03*
Y843839D03*
Y840492D03*
Y863918D03*
Y860571D03*
Y857225D03*
Y853878D03*
Y880650D03*
Y877303D03*
Y873957D03*
Y870610D03*
Y867264D03*
Y894036D03*
Y890689D03*
Y887343D03*
Y883996D03*
Y910768D03*
Y907422D03*
Y904075D03*
Y900729D03*
Y897382D03*
Y924154D03*
Y920807D03*
Y917461D03*
Y914114D03*
Y940886D03*
Y937540D03*
Y934193D03*
Y930847D03*
Y927500D03*
Y954272D03*
Y950925D03*
Y947579D03*
Y944233D03*
Y971004D03*
Y967658D03*
Y964311D03*
Y960965D03*
Y957618D03*
Y984390D03*
Y981044D03*
Y977697D03*
Y974351D03*
Y1001122D03*
Y997776D03*
Y994429D03*
Y991083D03*
Y987736D03*
Y1004469D03*
Y1027894D03*
Y1044626D03*
Y1041280D03*
Y1037933D03*
Y1034587D03*
Y1031240D03*
Y1058012D03*
Y1054666D03*
Y1051319D03*
Y1047973D03*
Y1074744D03*
Y1071398D03*
Y1068051D03*
Y1064705D03*
Y1061359D03*
Y1088130D03*
Y1084784D03*
Y1081437D03*
Y1078091D03*
Y1104862D03*
Y1101516D03*
Y1098170D03*
Y1094823D03*
Y1091477D03*
Y1118248D03*
Y1114902D03*
Y1111555D03*
Y1108209D03*
Y1134981D03*
Y1131634D03*
Y1128288D03*
Y1124941D03*
Y1121595D03*
Y1148366D03*
Y1145020D03*
Y1141674D03*
Y1138327D03*
Y1165099D03*
Y1161752D03*
Y1158406D03*
Y1155059D03*
Y1151713D03*
Y1178485D03*
Y1175138D03*
Y1171792D03*
Y1168445D03*
Y1191870D03*
Y1188524D03*
Y1185177D03*
Y1181831D03*
Y1208603D03*
Y1205256D03*
Y1201910D03*
Y1198563D03*
Y1195217D03*
Y1221988D03*
Y1218642D03*
Y1215296D03*
Y1211949D03*
Y1238721D03*
Y1235374D03*
Y1232028D03*
Y1228681D03*
Y1225335D03*
Y1252107D03*
Y1248760D03*
Y1245414D03*
Y1242067D03*
Y1255453D03*
X1682898Y760177D03*
Y756831D03*
Y776910D03*
Y773563D03*
Y770217D03*
Y766870D03*
Y763524D03*
Y790296D03*
Y786949D03*
Y783603D03*
Y780256D03*
Y807028D03*
Y803681D03*
Y800335D03*
Y796988D03*
Y793642D03*
Y820414D03*
Y817067D03*
Y813721D03*
Y810374D03*
Y837146D03*
Y833799D03*
Y830453D03*
Y827107D03*
Y823760D03*
Y850532D03*
Y847185D03*
Y843839D03*
Y840492D03*
Y863918D03*
Y860571D03*
Y857225D03*
Y853878D03*
Y880650D03*
Y877303D03*
Y873957D03*
Y870610D03*
Y867264D03*
Y894036D03*
Y890689D03*
Y887343D03*
Y883996D03*
Y910768D03*
Y907422D03*
Y904075D03*
Y900729D03*
Y897382D03*
Y924154D03*
Y920807D03*
Y917461D03*
Y914114D03*
Y940886D03*
Y937540D03*
Y934193D03*
Y930847D03*
Y927500D03*
Y954272D03*
Y950925D03*
Y947579D03*
Y944233D03*
Y971004D03*
Y967658D03*
Y964311D03*
Y960965D03*
Y957618D03*
Y984390D03*
Y981044D03*
Y977697D03*
Y974351D03*
Y1001122D03*
Y997776D03*
Y994429D03*
Y991083D03*
Y987736D03*
Y1004469D03*
Y1027894D03*
Y1044626D03*
Y1041280D03*
Y1037933D03*
Y1034587D03*
Y1031240D03*
Y1058012D03*
Y1054666D03*
Y1051319D03*
Y1047973D03*
Y1074744D03*
Y1071398D03*
Y1068051D03*
Y1064705D03*
Y1061359D03*
Y1088130D03*
Y1084784D03*
Y1081437D03*
Y1078091D03*
Y1104862D03*
Y1101516D03*
Y1098170D03*
Y1094823D03*
Y1091477D03*
Y1118248D03*
Y1114902D03*
Y1111555D03*
Y1108209D03*
Y1134981D03*
Y1131634D03*
Y1128288D03*
Y1124941D03*
Y1121595D03*
Y1148366D03*
Y1145020D03*
Y1141674D03*
Y1138327D03*
Y1165099D03*
Y1161752D03*
Y1158406D03*
Y1155059D03*
Y1151713D03*
Y1178485D03*
Y1175138D03*
Y1171792D03*
Y1168445D03*
Y1191870D03*
Y1188524D03*
Y1185177D03*
Y1181831D03*
Y1208603D03*
Y1205256D03*
Y1201910D03*
Y1198563D03*
Y1195217D03*
Y1221988D03*
Y1218642D03*
Y1215296D03*
Y1211949D03*
Y1238721D03*
Y1235374D03*
Y1232028D03*
Y1228681D03*
Y1225335D03*
Y1252107D03*
Y1248760D03*
Y1245414D03*
Y1242067D03*
Y1255453D03*
X1699040Y760177D03*
Y756831D03*
Y776910D03*
Y773563D03*
Y770217D03*
Y766870D03*
Y763524D03*
Y790296D03*
Y786949D03*
Y783603D03*
Y780256D03*
Y807028D03*
Y803681D03*
Y800335D03*
Y796988D03*
Y793642D03*
Y820414D03*
Y817067D03*
Y813721D03*
Y810374D03*
Y837146D03*
Y833799D03*
Y830453D03*
Y827107D03*
Y823760D03*
Y850532D03*
Y847185D03*
Y843839D03*
Y840492D03*
Y863918D03*
Y860571D03*
Y857225D03*
Y853878D03*
Y880650D03*
Y877303D03*
Y873957D03*
Y870610D03*
Y867264D03*
Y894036D03*
Y890689D03*
Y887343D03*
Y883996D03*
Y910768D03*
Y907422D03*
Y904075D03*
Y900729D03*
Y897382D03*
Y924154D03*
Y920807D03*
Y917461D03*
Y914114D03*
Y940886D03*
Y937540D03*
Y934193D03*
Y930847D03*
Y927500D03*
Y954272D03*
Y950925D03*
Y947579D03*
Y944233D03*
Y971004D03*
Y967658D03*
Y964311D03*
Y960965D03*
Y957618D03*
Y984390D03*
Y981044D03*
Y977697D03*
Y974351D03*
Y1001122D03*
Y997776D03*
Y994429D03*
Y991083D03*
Y987736D03*
Y1004469D03*
Y1027894D03*
Y1044626D03*
Y1041280D03*
Y1037933D03*
Y1034587D03*
Y1031240D03*
Y1058012D03*
Y1054666D03*
Y1051319D03*
Y1047973D03*
Y1074744D03*
Y1071398D03*
Y1068051D03*
Y1064705D03*
Y1061359D03*
Y1088130D03*
Y1084784D03*
Y1081437D03*
Y1078091D03*
Y1104862D03*
Y1101516D03*
Y1098170D03*
Y1094823D03*
Y1091477D03*
Y1118248D03*
Y1114902D03*
Y1111555D03*
Y1108209D03*
Y1134981D03*
Y1131634D03*
Y1128288D03*
Y1124941D03*
Y1121595D03*
Y1148366D03*
Y1145020D03*
Y1141674D03*
Y1138327D03*
Y1165099D03*
Y1161752D03*
Y1158406D03*
Y1155059D03*
Y1151713D03*
Y1178485D03*
Y1175138D03*
Y1171792D03*
Y1168445D03*
Y1191870D03*
Y1188524D03*
Y1185177D03*
Y1181831D03*
Y1208603D03*
Y1205256D03*
Y1201910D03*
Y1198563D03*
Y1195217D03*
Y1221988D03*
Y1218642D03*
Y1215296D03*
Y1211949D03*
Y1238721D03*
Y1235374D03*
Y1232028D03*
Y1228681D03*
Y1225335D03*
Y1252107D03*
Y1248760D03*
Y1245414D03*
Y1242067D03*
Y1255453D03*
X1712599Y760177D03*
Y756831D03*
Y776910D03*
Y773563D03*
Y770217D03*
Y766870D03*
Y763524D03*
Y790296D03*
Y786949D03*
Y783603D03*
Y780256D03*
Y807028D03*
Y803681D03*
Y800335D03*
Y796988D03*
Y793642D03*
Y820414D03*
Y817067D03*
Y813721D03*
Y810374D03*
Y837146D03*
Y833799D03*
Y830453D03*
Y827107D03*
Y823760D03*
Y850532D03*
Y847185D03*
Y843839D03*
Y840492D03*
Y863918D03*
Y860571D03*
Y857225D03*
Y853878D03*
Y880650D03*
Y877303D03*
Y873957D03*
Y870610D03*
Y867264D03*
Y894036D03*
Y890689D03*
Y887343D03*
Y883996D03*
Y910768D03*
Y907422D03*
Y904075D03*
Y900729D03*
Y897382D03*
Y924154D03*
Y920807D03*
Y917461D03*
Y914114D03*
Y940886D03*
Y937540D03*
Y934193D03*
Y930847D03*
Y927500D03*
Y954272D03*
Y950925D03*
Y947579D03*
Y944233D03*
Y971004D03*
Y967658D03*
Y964311D03*
Y960965D03*
Y957618D03*
Y984390D03*
Y981044D03*
Y977697D03*
Y974351D03*
Y1001122D03*
Y997776D03*
Y994429D03*
Y991083D03*
Y987736D03*
Y1004469D03*
Y1027894D03*
Y1044626D03*
Y1041280D03*
Y1037933D03*
Y1034587D03*
Y1031240D03*
Y1058012D03*
Y1054666D03*
Y1051319D03*
Y1047973D03*
Y1074744D03*
Y1071398D03*
Y1068051D03*
Y1064705D03*
Y1061359D03*
Y1088130D03*
Y1084784D03*
Y1081437D03*
Y1078091D03*
Y1104862D03*
Y1101516D03*
Y1098170D03*
Y1094823D03*
Y1091477D03*
Y1118248D03*
Y1114902D03*
Y1111555D03*
Y1108209D03*
Y1134981D03*
Y1131634D03*
Y1128288D03*
Y1124941D03*
Y1121595D03*
Y1148366D03*
Y1145020D03*
Y1141674D03*
Y1138327D03*
Y1165099D03*
Y1161752D03*
Y1158406D03*
Y1155059D03*
Y1151713D03*
Y1178485D03*
Y1175138D03*
Y1171792D03*
Y1168445D03*
Y1191870D03*
Y1188524D03*
Y1185177D03*
Y1181831D03*
Y1208603D03*
Y1205256D03*
Y1201910D03*
Y1198563D03*
Y1195217D03*
Y1221988D03*
Y1218642D03*
Y1215296D03*
Y1211949D03*
Y1238721D03*
Y1235374D03*
Y1232028D03*
Y1228681D03*
Y1225335D03*
Y1252107D03*
Y1248760D03*
Y1245414D03*
Y1242067D03*
Y1255453D03*
X1728741Y760177D03*
Y756831D03*
Y776910D03*
Y773563D03*
Y770217D03*
Y766870D03*
Y763524D03*
Y790296D03*
Y786949D03*
Y783603D03*
Y780256D03*
Y807028D03*
Y803681D03*
Y800335D03*
Y796988D03*
Y793642D03*
Y820414D03*
Y817067D03*
Y813721D03*
Y810374D03*
Y837146D03*
Y833799D03*
Y830453D03*
Y827107D03*
Y823760D03*
Y850532D03*
Y847185D03*
Y843839D03*
Y840492D03*
Y863918D03*
Y860571D03*
Y857225D03*
Y853878D03*
Y880650D03*
Y877303D03*
Y873957D03*
Y870610D03*
Y867264D03*
Y894036D03*
Y890689D03*
Y887343D03*
Y883996D03*
Y910768D03*
Y907422D03*
Y904075D03*
Y900729D03*
Y897382D03*
Y924154D03*
Y920807D03*
Y917461D03*
Y914114D03*
Y940886D03*
Y937540D03*
Y934193D03*
Y930847D03*
Y927500D03*
Y954272D03*
Y950925D03*
Y947579D03*
Y944233D03*
Y971004D03*
Y967658D03*
Y964311D03*
Y960965D03*
Y957618D03*
Y984390D03*
Y981044D03*
Y977697D03*
Y974351D03*
Y1001122D03*
Y997776D03*
Y994429D03*
Y991083D03*
Y987736D03*
Y1004469D03*
Y1027894D03*
Y1044626D03*
Y1041280D03*
Y1037933D03*
Y1034587D03*
Y1031240D03*
Y1058012D03*
Y1054666D03*
Y1051319D03*
Y1047973D03*
Y1074744D03*
Y1071398D03*
Y1068051D03*
Y1064705D03*
Y1061359D03*
Y1088130D03*
Y1084784D03*
Y1081437D03*
Y1078091D03*
Y1104862D03*
Y1101516D03*
Y1098170D03*
Y1094823D03*
Y1091477D03*
Y1118248D03*
Y1114902D03*
Y1111555D03*
Y1108209D03*
Y1134981D03*
Y1131634D03*
Y1128288D03*
Y1124941D03*
Y1121595D03*
Y1148366D03*
Y1145020D03*
Y1141674D03*
Y1138327D03*
Y1165099D03*
Y1161752D03*
Y1158406D03*
Y1155059D03*
Y1151713D03*
Y1178485D03*
Y1175138D03*
Y1171792D03*
Y1168445D03*
Y1191870D03*
Y1188524D03*
Y1185177D03*
Y1181831D03*
Y1208603D03*
Y1205256D03*
Y1201910D03*
Y1198563D03*
Y1195217D03*
Y1221988D03*
Y1218642D03*
Y1215296D03*
Y1211949D03*
Y1238721D03*
Y1235374D03*
Y1232028D03*
Y1228681D03*
Y1225335D03*
Y1252107D03*
Y1248760D03*
Y1245414D03*
Y1242067D03*
Y1255453D03*
X1742300Y760177D03*
Y756831D03*
Y776910D03*
Y773563D03*
Y770217D03*
Y766870D03*
Y763524D03*
Y790296D03*
Y786949D03*
Y783603D03*
Y780256D03*
Y807028D03*
Y803681D03*
Y800335D03*
Y796988D03*
Y793642D03*
Y820414D03*
Y817067D03*
Y813721D03*
Y810374D03*
Y837146D03*
Y833799D03*
Y830453D03*
Y827107D03*
Y823760D03*
Y850532D03*
Y847185D03*
Y843839D03*
Y840492D03*
Y863918D03*
Y860571D03*
Y857225D03*
Y853878D03*
Y880650D03*
Y877303D03*
Y873957D03*
Y870610D03*
Y867264D03*
Y894036D03*
Y890689D03*
Y887343D03*
Y883996D03*
Y910768D03*
Y907422D03*
Y904075D03*
Y900729D03*
Y897382D03*
Y924154D03*
Y920807D03*
Y917461D03*
Y914114D03*
Y940886D03*
Y937540D03*
Y934193D03*
Y930847D03*
Y927500D03*
Y954272D03*
Y950925D03*
Y947579D03*
Y944233D03*
Y971004D03*
Y967658D03*
Y964311D03*
Y960965D03*
Y957618D03*
Y984390D03*
Y981044D03*
Y977697D03*
Y974351D03*
Y1001122D03*
Y997776D03*
Y994429D03*
Y991083D03*
Y987736D03*
Y1004469D03*
Y1027894D03*
Y1044626D03*
Y1041280D03*
Y1037933D03*
Y1034587D03*
Y1031240D03*
Y1058012D03*
Y1054666D03*
Y1051319D03*
Y1047973D03*
Y1074744D03*
Y1071398D03*
Y1068051D03*
Y1064705D03*
Y1061359D03*
Y1088130D03*
Y1084784D03*
Y1081437D03*
Y1078091D03*
Y1104862D03*
Y1101516D03*
Y1098170D03*
Y1094823D03*
Y1091477D03*
Y1118248D03*
Y1114902D03*
Y1111555D03*
Y1108209D03*
Y1134981D03*
Y1131634D03*
Y1128288D03*
Y1124941D03*
Y1121595D03*
Y1148366D03*
Y1145020D03*
Y1141674D03*
Y1138327D03*
Y1165099D03*
Y1161752D03*
Y1158406D03*
Y1155059D03*
Y1151713D03*
Y1178485D03*
Y1175138D03*
Y1171792D03*
Y1168445D03*
Y1191870D03*
Y1188524D03*
Y1185177D03*
Y1181831D03*
Y1208603D03*
Y1205256D03*
Y1201910D03*
Y1198563D03*
Y1195217D03*
Y1221988D03*
Y1218642D03*
Y1215296D03*
Y1211949D03*
Y1238721D03*
Y1235374D03*
Y1232028D03*
Y1228681D03*
Y1225335D03*
Y1252107D03*
Y1248760D03*
Y1245414D03*
Y1242067D03*
Y1255453D03*
X1758442Y760177D03*
Y756831D03*
Y776910D03*
Y773563D03*
Y770217D03*
Y766870D03*
Y763524D03*
Y790296D03*
Y786949D03*
Y783603D03*
Y780256D03*
Y807028D03*
Y803681D03*
Y800335D03*
Y796988D03*
Y793642D03*
Y820414D03*
Y817067D03*
Y813721D03*
Y810374D03*
Y837146D03*
Y833799D03*
Y830453D03*
Y827107D03*
Y823760D03*
Y850532D03*
Y847185D03*
Y843839D03*
Y840492D03*
Y863918D03*
Y860571D03*
Y857225D03*
Y853878D03*
Y880650D03*
Y877303D03*
Y873957D03*
Y870610D03*
Y867264D03*
Y894036D03*
Y890689D03*
Y887343D03*
Y883996D03*
Y910768D03*
Y907422D03*
Y904075D03*
Y900729D03*
Y897382D03*
Y924154D03*
Y920807D03*
Y917461D03*
Y914114D03*
Y940886D03*
Y937540D03*
Y934193D03*
Y930847D03*
Y927500D03*
Y954272D03*
Y950925D03*
Y947579D03*
Y944233D03*
Y971004D03*
Y967658D03*
Y964311D03*
Y960965D03*
Y957618D03*
Y984390D03*
Y981044D03*
Y977697D03*
Y974351D03*
Y1001122D03*
Y997776D03*
Y994429D03*
Y991083D03*
Y987736D03*
Y1004469D03*
Y1027894D03*
Y1044626D03*
Y1041280D03*
Y1037933D03*
Y1034587D03*
Y1031240D03*
Y1058012D03*
Y1054666D03*
Y1051319D03*
Y1047973D03*
Y1074744D03*
Y1071398D03*
Y1068051D03*
Y1064705D03*
Y1061359D03*
Y1088130D03*
Y1084784D03*
Y1081437D03*
Y1078091D03*
Y1104862D03*
Y1101516D03*
Y1098170D03*
Y1094823D03*
Y1091477D03*
Y1118248D03*
Y1114902D03*
Y1111555D03*
Y1108209D03*
Y1134981D03*
Y1131634D03*
Y1128288D03*
Y1124941D03*
Y1121595D03*
Y1148366D03*
Y1145020D03*
Y1141674D03*
Y1138327D03*
Y1165099D03*
Y1161752D03*
Y1158406D03*
Y1155059D03*
Y1151713D03*
Y1178485D03*
Y1175138D03*
Y1171792D03*
Y1168445D03*
Y1191870D03*
Y1188524D03*
Y1185177D03*
Y1181831D03*
Y1208603D03*
Y1205256D03*
Y1201910D03*
Y1198563D03*
Y1195217D03*
Y1221988D03*
Y1218642D03*
Y1215296D03*
Y1211949D03*
Y1238721D03*
Y1235374D03*
Y1232028D03*
Y1228681D03*
Y1225335D03*
Y1252107D03*
Y1248760D03*
Y1245414D03*
Y1242067D03*
Y1255453D03*
X1772000Y760177D03*
Y756831D03*
Y776910D03*
Y773563D03*
Y770217D03*
Y766870D03*
Y763524D03*
Y790296D03*
Y786949D03*
Y783603D03*
Y780256D03*
Y807028D03*
Y803681D03*
Y800335D03*
Y796988D03*
Y793642D03*
Y820414D03*
Y817067D03*
Y813721D03*
Y810374D03*
Y837146D03*
Y833799D03*
Y830453D03*
Y827107D03*
Y823760D03*
Y850532D03*
Y847185D03*
Y843839D03*
Y840492D03*
Y863918D03*
Y860571D03*
Y857225D03*
Y853878D03*
Y880650D03*
Y877303D03*
Y873957D03*
Y870610D03*
Y867264D03*
Y894036D03*
Y890689D03*
Y887343D03*
Y883996D03*
Y910768D03*
Y907422D03*
Y904075D03*
Y900729D03*
Y897382D03*
Y924154D03*
Y920807D03*
Y917461D03*
Y914114D03*
Y940886D03*
Y937540D03*
Y934193D03*
Y930847D03*
Y927500D03*
Y954272D03*
Y950925D03*
Y947579D03*
Y944233D03*
Y971004D03*
Y967658D03*
Y964311D03*
Y960965D03*
Y957618D03*
Y984390D03*
Y981044D03*
Y977697D03*
Y974351D03*
Y1001122D03*
Y997776D03*
Y994429D03*
Y991083D03*
Y987736D03*
Y1004469D03*
Y1027894D03*
Y1044626D03*
Y1041280D03*
Y1037933D03*
Y1034587D03*
Y1031240D03*
Y1058012D03*
Y1054666D03*
Y1051319D03*
Y1047973D03*
Y1074744D03*
Y1071398D03*
Y1068051D03*
Y1064705D03*
Y1061359D03*
Y1088130D03*
Y1084784D03*
Y1081437D03*
Y1078091D03*
Y1104862D03*
Y1101516D03*
Y1098170D03*
Y1094823D03*
Y1091477D03*
Y1118248D03*
Y1114902D03*
Y1111555D03*
Y1108209D03*
Y1134981D03*
Y1131634D03*
Y1128288D03*
Y1124941D03*
Y1121595D03*
Y1148366D03*
Y1145020D03*
Y1141674D03*
Y1138327D03*
Y1165099D03*
Y1161752D03*
Y1158406D03*
Y1155059D03*
Y1151713D03*
Y1178485D03*
Y1175138D03*
Y1171792D03*
Y1168445D03*
Y1191870D03*
Y1188524D03*
Y1185177D03*
Y1181831D03*
Y1208603D03*
Y1205256D03*
Y1201910D03*
Y1198563D03*
Y1195217D03*
Y1221988D03*
Y1218642D03*
Y1215296D03*
Y1211949D03*
Y1238721D03*
Y1235374D03*
Y1232028D03*
Y1228681D03*
Y1225335D03*
Y1252107D03*
Y1248760D03*
Y1245414D03*
Y1242067D03*
Y1255453D03*
X1788142Y760177D03*
Y756831D03*
Y776910D03*
Y773563D03*
Y770217D03*
Y766870D03*
Y763524D03*
Y790296D03*
Y786949D03*
Y783603D03*
Y780256D03*
Y807028D03*
Y803681D03*
Y800335D03*
Y796988D03*
Y793642D03*
Y820414D03*
Y817067D03*
Y813721D03*
Y810374D03*
Y837146D03*
Y833799D03*
Y830453D03*
Y827107D03*
Y823760D03*
Y850532D03*
Y847185D03*
Y843839D03*
Y840492D03*
Y863918D03*
Y860571D03*
Y857225D03*
Y853878D03*
Y880650D03*
Y877303D03*
Y873957D03*
Y870610D03*
Y867264D03*
Y894036D03*
Y890689D03*
Y887343D03*
Y883996D03*
Y910768D03*
Y907422D03*
Y904075D03*
Y900729D03*
Y897382D03*
Y924154D03*
Y920807D03*
Y917461D03*
Y914114D03*
Y940886D03*
Y937540D03*
Y934193D03*
Y930847D03*
Y927500D03*
Y954272D03*
Y950925D03*
Y947579D03*
Y944233D03*
Y971004D03*
Y967658D03*
Y964311D03*
Y960965D03*
Y957618D03*
Y984390D03*
Y981044D03*
Y977697D03*
Y974351D03*
Y1001122D03*
Y997776D03*
Y994429D03*
Y991083D03*
Y987736D03*
Y1004469D03*
Y1027894D03*
Y1044626D03*
Y1041280D03*
Y1037933D03*
Y1034587D03*
Y1031240D03*
Y1058012D03*
Y1054666D03*
Y1051319D03*
Y1047973D03*
Y1074744D03*
Y1071398D03*
Y1068051D03*
Y1064705D03*
Y1061359D03*
Y1088130D03*
Y1084784D03*
Y1081437D03*
Y1078091D03*
Y1104862D03*
Y1101516D03*
Y1098170D03*
Y1094823D03*
Y1091477D03*
Y1118248D03*
Y1114902D03*
Y1111555D03*
Y1108209D03*
Y1134981D03*
Y1131634D03*
Y1128288D03*
Y1124941D03*
Y1121595D03*
Y1148366D03*
Y1145020D03*
Y1141674D03*
Y1138327D03*
Y1165099D03*
Y1161752D03*
Y1158406D03*
Y1155059D03*
Y1151713D03*
Y1178485D03*
Y1175138D03*
Y1171792D03*
Y1168445D03*
Y1191870D03*
Y1188524D03*
Y1185177D03*
Y1181831D03*
Y1208603D03*
Y1205256D03*
Y1201910D03*
Y1198563D03*
Y1195217D03*
Y1221988D03*
Y1218642D03*
Y1215296D03*
Y1211949D03*
Y1238721D03*
Y1235374D03*
Y1232028D03*
Y1228681D03*
Y1225335D03*
Y1252107D03*
Y1248760D03*
Y1245414D03*
Y1242067D03*
Y1255453D03*
G54D293*
X1124186Y1546733D03*
X1119067D03*
X1121626D03*
X1119067Y1565237D03*
X1121626D03*
X1124186D03*
X1126745Y1546733D03*
Y1565237D03*
G54D149*
X313500Y247472D03*
X309760Y256528D03*
X317240D03*
X881000Y310972D03*
X877260Y320028D03*
X884740D03*
X1638500Y386972D03*
X1634760Y396028D03*
X1642240D03*
G36*
G01X791285Y1719440D02*
G02X791280Y1690339I-5J-14550D01*
G02X791275Y1719440I0J14551D01*
G01Y1712890D01*
G03X791280Y1696889I5J-8000D01*
G03X791285Y1712890I0J8001D01*
G01Y1719440D01*
G37*
G36*
G01X1066285D02*
G02X1066280Y1690339I-5J-14550D01*
G02X1066275Y1719440I0J14551D01*
G01Y1712890D01*
G03X1066280Y1696889I5J-8000D01*
G03X1066285Y1712890I0J8001D01*
G01Y1719440D01*
G37*
G54D239*
X746517Y126419D03*
X757935D03*
G54D257*
X829028Y491614D03*
Y486496D03*
X821588D03*
Y489055D03*
Y491614D03*
X931348Y267222D03*
Y272340D03*
X938788Y269781D03*
Y267222D03*
Y272340D03*
G54D266*
X887519Y1528191D03*
G54D167*
X404743Y483094D03*
X402184D03*
X399625D03*
Y490476D03*
X402184D03*
X404743D03*
X418543Y483017D03*
X415984D03*
X413425D03*
Y490399D03*
X415984D03*
X418543D03*
X432343Y482940D03*
X429784D03*
X427225D03*
Y490322D03*
X429784D03*
X432343D03*
G54D176*
X430520Y248768D03*
Y253768D03*
Y258768D03*
Y263768D03*
X450992Y253768D03*
Y248768D03*
Y263768D03*
Y258768D03*
X1133070Y1579453D03*
Y1584453D03*
Y1589453D03*
Y1594453D03*
X1153542Y1579453D03*
Y1594453D03*
Y1589453D03*
Y1584453D03*
X1205182Y431875D03*
Y436875D03*
Y441875D03*
Y446875D03*
X1225654Y431875D03*
Y446875D03*
Y441875D03*
Y436875D03*
X1217866Y455376D03*
Y460376D03*
Y465376D03*
Y470376D03*
X1238338Y460376D03*
Y455376D03*
Y470376D03*
Y465376D03*
G54D275*
X916889Y582573D03*
Y597073D03*
Y585132D03*
Y587692D03*
Y590251D03*
Y611573D03*
Y599632D03*
Y602192D03*
Y604751D03*
Y626073D03*
Y614132D03*
Y616692D03*
Y619251D03*
Y628632D03*
Y631192D03*
Y633751D03*
X931455Y582573D03*
Y597073D03*
Y590251D03*
Y587692D03*
Y585132D03*
Y611573D03*
Y604751D03*
Y602192D03*
Y599632D03*
Y626073D03*
Y619251D03*
Y616692D03*
Y614132D03*
Y633751D03*
Y631192D03*
Y628632D03*
G54D83*
X123811Y524366D03*
Y529484D03*
X130811D03*
Y526925D03*
Y524366D03*
X271500Y220441D03*
Y223000D03*
Y225559D03*
X278500D03*
Y220441D03*
X852500Y395559D03*
Y390441D03*
X845500D03*
Y393000D03*
Y395559D03*
G54D38*
X45951Y522792D03*
Y524760D03*
Y526729D03*
Y528697D03*
Y530666D03*
Y532634D03*
X60715Y522792D03*
Y532634D03*
Y530666D03*
Y528697D03*
Y526729D03*
Y524760D03*
X408943Y1605835D03*
Y1607804D03*
Y1609772D03*
Y1611741D03*
Y1613709D03*
Y1615678D03*
Y1617646D03*
Y1619615D03*
X427643Y1605835D03*
Y1607804D03*
Y1609772D03*
Y1611741D03*
Y1613709D03*
Y1615678D03*
Y1617646D03*
Y1619615D03*
X1116166Y1640051D03*
Y1642020D03*
Y1643988D03*
Y1645957D03*
Y1647925D03*
Y1649894D03*
Y1651862D03*
Y1653831D03*
X1134866Y1640051D03*
Y1642020D03*
Y1643988D03*
Y1645957D03*
Y1647925D03*
Y1649894D03*
Y1651862D03*
Y1653831D03*
G54D329*
X1900275Y-29973D03*
Y562227D03*
X1898799Y1208198D03*
Y1800398D03*
X1910275Y-29973D03*
Y562227D03*
X1908799Y1208198D03*
Y1800398D03*
X1921395Y-29963D03*
X1931395D03*
Y562237D03*
X1921395D03*
X1931395Y582237D03*
X1921395D03*
Y1174437D03*
X1931395D03*
X1929766Y1208160D03*
X1919766D03*
Y1800360D03*
X1929766D03*
X1942395Y-29783D03*
Y562417D03*
Y582417D03*
Y1174617D03*
X1940886Y1208170D03*
Y1800370D03*
X1952395Y-29783D03*
Y562417D03*
Y582417D03*
Y1174617D03*
X1950886Y1208170D03*
X1961856D03*
X1950886Y1800370D03*
X1961856D03*
X1963362Y-29821D03*
X1973362D03*
Y562379D03*
X1963362D03*
X1973362Y582379D03*
X1963362D03*
Y1174579D03*
X1973362D03*
X1971856Y1208170D03*
Y1800370D03*
X1984482Y-29811D03*
Y562389D03*
Y582389D03*
Y1174589D03*
X1982856Y1208350D03*
Y1800550D03*
X1994482Y-29811D03*
X2005452D03*
X1994482Y562389D03*
X2005452D03*
Y582389D03*
X1994482D03*
Y1174589D03*
X2005452D03*
X1992856Y1208350D03*
X2003823Y1208312D03*
X1992856Y1800550D03*
X2003823Y1800512D03*
X2015452Y-29811D03*
Y562389D03*
Y582389D03*
Y1174589D03*
X2013823Y1208312D03*
Y1800512D03*
X2036452Y-29631D03*
X2026452D03*
Y562569D03*
X2036452D03*
X2026452Y582569D03*
X2036452D03*
Y1174769D03*
X2026452D03*
X2047419Y-29669D03*
Y562531D03*
Y582531D03*
Y1174731D03*
X2057419Y-29669D03*
Y562531D03*
Y582531D03*
Y1174731D03*
X2068539Y582541D03*
X2078539D03*
Y1174741D03*
X2068539D03*
G54D74*
X113065Y1311630D03*
Y1345094D03*
X145665Y1311630D03*
Y1345094D03*
X178165Y1311630D03*
Y1345094D03*
X210765Y1311630D03*
Y1345094D03*
X243365Y1311630D03*
Y1345094D03*
X257991Y685023D03*
Y718487D03*
X277665Y1265484D03*
Y1298948D03*
X290721Y719264D03*
Y752728D03*
X310561Y1265399D03*
Y1298863D03*
X323491Y739414D03*
Y772878D03*
X343465Y1265399D03*
Y1298863D03*
X356551Y739326D03*
Y772790D03*
X375961Y1265456D03*
Y1298920D03*
X389591Y739214D03*
Y772678D03*
X408847Y1284930D03*
Y1318394D03*
X425562Y721429D03*
Y754893D03*
X457090Y696814D03*
Y730278D03*
X489462Y670314D03*
Y703778D03*
X522062Y636214D03*
Y669678D03*
X1084803Y1311611D03*
Y1345075D03*
X1117403Y1311611D03*
Y1345075D03*
X1150103Y1311611D03*
Y1345075D03*
X1183003Y1311611D03*
Y1345075D03*
X1215803Y1311611D03*
Y1345075D03*
X1253794Y1265465D03*
Y1298929D03*
X1286690Y1265380D03*
Y1298844D03*
X1319594Y1265380D03*
Y1298844D03*
X1352090Y1265437D03*
Y1298901D03*
X1368861Y654359D03*
Y687823D03*
X1384976Y1284911D03*
Y1318375D03*
X1401243Y687257D03*
Y720721D03*
X1433843Y719837D03*
Y753301D03*
X1466761Y739414D03*
Y772878D03*
X1499843Y739414D03*
Y772878D03*
X1532643Y739414D03*
Y772878D03*
X1567114Y717474D03*
Y750938D03*
X1600244Y683705D03*
Y717169D03*
X1633043Y664705D03*
Y698169D03*
G54D56*
X66229Y1542339D03*
X57370D03*
X59142D03*
X60914D03*
X62685D03*
X64457D03*
X73315D03*
X71544D03*
X69772D03*
X68000D03*
X94407Y151279D03*
X92438D03*
X90470D03*
X88501D03*
Y162303D03*
X90470D03*
X92438D03*
X94407D03*
X93113Y1542339D03*
X94885D03*
X96657D03*
X110081Y1376461D03*
X104766D03*
X108310D03*
X106538D03*
X111853D03*
X109058Y1542339D03*
X107287D03*
X105515D03*
X103743D03*
X101972D03*
X98428D03*
X100200D03*
X120711Y1376461D03*
X113625D03*
X117168D03*
X118940D03*
X115396D03*
X137366D03*
X140910D03*
X139138D03*
X153311D03*
X142681D03*
X146225D03*
X149768D03*
X144453D03*
X151540D03*
X147996D03*
X170066D03*
X186011D03*
X175381D03*
X178925D03*
X182468D03*
X173610D03*
X171838D03*
X177153D03*
X184240D03*
X180696D03*
X208281D03*
X202966D03*
X211825D03*
X215368D03*
X206510D03*
X204738D03*
X210053D03*
X213596D03*
X218911D03*
X217140D03*
X241081D03*
X235766D03*
X244625D03*
X239310D03*
X237538D03*
X242853D03*
X250345Y653656D03*
X252116D03*
X253888D03*
X255660D03*
X257431D03*
X259203D03*
X251711Y1376461D03*
X248168D03*
X249940D03*
X246396D03*
X266290Y653656D03*
X264518D03*
X262746D03*
X260975D03*
X274681Y1330315D03*
X269366D03*
X272910D03*
X271138D03*
X289206Y149291D03*
X287237D03*
X285269D03*
X283300D03*
Y160315D03*
X285269D03*
X287237D03*
X289206D03*
X283075Y687897D03*
X284846D03*
X286618D03*
X288390D03*
X290161D03*
X285311Y1330315D03*
X278225D03*
X281768D03*
X276453D03*
X283540D03*
X279996D03*
X299020Y687897D03*
X297248D03*
X295476D03*
X293705D03*
X291933D03*
X302262Y1330287D03*
X304034D03*
X315845Y708047D03*
X317616D03*
X319388D03*
X318207Y1330287D03*
X307577D03*
X311121D03*
X314664D03*
X305806D03*
X309349D03*
X316436D03*
X312892D03*
X321160Y708047D03*
X322931D03*
X331790D03*
X330018D03*
X328246D03*
X326475D03*
X324703D03*
X335166Y1330230D03*
X348905Y707779D03*
X340481Y1330230D03*
X344025D03*
X347568D03*
X338710D03*
X336938D03*
X342253D03*
X349340D03*
X345796D03*
X350676Y707779D03*
X352448D03*
X354220D03*
X355991D03*
X364850D03*
X363078D03*
X361306D03*
X359535D03*
X357763D03*
X351111Y1330230D03*
X373281Y1330430D03*
X367966D03*
X376825D03*
X371510D03*
X369738D03*
X375053D03*
X378596D03*
X381945Y707847D03*
X383716D03*
X385488D03*
X387260D03*
X389031D03*
X394346D03*
X392575D03*
X390803D03*
X383911Y1330430D03*
X380368D03*
X382140D03*
X397890Y707847D03*
X396118D03*
X405863Y1349761D03*
X400548D03*
X409407D03*
X404092D03*
X402320D03*
X407635D03*
X414945Y690047D03*
X416716D03*
X418488D03*
X420260D03*
X422031D03*
X423803D03*
X416493Y1349761D03*
X412950D03*
X414722D03*
X411178D03*
X430890Y690047D03*
X429118D03*
X427346D03*
X425575D03*
X447345Y665447D03*
X449116D03*
X450888D03*
X452660D03*
X454431D03*
X463290D03*
X461518D03*
X459746D03*
X457975D03*
X456203D03*
X479945Y638947D03*
X481716D03*
X483488D03*
X485260D03*
X487031D03*
X495890D03*
X494118D03*
X492346D03*
X490575D03*
X488803D03*
X513245Y604847D03*
X515016D03*
X516788D03*
X518560D03*
X520331D03*
X529190D03*
X527418D03*
X525646D03*
X523875D03*
X522103D03*
X613182Y219365D03*
X611213D03*
X609245D03*
X607276D03*
Y230389D03*
X609245D03*
X611213D03*
X613182D03*
X717637Y1394470D03*
X712322D03*
X721181D03*
X715866D03*
X714094D03*
X719409D03*
X722952D03*
X728267D03*
X724724D03*
X726496D03*
X750419Y1394570D03*
X745104D03*
X748648D03*
X746876D03*
X752191D03*
X761049D03*
X753963D03*
X757506D03*
X759278D03*
X755734D03*
X826467Y131386D03*
X824498D03*
X822530D03*
X820561D03*
Y142410D03*
X822530D03*
X824498D03*
X826467D03*
X850432Y208879D03*
X848463D03*
X846495D03*
X844526D03*
Y219903D03*
X846495D03*
X848463D03*
X850432D03*
X1076504Y1376442D03*
X1080048D03*
X1078276D03*
X1092449D03*
X1081819D03*
X1085363D03*
X1088906D03*
X1083591D03*
X1090678D03*
X1087134D03*
X1109104D03*
X1125049D03*
X1114419D03*
X1117963D03*
X1121506D03*
X1112648D03*
X1110876D03*
X1116191D03*
X1123278D03*
X1119734D03*
X1147119D03*
X1141804D03*
X1150663D03*
X1154206D03*
X1145348D03*
X1143576D03*
X1148891D03*
X1152434D03*
X1157749D03*
X1155978D03*
X1180019D03*
X1174704D03*
X1183563D03*
X1178248D03*
X1176476D03*
X1181791D03*
X1190649D03*
X1187106D03*
X1188878D03*
X1185334D03*
X1212819D03*
X1207504D03*
X1211048D03*
X1209276D03*
X1214591D03*
X1223449D03*
X1216363D03*
X1219906D03*
X1221678D03*
X1218134D03*
X1250810Y1330296D03*
X1245495D03*
X1254354D03*
X1257897D03*
X1249039D03*
X1247267D03*
X1252582D03*
X1259669D03*
X1256125D03*
X1261440D03*
X1282855Y401213D03*
X1280886D03*
X1278918D03*
X1276949D03*
Y412237D03*
X1278918D03*
X1280886D03*
X1282855D03*
X1283706Y1330268D03*
X1278391D03*
X1287250D03*
X1281935D03*
X1280163D03*
X1285478D03*
X1289021D03*
X1294336D03*
X1290793D03*
X1292565D03*
X1316610Y1330211D03*
X1311295D03*
X1314839D03*
X1313067D03*
X1318382D03*
X1327240D03*
X1320154D03*
X1323697D03*
X1325469D03*
X1321925D03*
X1344095Y1330411D03*
X1347639D03*
X1345867D03*
X1360897Y622990D03*
X1362668D03*
X1360040Y1330411D03*
X1349410D03*
X1352954D03*
X1356497D03*
X1351182D03*
X1358269D03*
X1354725D03*
X1364440Y622990D03*
X1366212D03*
X1367983D03*
X1376842D03*
X1375070D03*
X1373298D03*
X1371527D03*
X1369755D03*
X1376677Y1349742D03*
X1378449D03*
X1393597Y655890D03*
X1392622Y1349742D03*
X1381992D03*
X1385536D03*
X1389079D03*
X1380221D03*
X1383764D03*
X1390851D03*
X1387307D03*
X1395368Y655890D03*
X1397140D03*
X1398912D03*
X1400683D03*
X1407770D03*
X1405998D03*
X1404227D03*
X1402455D03*
X1409542D03*
X1426197Y688470D03*
X1427968D03*
X1429740D03*
X1431512D03*
X1433283D03*
X1438598D03*
X1436827D03*
X1435055D03*
X1442142D03*
X1440370D03*
X1459115Y708047D03*
X1460886D03*
X1462658D03*
X1464430D03*
X1466201D03*
X1467973D03*
X1475060D03*
X1473288D03*
X1471516D03*
X1469745D03*
X1492197Y708215D03*
X1493968D03*
X1495740D03*
X1497512D03*
X1499283D03*
X1508142D03*
X1506370D03*
X1504598D03*
X1502827D03*
X1501055D03*
X1524997Y708047D03*
X1526768D03*
X1528540D03*
X1530312D03*
X1532083D03*
X1540942D03*
X1539170D03*
X1537398D03*
X1535627D03*
X1533855D03*
X1557201Y294904D03*
X1555233D03*
X1553264D03*
Y305928D03*
X1555233D03*
X1557201D03*
X1559170Y294904D03*
Y305928D03*
X1558127Y686107D03*
X1559898D03*
X1561670D03*
X1563442D03*
X1565213D03*
X1572300D03*
X1570528D03*
X1568757D03*
X1566985D03*
X1574072D03*
X1590897Y652338D03*
X1592668D03*
X1594440D03*
X1596212D03*
X1597983D03*
X1601527D03*
X1599755D03*
X1606842D03*
X1605070D03*
X1603298D03*
X1623897Y633338D03*
X1625668D03*
X1627440D03*
X1629212D03*
X1630983D03*
X1639842D03*
X1638070D03*
X1636298D03*
X1634527D03*
X1632755D03*
X1660055Y1393759D03*
X1661827D03*
X1676000D03*
X1665370D03*
X1668914D03*
X1672457D03*
X1663599D03*
X1667142D03*
X1674229D03*
X1670685D03*
X1692026Y1680733D03*
X1690057D03*
X1686120D03*
X1688089D03*
X1686120Y1691757D03*
X1692026D03*
X1688089D03*
X1690057D03*
X1698152Y1393859D03*
X1692837D03*
X1701696D03*
X1705239D03*
X1696381D03*
X1694609D03*
X1699924D03*
X1707011D03*
X1703467D03*
X1708782D03*
X1735976Y364872D03*
X1734008D03*
X1732039D03*
Y375896D03*
X1734008D03*
X1735976D03*
X1737945Y364872D03*
Y375896D03*
X1744653Y1575375D03*
X1746425D03*
X1748197D03*
X1749968D03*
X1751740D03*
X1760598D03*
X1758827D03*
X1757055D03*
X1755283D03*
X1753512D03*
X1780396D03*
X1796341D03*
X1794570D03*
X1792798D03*
X1791026D03*
X1789255D03*
X1782168D03*
X1783940D03*
X1785711D03*
X1787483D03*
G54D65*
X79729Y289822D03*
Y310256D03*
X89729Y289822D03*
Y310256D03*
X757184Y1702772D03*
Y1712772D03*
X1072863Y1409176D03*
Y1419176D03*
X1080970Y1640958D03*
Y1650958D03*
X1299439Y102812D03*
Y112812D03*
X1530377Y581353D03*
X1540377D03*
G54D92*
X129932Y1669725D03*
Y1671300D03*
Y1666575D03*
Y1668150D03*
Y1674449D03*
Y1672874D03*
Y1677599D03*
Y1676024D03*
G54D158*
X373673Y-28871D03*
Y-18871D03*
D03*
Y-8871D03*
X398673Y-28871D03*
Y-18871D03*
D03*
Y-8871D03*
X718093Y-28871D03*
Y-18871D03*
D03*
Y-8871D03*
X743093Y-28871D03*
Y-18871D03*
D03*
Y-8871D03*
X825152Y-35011D03*
Y-25011D03*
Y-15011D03*
Y-25011D03*
Y-15011D03*
Y-5011D03*
D03*
Y4989D03*
Y14989D03*
D03*
Y4989D03*
Y24989D03*
X850152Y-35011D03*
Y-25011D03*
Y-15011D03*
Y-25011D03*
Y-15011D03*
Y-5011D03*
D03*
Y4989D03*
Y14989D03*
D03*
Y4989D03*
Y24989D03*
X1169572Y-35011D03*
Y-15011D03*
Y-25011D03*
D03*
Y-15011D03*
Y-5011D03*
D03*
Y4989D03*
Y14989D03*
Y4989D03*
Y14989D03*
Y24989D03*
X1194572Y-35011D03*
Y-15011D03*
Y-25011D03*
D03*
Y-15011D03*
Y-5011D03*
D03*
Y4989D03*
Y14989D03*
Y4989D03*
Y14989D03*
Y24989D03*
X1228672Y-35011D03*
Y-25011D03*
Y-15011D03*
Y-25011D03*
Y-15011D03*
Y-5011D03*
D03*
Y4989D03*
Y14989D03*
D03*
Y4989D03*
Y24989D03*
X1253672Y-35011D03*
Y-25011D03*
Y-15011D03*
Y-25011D03*
Y-15011D03*
Y-5011D03*
D03*
Y4989D03*
Y14989D03*
D03*
Y4989D03*
Y24989D03*
X1428431Y-35011D03*
Y-15011D03*
Y-25011D03*
D03*
Y-15011D03*
Y-5011D03*
D03*
Y4989D03*
Y14989D03*
Y4989D03*
Y14989D03*
Y24989D03*
X1453431Y-35011D03*
Y-15011D03*
Y-25011D03*
D03*
Y-15011D03*
Y-5011D03*
D03*
Y4989D03*
Y14989D03*
Y4989D03*
Y14989D03*
Y24989D03*
X1521966Y-29212D03*
D03*
Y-39212D03*
Y-19212D03*
X1546966Y-29212D03*
D03*
Y-39212D03*
Y-19212D03*
X1721725Y-29212D03*
Y-39212D03*
Y-29212D03*
Y-19212D03*
X1746725Y-29212D03*
Y-39212D03*
Y-29212D03*
Y-19212D03*
G54D29*
X35852Y670445D03*
Y667045D03*
Y681410D03*
Y678010D03*
Y692316D03*
Y703222D03*
Y688916D03*
Y699822D03*
X49212Y451602D03*
X45812D03*
X50880Y1415563D03*
Y1418963D03*
X58349Y1406331D03*
Y1409731D03*
X90965Y960966D03*
X120666D03*
X150366D03*
X154945Y1624350D03*
Y1627750D03*
X142576Y1640163D03*
Y1643563D03*
X163735Y1635369D03*
Y1631969D03*
X180067Y960966D03*
X194196Y1602380D03*
X197596D03*
X194196Y1614292D03*
X197596D03*
X193679Y1640052D03*
Y1643452D03*
X209768Y960966D03*
X206256Y1602380D03*
X209656D03*
X206256Y1614292D03*
X209656D03*
X205479Y1652130D03*
Y1648730D03*
X218316Y1602380D03*
X230376D03*
X221716D03*
X218316Y1614292D03*
X230376D03*
X221716D03*
X242436Y1602380D03*
X233776D03*
X245836D03*
X242436Y1614292D03*
X233776D03*
X245836D03*
X254496Y1602380D03*
X257896D03*
X254496Y1614292D03*
X257896D03*
X266556Y1602380D03*
X269956D03*
X266556Y1614292D03*
X269956D03*
X278616Y1602380D03*
X290676D03*
X282016D03*
X278616Y1614292D03*
X290676D03*
X282016D03*
X302736Y1602380D03*
X294076D03*
X306136D03*
X302736Y1614292D03*
X294076D03*
X306136D03*
X297323Y1657172D03*
Y1653772D03*
X313284Y1218522D03*
Y1215122D03*
X314796Y1602380D03*
X318196D03*
X314796Y1614292D03*
X318196D03*
X307255Y1643750D03*
Y1647150D03*
X326856Y1602380D03*
X330256D03*
X326856Y1614292D03*
X330256D03*
X338916Y1602380D03*
X350976D03*
X342316D03*
X338916Y1614292D03*
X350976D03*
X342316D03*
X363036Y1602380D03*
X354376D03*
X363036Y1614292D03*
X354376D03*
X372126Y1214455D03*
X368726D03*
X375096Y1602380D03*
X366436D03*
X378496D03*
X375096Y1614292D03*
X366436D03*
X378496D03*
X390841Y-15571D03*
Y-12171D03*
X390974Y1222849D03*
Y1219449D03*
X388630Y1236747D03*
Y1240147D03*
X458369Y1602380D03*
X461769D03*
X458369Y1614292D03*
X461769D03*
X470429Y1602380D03*
X482489D03*
X473829D03*
X470429Y1614292D03*
X482489D03*
X473829D03*
X494549Y1602380D03*
X485889D03*
X497949D03*
X494549Y1614292D03*
X485889D03*
X497949D03*
X506609Y1602380D03*
X510009D03*
X506609Y1614292D03*
X510009D03*
X518669Y1602380D03*
X522069D03*
X518669Y1614292D03*
X522069D03*
X530729Y1602380D03*
X542789D03*
X534129D03*
X530729Y1614292D03*
X542789D03*
X534129D03*
X554849Y1602380D03*
X546189D03*
X558249D03*
X554849Y1614292D03*
X546189D03*
X558249D03*
X566909Y1602380D03*
X570309D03*
X566909Y1614292D03*
X570309D03*
X578969Y1602380D03*
X582369D03*
X578969Y1614292D03*
X582369D03*
X591029Y1602380D03*
X603089D03*
X594429D03*
X591029Y1614292D03*
X603089D03*
X594429D03*
X615149Y1602380D03*
X606489D03*
X618549D03*
X615149Y1614292D03*
X606489D03*
X618549D03*
X627209Y1602380D03*
X630609D03*
X627209Y1614292D03*
X630609D03*
X639269Y1602380D03*
X642669D03*
X639269Y1614292D03*
X642669D03*
X687697Y960966D03*
X717398D03*
X725925Y-15571D03*
Y-12171D03*
X747099Y960966D03*
X776800D03*
X806500D03*
X842320Y-11711D03*
Y-8311D03*
Y11689D03*
Y8289D03*
X1067107Y960965D03*
X1096808D03*
X1126508D03*
X1156209D03*
X1177404Y-11711D03*
Y-8311D03*
Y11689D03*
Y8289D03*
X1185910Y960965D03*
X1202069Y1635380D03*
X1214129D03*
X1205469D03*
X1202069Y1647292D03*
X1214129D03*
X1205469D03*
X1226189Y1635380D03*
X1217529D03*
X1229589D03*
X1226189Y1647292D03*
X1217529D03*
X1229589D03*
X1238249Y1635380D03*
X1241649D03*
X1238249Y1647292D03*
X1241649D03*
X1245840Y-28311D03*
Y-31711D03*
Y11689D03*
Y8289D03*
X1250309Y1635380D03*
X1253709D03*
X1250309Y1647292D03*
X1253709D03*
X1262369Y1635380D03*
X1274429D03*
X1265769D03*
X1262369Y1647292D03*
X1274429D03*
X1265769D03*
X1286489Y1635380D03*
X1277829D03*
X1289889D03*
X1286489Y1647292D03*
X1277829D03*
X1289889D03*
X1298549Y1635380D03*
X1301949D03*
X1298549Y1647292D03*
X1301949D03*
X1315657Y1199532D03*
Y1196132D03*
X1310609Y1635380D03*
X1314009D03*
X1310609Y1647292D03*
X1314009D03*
X1322669Y1635380D03*
X1334729D03*
X1326069D03*
X1322669Y1647292D03*
X1334729D03*
X1326069D03*
X1342036Y1206429D03*
Y1203029D03*
X1346063Y1217729D03*
Y1214329D03*
X1346789Y1635380D03*
X1338129D03*
X1346789Y1647292D03*
X1338129D03*
X1358849Y1635380D03*
X1350189D03*
X1362249D03*
X1358849Y1647292D03*
X1350189D03*
X1362249D03*
X1370685Y1223032D03*
Y1226432D03*
X1370909Y1635380D03*
X1374309D03*
X1370909Y1647292D03*
X1374309D03*
X1382969Y1635380D03*
X1386369D03*
X1382969Y1647292D03*
X1386369D03*
X1436263Y-28311D03*
Y-31711D03*
Y11689D03*
Y8289D03*
X1466243Y1635380D03*
Y1647292D03*
X1478303Y1635380D03*
X1469643D03*
X1481703D03*
X1478303Y1647292D03*
X1469643D03*
X1481703D03*
X1490363Y1635380D03*
X1493763D03*
X1490363Y1647292D03*
X1493763D03*
X1502423Y1635380D03*
X1505823D03*
X1502423Y1647292D03*
X1505823D03*
X1514483Y1635380D03*
X1526543D03*
X1517883D03*
X1514483Y1647292D03*
X1526543D03*
X1517883D03*
X1539134Y-35912D03*
Y-32512D03*
X1538603Y1635380D03*
X1529943D03*
X1542003D03*
X1538603Y1647292D03*
X1529943D03*
X1542003D03*
X1550663Y1635380D03*
X1554063D03*
X1550663Y1647292D03*
X1554063D03*
X1562723Y1635380D03*
X1566123D03*
X1562723Y1647292D03*
X1566123D03*
X1586843Y1635380D03*
X1574783D03*
X1578183D03*
X1586843Y1647292D03*
X1574783D03*
X1578183D03*
X1598903Y1635380D03*
X1590243D03*
X1602303D03*
X1598903Y1647292D03*
X1590243D03*
X1602303D03*
X1610963Y1635380D03*
X1614363D03*
X1610963Y1647292D03*
X1614363D03*
X1623023Y1635380D03*
X1626423D03*
X1623023Y1647292D03*
X1626423D03*
X1635083Y1635380D03*
X1647143D03*
X1638483D03*
X1635083Y1647292D03*
X1647143D03*
X1638483D03*
X1650543Y1635380D03*
Y1647292D03*
X1663839Y960965D03*
X1693540D03*
X1729557Y-35912D03*
Y-32512D03*
X1723241Y960965D03*
X1752942D03*
X1782642D03*
G54D185*
X473445Y288569D03*
X560445Y297569D03*
G54D339*
G01X-476840Y-884638D02*
Y2768362D01*
X5911000D01*
Y-884638D01*
X-476840D01*
G01X8000Y-625138D02*
Y-630138D01*
G01X6543Y-625138D02*
X9457D01*
G01X14367Y-630138D02*
X11833D01*
Y-625138D01*
X14367D01*
G01X13353Y-627555D02*
X11833D01*
G01X16933Y-625138D02*
Y-630138D01*
X19467D01*
G01X23300Y-630305D02*
X23173Y-630221D01*
Y-630055D01*
X23300Y-629971D01*
X23427Y-630055D01*
Y-630221D01*
X23300Y-630305D01*
G01Y-628055D02*
X23173Y-627971D01*
Y-627805D01*
X23300Y-627721D01*
X23427Y-627805D01*
Y-627971D01*
X23300Y-628055D01*
G01X28083Y-631805D02*
X27450Y-630971D01*
X27133Y-630138D01*
Y-626805D01*
X27450Y-625971D01*
X28083Y-625138D01*
G01X33500D02*
X32993Y-625305D01*
X32613Y-625721D01*
X32360Y-626221D01*
X32170Y-626888D01*
X32107Y-627638D01*
X32170Y-628388D01*
X32360Y-629055D01*
X32613Y-629555D01*
X32993Y-629971D01*
X33500Y-630138D01*
X34007Y-629971D01*
X34387Y-629555D01*
X34640Y-629055D01*
X34830Y-628388D01*
X34893Y-627638D01*
X34830Y-626888D01*
X34640Y-626221D01*
X34387Y-625721D01*
X34007Y-625305D01*
X33500Y-625138D01*
G01X37207Y-629138D02*
X37587Y-629721D01*
X38093Y-630055D01*
X38663Y-630138D01*
X39170Y-630055D01*
X39677Y-629638D01*
X39993Y-629138D01*
X40057Y-628638D01*
X39930Y-628055D01*
X39487Y-627638D01*
X39043Y-627471D01*
X38473D01*
G01X39043D02*
X39423Y-627221D01*
X39740Y-626805D01*
X39867Y-626305D01*
X39740Y-625805D01*
X39423Y-625388D01*
X38853Y-625138D01*
X38283Y-625221D01*
X37713Y-625555D01*
G01X44017Y-631805D02*
X44650Y-630971D01*
X44967Y-630138D01*
Y-626805D01*
X44650Y-625971D01*
X44017Y-625138D01*
G01X47407Y-629138D02*
X47787Y-629721D01*
X48293Y-630055D01*
X48863Y-630138D01*
X49370Y-630055D01*
X49877Y-629638D01*
X50193Y-629138D01*
X50257Y-628638D01*
X50130Y-628055D01*
X49687Y-627638D01*
X49243Y-627471D01*
X48673D01*
G01X49243D02*
X49623Y-627221D01*
X49940Y-626805D01*
X50067Y-626305D01*
X49940Y-625805D01*
X49623Y-625388D01*
X49053Y-625138D01*
X48483Y-625221D01*
X47913Y-625555D01*
G01X52697Y-625971D02*
X53077Y-625471D01*
X53520Y-625221D01*
X54027Y-625138D01*
X54660Y-625305D01*
X55103Y-625721D01*
X55230Y-626221D01*
X55167Y-626721D01*
X54913Y-627138D01*
X53647Y-627971D01*
X53077Y-628555D01*
X52697Y-629388D01*
X52570Y-630138D01*
X55230D01*
G01X58873D02*
X59000Y-629055D01*
X59190Y-628138D01*
X59443Y-627305D01*
X59760Y-626388D01*
X60267Y-625138D01*
X57733D01*
G01X63277Y-628471D02*
X64923D01*
G01X67997Y-625971D02*
X68377Y-625471D01*
X68820Y-625221D01*
X69327Y-625138D01*
X69960Y-625305D01*
X70403Y-625721D01*
X70530Y-626221D01*
X70467Y-626721D01*
X70213Y-627138D01*
X68947Y-627971D01*
X68377Y-628555D01*
X67997Y-629388D01*
X67870Y-630138D01*
X70530D01*
G01X72907Y-629138D02*
X73287Y-629721D01*
X73793Y-630055D01*
X74363Y-630138D01*
X74870Y-630055D01*
X75377Y-629638D01*
X75693Y-629138D01*
X75757Y-628638D01*
X75630Y-628055D01*
X75187Y-627638D01*
X74743Y-627471D01*
X74173D01*
G01X74743D02*
X75123Y-627221D01*
X75440Y-626805D01*
X75567Y-626305D01*
X75440Y-625805D01*
X75123Y-625388D01*
X74553Y-625138D01*
X73983Y-625221D01*
X73413Y-625555D01*
G01X80160Y-630138D02*
Y-625138D01*
X77817Y-628721D01*
X80983D01*
G01X83107Y-629388D02*
X83487Y-629805D01*
X83930Y-630055D01*
X84500Y-630138D01*
X85070Y-629971D01*
X85513Y-629638D01*
X85830Y-629055D01*
X85893Y-628388D01*
X85767Y-627721D01*
X85450Y-627305D01*
X85007Y-626971D01*
X84563Y-626888D01*
X84120Y-626971D01*
X83550Y-627305D01*
X83740Y-625138D01*
X85450D01*
G01X93497Y-630138D02*
Y-625138D01*
X95903D01*
G01X95017Y-627555D02*
X93497D01*
G01X98217Y-630138D02*
X99800Y-625138D01*
X101383Y-630138D01*
G01X100813Y-628388D02*
X98787D01*
G01X103570Y-630138D02*
X106230Y-625138D01*
G01X103570D02*
X106230Y-630138D01*
G01X110000Y-630305D02*
X109873Y-630221D01*
Y-630055D01*
X110000Y-629971D01*
X110127Y-630055D01*
Y-630221D01*
X110000Y-630305D01*
G01Y-628055D02*
X109873Y-627971D01*
Y-627805D01*
X110000Y-627721D01*
X110127Y-627805D01*
Y-627971D01*
X110000Y-628055D01*
G01X114783Y-631805D02*
X114150Y-630971D01*
X113833Y-630138D01*
Y-626805D01*
X114150Y-625971D01*
X114783Y-625138D01*
G01X120200D02*
X119693Y-625305D01*
X119313Y-625721D01*
X119060Y-626221D01*
X118870Y-626888D01*
X118807Y-627638D01*
X118870Y-628388D01*
X119060Y-629055D01*
X119313Y-629555D01*
X119693Y-629971D01*
X120200Y-630138D01*
X120707Y-629971D01*
X121087Y-629555D01*
X121340Y-629055D01*
X121530Y-628388D01*
X121593Y-627638D01*
X121530Y-626888D01*
X121340Y-626221D01*
X121087Y-625721D01*
X120707Y-625305D01*
X120200Y-625138D01*
G01X123907Y-629138D02*
X124287Y-629721D01*
X124793Y-630055D01*
X125363Y-630138D01*
X125870Y-630055D01*
X126377Y-629638D01*
X126693Y-629138D01*
X126757Y-628638D01*
X126630Y-628055D01*
X126187Y-627638D01*
X125743Y-627471D01*
X125173D01*
G01X125743D02*
X126123Y-627221D01*
X126440Y-626805D01*
X126567Y-626305D01*
X126440Y-625805D01*
X126123Y-625388D01*
X125553Y-625138D01*
X124983Y-625221D01*
X124413Y-625555D01*
G01X130717Y-631805D02*
X131350Y-630971D01*
X131667Y-630138D01*
Y-626805D01*
X131350Y-625971D01*
X130717Y-625138D01*
G01X134107Y-629138D02*
X134487Y-629721D01*
X134993Y-630055D01*
X135563Y-630138D01*
X136070Y-630055D01*
X136577Y-629638D01*
X136893Y-629138D01*
X136957Y-628638D01*
X136830Y-628055D01*
X136387Y-627638D01*
X135943Y-627471D01*
X135373D01*
G01X135943D02*
X136323Y-627221D01*
X136640Y-626805D01*
X136767Y-626305D01*
X136640Y-625805D01*
X136323Y-625388D01*
X135753Y-625138D01*
X135183Y-625221D01*
X134613Y-625555D01*
G01X139523Y-629555D02*
X139967Y-629971D01*
X140473Y-630138D01*
X140980Y-629971D01*
X141423Y-629471D01*
X141740Y-628721D01*
X141867Y-627971D01*
Y-627055D01*
X141740Y-626305D01*
X141423Y-625638D01*
X141043Y-625305D01*
X140600Y-625138D01*
X140093Y-625305D01*
X139713Y-625638D01*
X139460Y-626138D01*
X139333Y-626805D01*
X139460Y-627388D01*
X139777Y-627971D01*
X140157Y-628305D01*
X140600Y-628388D01*
X141107Y-628221D01*
X141487Y-627805D01*
X141867Y-627055D01*
G01X145573Y-630138D02*
X145700Y-629055D01*
X145890Y-628138D01*
X146143Y-627305D01*
X146460Y-626388D01*
X146967Y-625138D01*
X144433D01*
G01X149977Y-628471D02*
X151623D01*
G01X154507Y-629138D02*
X154887Y-629721D01*
X155393Y-630055D01*
X155963Y-630138D01*
X156470Y-630055D01*
X156977Y-629638D01*
X157293Y-629138D01*
X157357Y-628638D01*
X157230Y-628055D01*
X156787Y-627638D01*
X156343Y-627471D01*
X155773D01*
G01X156343D02*
X156723Y-627221D01*
X157040Y-626805D01*
X157167Y-626305D01*
X157040Y-625805D01*
X156723Y-625388D01*
X156153Y-625138D01*
X155583Y-625221D01*
X155013Y-625555D01*
G01X159797Y-628055D02*
X160240Y-627471D01*
X160620Y-627138D01*
X161127Y-626971D01*
X161570Y-627138D01*
X161887Y-627471D01*
X162140Y-627971D01*
X162203Y-628555D01*
X162140Y-629055D01*
X161887Y-629555D01*
X161507Y-629971D01*
X161063Y-630138D01*
X160557Y-629971D01*
X160113Y-629471D01*
X159860Y-628721D01*
X159797Y-627888D01*
X159923Y-626805D01*
X160113Y-626221D01*
X160430Y-625638D01*
X160873Y-625221D01*
X161317Y-625138D01*
X161760Y-625305D01*
X162077Y-625721D01*
G01X166100Y-630138D02*
Y-625138D01*
X165340Y-626138D01*
G01Y-630138D02*
X166860D01*
G01X171960D02*
Y-625138D01*
X169617Y-628721D01*
X172783D01*
G01X-4000Y-560138D02*
Y-635138D01*
X496000D01*
Y-560138D01*
X-4000D01*
G01X191000D02*
Y-635138D01*
G01Y-610138D02*
X294000D01*
Y-585138D01*
G01X191000D02*
X294000D01*
G01X296000Y-560138D02*
Y-635138D01*
G01X294000Y-560138D02*
Y-635138D01*
G01X301507Y-620138D02*
Y-615138D01*
X302773D01*
X303280Y-615388D01*
X303660Y-615721D01*
X303977Y-616221D01*
X304230Y-616805D01*
X304293Y-617638D01*
X304230Y-618471D01*
X303977Y-619055D01*
X303660Y-619555D01*
X303280Y-619888D01*
X302773Y-620138D01*
X301507D01*
G01X306417D02*
X308000Y-615138D01*
X309583Y-620138D01*
G01X309013Y-618388D02*
X306987D01*
G01X313100Y-615138D02*
Y-620138D01*
G01X311643Y-615138D02*
X314557D01*
G01X319467Y-620138D02*
X316933D01*
Y-615138D01*
X319467D01*
G01X318453Y-617555D02*
X316933D01*
G01X323300Y-620305D02*
X323173Y-620221D01*
Y-620055D01*
X323300Y-619971D01*
X323427Y-620055D01*
Y-620221D01*
X323300Y-620305D01*
G01Y-618055D02*
X323173Y-617971D01*
Y-617805D01*
X323300Y-617721D01*
X323427Y-617805D01*
Y-617971D01*
X323300Y-618055D01*
G01X296000Y-610138D02*
X496000D01*
G01X301633Y-595138D02*
Y-590138D01*
X303153D01*
X303660Y-590388D01*
X304040Y-590971D01*
X304167Y-591638D01*
X304040Y-592305D01*
X303723Y-592805D01*
X303153Y-593055D01*
X301633D01*
G01X306860Y-595305D02*
X309140Y-590138D01*
G01X311643Y-595138D02*
Y-590138D01*
X314557Y-595138D01*
Y-590138D01*
G01X318200Y-595305D02*
X318073Y-595221D01*
Y-595055D01*
X318200Y-594971D01*
X318327Y-595055D01*
Y-595221D01*
X318200Y-595305D01*
G01Y-593055D02*
X318073Y-592971D01*
Y-592805D01*
X318200Y-592721D01*
X318327Y-592805D01*
Y-592971D01*
X318200Y-593055D01*
G01X296000Y-585138D02*
X496000D01*
G01X301633Y-570138D02*
Y-565138D01*
X303153D01*
X303660Y-565388D01*
X304040Y-565971D01*
X304167Y-566638D01*
X304040Y-567305D01*
X303723Y-567805D01*
X303153Y-568055D01*
X301633D01*
G01X306733Y-570138D02*
Y-565138D01*
X308317D01*
X308823Y-565388D01*
X309140Y-565721D01*
X309267Y-566388D01*
X309140Y-567055D01*
X308760Y-567471D01*
X308317Y-567721D01*
X306733D01*
G01X308317D02*
X309267Y-570138D01*
G01X313100D02*
X312593Y-570055D01*
X312150Y-569721D01*
X311770Y-569221D01*
X311517Y-568638D01*
X311390Y-567971D01*
Y-567305D01*
X311517Y-566638D01*
X311770Y-566055D01*
X312150Y-565555D01*
X312593Y-565221D01*
X313100Y-565138D01*
X313607Y-565221D01*
X314050Y-565555D01*
X314430Y-566055D01*
X314683Y-566638D01*
X314810Y-567305D01*
Y-567971D01*
X314683Y-568638D01*
X314430Y-569221D01*
X314050Y-569721D01*
X313607Y-570055D01*
X313100Y-570138D01*
G01X316933Y-569138D02*
X317250Y-569638D01*
X317630Y-569971D01*
X318073Y-570138D01*
X318580Y-569971D01*
X318960Y-569638D01*
X319340Y-569138D01*
X319467Y-568471D01*
Y-565138D01*
G01X324567Y-570138D02*
X322033D01*
Y-565138D01*
X324567D01*
G01X323553Y-567555D02*
X322033D01*
G01X329793Y-565555D02*
X329413Y-565305D01*
X328970Y-565138D01*
X328463D01*
X327893Y-565388D01*
X327450Y-565805D01*
X327133Y-566305D01*
X326880Y-567138D01*
X326817Y-567888D01*
X326943Y-568638D01*
X327133Y-569138D01*
X327513Y-569638D01*
X327957Y-569971D01*
X328400Y-570138D01*
X328843D01*
X329287Y-569971D01*
X329667Y-569721D01*
X329983Y-569388D01*
G01X333500Y-565138D02*
Y-570138D01*
G01X332043Y-565138D02*
X334957D01*
G01X338600Y-570305D02*
X338473Y-570221D01*
Y-570055D01*
X338600Y-569971D01*
X338727Y-570055D01*
Y-570221D01*
X338600Y-570305D01*
G01Y-568055D02*
X338473Y-567971D01*
Y-567805D01*
X338600Y-567721D01*
X338727Y-567805D01*
Y-567971D01*
X338600Y-568055D01*
G01X411000Y-610138D02*
Y-635138D01*
G01X413633Y-612638D02*
Y-617638D01*
X416167D01*
G01X419240Y-612638D02*
X420760D01*
G01X420000D02*
Y-617638D01*
G01X419240D02*
X420760D01*
G01X425607Y-614971D02*
X425860Y-614721D01*
X426050Y-614305D01*
X426177Y-613721D01*
X426050Y-613221D01*
X425797Y-612888D01*
X425353Y-612638D01*
X423643D01*
Y-617638D01*
X425733D01*
X426177Y-617305D01*
X426430Y-616805D01*
X426557Y-616221D01*
X426430Y-615638D01*
X426050Y-615138D01*
X425607Y-614971D01*
X423643D01*
G01X430200Y-617805D02*
X430073Y-617721D01*
Y-617555D01*
X430200Y-617471D01*
X430327Y-617555D01*
Y-617721D01*
X430200Y-617805D01*
G01Y-615555D02*
X430073Y-615471D01*
Y-615305D01*
X430200Y-615221D01*
X430327Y-615305D01*
Y-615471D01*
X430200Y-615555D01*
G01X454000Y-610138D02*
Y-635138D01*
G01Y-585138D02*
Y-610138D01*
G01X459013Y-637305D02*
X459120Y-637180D01*
X459200Y-636971D01*
X459253Y-636680D01*
X459200Y-636430D01*
X459093Y-636263D01*
X458907Y-636138D01*
X458187D01*
Y-638638D01*
X459067D01*
X459253Y-638471D01*
X459360Y-638221D01*
X459413Y-637930D01*
X459360Y-637638D01*
X459200Y-637388D01*
X459013Y-637305D01*
X458187D01*
G01X461480Y-638638D02*
Y-636971D01*
G01Y-637263D02*
X461373Y-637096D01*
X461213Y-637013D01*
X461027Y-636971D01*
X460840Y-637055D01*
X460680Y-637221D01*
X460573Y-637471D01*
X460520Y-637805D01*
X460573Y-638138D01*
X460680Y-638388D01*
X460840Y-638555D01*
X461027Y-638638D01*
X461213Y-638596D01*
X461373Y-638471D01*
X461480Y-638305D01*
G01X462800Y-638346D02*
X462933Y-638513D01*
X463120Y-638638D01*
X463280D01*
X463440Y-638555D01*
X463547Y-638430D01*
X463600Y-638263D01*
X463573Y-638013D01*
X463467Y-637888D01*
X462987Y-637638D01*
X462880Y-637346D01*
X462933Y-637138D01*
X463040Y-637013D01*
X463200Y-636971D01*
X463360Y-637013D01*
X463520Y-637138D01*
G01X465000Y-637513D02*
X465853D01*
X465773Y-637221D01*
X465640Y-637055D01*
X465453Y-636971D01*
X465267Y-637013D01*
X465107Y-637138D01*
X465000Y-637430D01*
X464947Y-637680D01*
Y-637930D01*
X465000Y-638180D01*
X465133Y-638430D01*
X465293Y-638596D01*
X465480Y-638638D01*
X465667Y-638555D01*
X465853Y-638305D01*
G01X467120Y-638638D02*
Y-636138D01*
G01Y-637388D02*
X467253Y-637138D01*
X467413Y-637013D01*
X467573Y-636971D01*
X467813Y-637055D01*
X467973Y-637221D01*
X468080Y-637513D01*
Y-637846D01*
X468027Y-638180D01*
X467920Y-638430D01*
X467733Y-638596D01*
X467573Y-638638D01*
X467413Y-638596D01*
X467253Y-638471D01*
X467120Y-638263D01*
G01X469800Y-638638D02*
X469640Y-638596D01*
X469480Y-638430D01*
X469373Y-638138D01*
X469320Y-637805D01*
X469373Y-637471D01*
X469480Y-637180D01*
X469640Y-637013D01*
X469800Y-636971D01*
X469960Y-637013D01*
X470120Y-637180D01*
X470227Y-637471D01*
X470253Y-637805D01*
X470227Y-638138D01*
X470120Y-638430D01*
X469960Y-638596D01*
X469800Y-638638D01*
G01X472480D02*
Y-636971D01*
G01Y-637263D02*
X472373Y-637096D01*
X472213Y-637013D01*
X472027Y-636971D01*
X471840Y-637055D01*
X471680Y-637221D01*
X471573Y-637471D01*
X471520Y-637805D01*
X471573Y-638138D01*
X471680Y-638388D01*
X471840Y-638555D01*
X472027Y-638638D01*
X472213Y-638596D01*
X472373Y-638471D01*
X472480Y-638305D01*
G01X473827Y-638638D02*
Y-636971D01*
G01Y-637305D02*
X473960Y-637138D01*
X474093Y-637013D01*
X474280Y-636971D01*
X474413Y-637013D01*
X474573Y-637138D01*
G01X476880Y-636138D02*
Y-638638D01*
G01Y-638263D02*
X476773Y-638471D01*
X476613Y-638596D01*
X476427Y-638638D01*
X476213Y-638555D01*
X476053Y-638346D01*
X475947Y-638096D01*
X475920Y-637805D01*
X475947Y-637513D01*
X476053Y-637263D01*
X476213Y-637055D01*
X476427Y-636971D01*
X476613Y-637013D01*
X476747Y-637096D01*
X476880Y-637263D01*
G01X480267Y-638638D02*
Y-636138D01*
X480933D01*
X481147Y-636263D01*
X481280Y-636430D01*
X481333Y-636763D01*
X481280Y-637096D01*
X481120Y-637305D01*
X480933Y-637430D01*
X480267D01*
G01X480933D02*
X481333Y-638638D01*
G01X482600Y-637513D02*
X483453D01*
X483373Y-637221D01*
X483240Y-637055D01*
X483053Y-636971D01*
X482867Y-637013D01*
X482707Y-637138D01*
X482600Y-637430D01*
X482547Y-637680D01*
Y-637930D01*
X482600Y-638180D01*
X482733Y-638430D01*
X482893Y-638596D01*
X483080Y-638638D01*
X483267Y-638555D01*
X483453Y-638305D01*
G01X484720Y-636971D02*
X485200Y-638638D01*
X485680Y-636971D01*
G01X487400Y-638721D02*
X487347Y-638680D01*
Y-638596D01*
X487400Y-638555D01*
X487453Y-638596D01*
Y-638680D01*
X487400Y-638721D01*
G01X489147Y-638346D02*
X489333Y-638555D01*
X489547Y-638638D01*
X489760Y-638555D01*
X489947Y-638305D01*
X490080Y-637930D01*
X490133Y-637555D01*
Y-637096D01*
X490080Y-636721D01*
X489947Y-636388D01*
X489787Y-636221D01*
X489600Y-636138D01*
X489387Y-636221D01*
X489227Y-636388D01*
X489120Y-636638D01*
X489067Y-636971D01*
X489120Y-637263D01*
X489253Y-637555D01*
X489413Y-637721D01*
X489600Y-637763D01*
X489813Y-637680D01*
X489973Y-637471D01*
X490133Y-637096D01*
G01X492013Y-637305D02*
X492120Y-637180D01*
X492200Y-636971D01*
X492253Y-636680D01*
X492200Y-636430D01*
X492093Y-636263D01*
X491907Y-636138D01*
X491187D01*
Y-638638D01*
X492067D01*
X492253Y-638471D01*
X492360Y-638221D01*
X492413Y-637930D01*
X492360Y-637638D01*
X492200Y-637388D01*
X492013Y-637305D01*
X491187D01*
G01X457900Y-612638D02*
Y-617638D01*
G01X456443Y-612638D02*
X459357D01*
G01X463000Y-617638D02*
X462620Y-617555D01*
X462240Y-617221D01*
X461987Y-616638D01*
X461860Y-615971D01*
X461987Y-615305D01*
X462240Y-614721D01*
X462620Y-614388D01*
X463000Y-614305D01*
X463380Y-614388D01*
X463760Y-614721D01*
X464013Y-615305D01*
X464077Y-615971D01*
X464013Y-616638D01*
X463760Y-617221D01*
X463380Y-617555D01*
X463000Y-617638D01*
G01X468100D02*
X467720Y-617555D01*
X467340Y-617221D01*
X467087Y-616638D01*
X466960Y-615971D01*
X467087Y-615305D01*
X467340Y-614721D01*
X467720Y-614388D01*
X468100Y-614305D01*
X468480Y-614388D01*
X468860Y-614721D01*
X469113Y-615305D01*
X469177Y-615971D01*
X469113Y-616638D01*
X468860Y-617221D01*
X468480Y-617555D01*
X468100Y-617638D01*
G01X473200D02*
Y-612638D01*
G01X478300Y-617805D02*
X478173Y-617721D01*
Y-617555D01*
X478300Y-617471D01*
X478427Y-617555D01*
Y-617721D01*
X478300Y-617805D01*
G01Y-615555D02*
X478173Y-615471D01*
Y-615305D01*
X478300Y-615221D01*
X478427Y-615305D01*
Y-615471D01*
X478300Y-615555D01*
G01X456633Y-592638D02*
Y-587638D01*
X458217D01*
X458723Y-587888D01*
X459040Y-588221D01*
X459167Y-588888D01*
X459040Y-589555D01*
X458660Y-589971D01*
X458217Y-590221D01*
X456633D01*
G01X458217D02*
X459167Y-592638D01*
G01X464267D02*
X461733D01*
Y-587638D01*
X464267D01*
G01X463253Y-590055D02*
X461733D01*
G01X466517Y-587638D02*
X468100Y-592638D01*
X469683Y-587638D01*
G01X473200Y-592805D02*
X473073Y-592721D01*
Y-592555D01*
X473200Y-592471D01*
X473327Y-592555D01*
Y-592721D01*
X473200Y-592805D01*
G01Y-590555D02*
X473073Y-590471D01*
Y-590305D01*
X473200Y-590221D01*
X473327Y-590305D01*
Y-590471D01*
X473200Y-590555D01*
G01X-476840Y-884638D02*
Y2768362D01*
X5911000D01*
Y-884638D01*
X-476840D01*
G01X8820Y-607488D02*
X10387D01*
Y-609378D01*
X9917Y-610008D01*
X9368Y-610428D01*
X8585Y-610638D01*
X7802Y-610428D01*
X7253Y-610008D01*
X6783Y-609378D01*
X6470Y-608643D01*
X6313Y-607803D01*
Y-607068D01*
X6470Y-606438D01*
X6783Y-605703D01*
X7253Y-605073D01*
X7723Y-604653D01*
X8350Y-604338D01*
X8898D01*
X9525Y-604548D01*
X9995Y-604968D01*
G01X12927Y-604338D02*
Y-608853D01*
X13240Y-609798D01*
X13867Y-610428D01*
X14650Y-610638D01*
X15433Y-610428D01*
X16060Y-609798D01*
X16373Y-608853D01*
Y-604338D01*
G01X20010D02*
X21890D01*
G01X20950D02*
Y-610638D01*
G01X20010D02*
X21890D01*
G01X25605Y-609798D02*
X26232Y-610323D01*
X26937Y-610638D01*
X27563D01*
X28190Y-610323D01*
X28660Y-609798D01*
X28895Y-609063D01*
X28738Y-608328D01*
X28347Y-607698D01*
X27642Y-607278D01*
X26702Y-607068D01*
X26153Y-606648D01*
X25918Y-605913D01*
X26075Y-605178D01*
X26467Y-604653D01*
X27015Y-604338D01*
X27563D01*
X28112Y-604548D01*
X28582Y-605073D01*
G01X31905Y-610638D02*
Y-604338D01*
G01X35195D02*
Y-610638D01*
G01Y-607488D02*
X31905D01*
G01X37892Y-610638D02*
X39850Y-604338D01*
X41808Y-610638D01*
G01X41103Y-608433D02*
X38597D01*
G01X44348Y-610638D02*
Y-604338D01*
X47952Y-610638D01*
Y-604338D01*
G01X57027Y-610638D02*
Y-604338D01*
X58593D01*
X59220Y-604653D01*
X59690Y-605073D01*
X60082Y-605703D01*
X60395Y-606438D01*
X60473Y-607488D01*
X60395Y-608538D01*
X60082Y-609273D01*
X59690Y-609903D01*
X59220Y-610323D01*
X58593Y-610638D01*
X57027D01*
G01X64110Y-604338D02*
X65990D01*
G01X65050D02*
Y-610638D01*
G01X64110D02*
X65990D01*
G01X69705Y-609798D02*
X70332Y-610323D01*
X71037Y-610638D01*
X71663D01*
X72290Y-610323D01*
X72760Y-609798D01*
X72995Y-609063D01*
X72838Y-608328D01*
X72447Y-607698D01*
X71742Y-607278D01*
X70802Y-607068D01*
X70253Y-606648D01*
X70018Y-605913D01*
X70175Y-605178D01*
X70567Y-604653D01*
X71115Y-604338D01*
X71663D01*
X72212Y-604548D01*
X72682Y-605073D01*
G01X77650Y-604338D02*
Y-610638D01*
G01X75848Y-604338D02*
X79452D01*
G01X83950Y-610848D02*
X83793Y-610743D01*
Y-610533D01*
X83950Y-610428D01*
X84107Y-610533D01*
Y-610743D01*
X83950Y-610848D01*
G01X90093Y-611793D02*
X90407Y-610428D01*
G01X96550Y-604338D02*
Y-610638D01*
G01X94748Y-604338D02*
X98352D01*
G01X100892Y-610638D02*
X102850Y-604338D01*
X104808Y-610638D01*
G01X104103Y-608433D02*
X101597D01*
G01X109150Y-610638D02*
X108523Y-610533D01*
X107975Y-610113D01*
X107505Y-609483D01*
X107192Y-608748D01*
X107035Y-607908D01*
Y-607068D01*
X107192Y-606228D01*
X107505Y-605493D01*
X107975Y-604863D01*
X108523Y-604443D01*
X109150Y-604338D01*
X109777Y-604443D01*
X110325Y-604863D01*
X110795Y-605493D01*
X111108Y-606228D01*
X111265Y-607068D01*
Y-607908D01*
X111108Y-608748D01*
X110795Y-609483D01*
X110325Y-610113D01*
X109777Y-610533D01*
X109150Y-610638D01*
G01X115450D02*
Y-607803D01*
X113883Y-604338D01*
G01X117017D02*
X115450Y-607803D01*
G01X120027Y-604338D02*
Y-608853D01*
X120340Y-609798D01*
X120967Y-610428D01*
X121750Y-610638D01*
X122533Y-610428D01*
X123160Y-609798D01*
X123473Y-608853D01*
Y-604338D01*
G01X126092Y-610638D02*
X128050Y-604338D01*
X130008Y-610638D01*
G01X129303Y-608433D02*
X126797D01*
G01X132548Y-610638D02*
Y-604338D01*
X136152Y-610638D01*
Y-604338D01*
G01X10073Y-614863D02*
X9603Y-614548D01*
X9055Y-614338D01*
X8428D01*
X7723Y-614653D01*
X7175Y-615178D01*
X6783Y-615808D01*
X6470Y-616858D01*
X6392Y-617803D01*
X6548Y-618748D01*
X6783Y-619378D01*
X7253Y-620008D01*
X7802Y-620428D01*
X8350Y-620638D01*
X8898D01*
X9447Y-620428D01*
X9917Y-620113D01*
X10308Y-619693D01*
G01X13710Y-614338D02*
X15590D01*
G01X14650D02*
Y-620638D01*
G01X13710D02*
X15590D01*
G01X20950Y-614338D02*
Y-620638D01*
G01X19148Y-614338D02*
X22752D01*
G01X27250Y-620638D02*
Y-617803D01*
X25683Y-614338D01*
G01X28817D02*
X27250Y-617803D01*
G01X38127Y-619378D02*
X38597Y-620113D01*
X39223Y-620533D01*
X39928Y-620638D01*
X40555Y-620533D01*
X41182Y-620008D01*
X41573Y-619378D01*
X41652Y-618748D01*
X41495Y-618013D01*
X40947Y-617488D01*
X40398Y-617278D01*
X39693D01*
G01X40398D02*
X40868Y-616963D01*
X41260Y-616438D01*
X41417Y-615808D01*
X41260Y-615178D01*
X40868Y-614653D01*
X40163Y-614338D01*
X39458Y-614443D01*
X38753Y-614863D01*
G01X44427Y-619378D02*
X44897Y-620113D01*
X45523Y-620533D01*
X46228Y-620638D01*
X46855Y-620533D01*
X47482Y-620008D01*
X47873Y-619378D01*
X47952Y-618748D01*
X47795Y-618013D01*
X47247Y-617488D01*
X46698Y-617278D01*
X45993D01*
G01X46698D02*
X47168Y-616963D01*
X47560Y-616438D01*
X47717Y-615808D01*
X47560Y-615178D01*
X47168Y-614653D01*
X46463Y-614338D01*
X45758Y-614443D01*
X45053Y-614863D01*
G01X50727Y-619378D02*
X51197Y-620113D01*
X51823Y-620533D01*
X52528Y-620638D01*
X53155Y-620533D01*
X53782Y-620008D01*
X54173Y-619378D01*
X54252Y-618748D01*
X54095Y-618013D01*
X53547Y-617488D01*
X52998Y-617278D01*
X52293D01*
G01X52998D02*
X53468Y-616963D01*
X53860Y-616438D01*
X54017Y-615808D01*
X53860Y-615178D01*
X53468Y-614653D01*
X52763Y-614338D01*
X52058Y-614443D01*
X51353Y-614863D01*
G01X58593Y-620638D02*
X58750Y-619273D01*
X58985Y-618118D01*
X59298Y-617068D01*
X59690Y-615913D01*
X60317Y-614338D01*
X57183D01*
G01X64893Y-620638D02*
X65050Y-619273D01*
X65285Y-618118D01*
X65598Y-617068D01*
X65990Y-615913D01*
X66617Y-614338D01*
X63483D01*
G01X71193Y-621793D02*
X71507Y-620428D01*
G01X77650Y-614338D02*
Y-620638D01*
G01X75848Y-614338D02*
X79452D01*
G01X81992Y-620638D02*
X83950Y-614338D01*
X85908Y-620638D01*
G01X85203Y-618433D02*
X82697D01*
G01X89310Y-614338D02*
X91190D01*
G01X90250D02*
Y-620638D01*
G01X89310D02*
X91190D01*
G01X94200Y-614338D02*
X95297Y-620638D01*
X96550Y-614338D01*
X97803Y-620638D01*
X98900Y-614338D01*
G01X100892Y-620638D02*
X102850Y-614338D01*
X104808Y-620638D01*
G01X104103Y-618433D02*
X101597D01*
G01X107348Y-620638D02*
Y-614338D01*
X110952Y-620638D01*
Y-614338D01*
G01X121358Y-622738D02*
X120575Y-621688D01*
X120183Y-620638D01*
Y-616438D01*
X120575Y-615388D01*
X121358Y-614338D01*
G01X132783Y-620638D02*
Y-614338D01*
X134742D01*
X135368Y-614653D01*
X135760Y-615073D01*
X135917Y-615913D01*
X135760Y-616753D01*
X135290Y-617278D01*
X134742Y-617593D01*
X132783D01*
G01X134742D02*
X135917Y-620638D01*
G01X140650Y-620848D02*
X140493Y-620743D01*
Y-620533D01*
X140650Y-620428D01*
X140807Y-620533D01*
Y-620743D01*
X140650Y-620848D01*
G01X146950Y-620638D02*
X146323Y-620533D01*
X145775Y-620113D01*
X145305Y-619483D01*
X144992Y-618748D01*
X144835Y-617908D01*
Y-617068D01*
X144992Y-616228D01*
X145305Y-615493D01*
X145775Y-614863D01*
X146323Y-614443D01*
X146950Y-614338D01*
X147577Y-614443D01*
X148125Y-614863D01*
X148595Y-615493D01*
X148908Y-616228D01*
X149065Y-617068D01*
Y-617908D01*
X148908Y-618748D01*
X148595Y-619483D01*
X148125Y-620113D01*
X147577Y-620533D01*
X146950Y-620638D01*
G01X153250Y-620848D02*
X153093Y-620743D01*
Y-620533D01*
X153250Y-620428D01*
X153407Y-620533D01*
Y-620743D01*
X153250Y-620848D01*
G01X161273Y-614863D02*
X160803Y-614548D01*
X160255Y-614338D01*
X159628D01*
X158923Y-614653D01*
X158375Y-615178D01*
X157983Y-615808D01*
X157670Y-616858D01*
X157592Y-617803D01*
X157748Y-618748D01*
X157983Y-619378D01*
X158453Y-620008D01*
X159002Y-620428D01*
X159550Y-620638D01*
X160098D01*
X160647Y-620428D01*
X161117Y-620113D01*
X161508Y-619693D01*
G01X165850Y-620848D02*
X165693Y-620743D01*
Y-620533D01*
X165850Y-620428D01*
X166007Y-620533D01*
Y-620743D01*
X165850Y-620848D01*
G01X172542Y-622738D02*
X173325Y-621688D01*
X173717Y-620638D01*
Y-616438D01*
X173325Y-615388D01*
X172542Y-614338D01*
G01X6548Y-600638D02*
Y-594338D01*
X10152Y-600638D01*
Y-594338D01*
G01X14650Y-600638D02*
X14023Y-600533D01*
X13475Y-600113D01*
X13005Y-599483D01*
X12692Y-598748D01*
X12535Y-597908D01*
Y-597068D01*
X12692Y-596228D01*
X13005Y-595493D01*
X13475Y-594863D01*
X14023Y-594443D01*
X14650Y-594338D01*
X15277Y-594443D01*
X15825Y-594863D01*
X16295Y-595493D01*
X16608Y-596228D01*
X16765Y-597068D01*
Y-597908D01*
X16608Y-598748D01*
X16295Y-599483D01*
X15825Y-600113D01*
X15277Y-600533D01*
X14650Y-600638D01*
G01X20950Y-600848D02*
X20793Y-600743D01*
Y-600533D01*
X20950Y-600428D01*
X21107Y-600533D01*
Y-600743D01*
X20950Y-600848D01*
G01X25762Y-595388D02*
X26232Y-594758D01*
X26780Y-594443D01*
X27407Y-594338D01*
X28190Y-594548D01*
X28738Y-595073D01*
X28895Y-595703D01*
X28817Y-596333D01*
X28503Y-596858D01*
X26937Y-597908D01*
X26232Y-598643D01*
X25762Y-599693D01*
X25605Y-600638D01*
X28895D01*
G01X33550D02*
Y-594338D01*
X32610Y-595598D01*
G01Y-600638D02*
X34490D01*
G01X39850D02*
Y-594338D01*
X38910Y-595598D01*
G01Y-600638D02*
X40790D01*
G01X45993Y-601793D02*
X46307Y-600428D01*
G01X50100Y-594338D02*
X51197Y-600638D01*
X52450Y-594338D01*
X53703Y-600638D01*
X54800Y-594338D01*
G01X60317Y-600638D02*
X57183D01*
Y-594338D01*
X60317D01*
G01X59063Y-597383D02*
X57183D01*
G01X63248Y-600638D02*
Y-594338D01*
X66852Y-600638D01*
Y-594338D01*
G01X69705Y-600638D02*
Y-594338D01*
G01X72995D02*
Y-600638D01*
G01Y-597488D02*
X69705D01*
G01X75927Y-594338D02*
Y-598853D01*
X76240Y-599798D01*
X76867Y-600428D01*
X77650Y-600638D01*
X78433Y-600428D01*
X79060Y-599798D01*
X79373Y-598853D01*
Y-594338D01*
G01X81992Y-600638D02*
X83950Y-594338D01*
X85908Y-600638D01*
G01X85203Y-598433D02*
X82697D01*
G01X95062Y-595388D02*
X95532Y-594758D01*
X96080Y-594443D01*
X96707Y-594338D01*
X97490Y-594548D01*
X98038Y-595073D01*
X98195Y-595703D01*
X98117Y-596333D01*
X97803Y-596858D01*
X96237Y-597908D01*
X95532Y-598643D01*
X95062Y-599693D01*
X94905Y-600638D01*
X98195D01*
G01X101048D02*
Y-594338D01*
X104652Y-600638D01*
Y-594338D01*
G01X107427Y-600638D02*
Y-594338D01*
X108993D01*
X109620Y-594653D01*
X110090Y-595073D01*
X110482Y-595703D01*
X110795Y-596438D01*
X110873Y-597488D01*
X110795Y-598538D01*
X110482Y-599273D01*
X110090Y-599903D01*
X109620Y-600323D01*
X108993Y-600638D01*
X107427D01*
G01X120183D02*
Y-594338D01*
X122142D01*
X122768Y-594653D01*
X123160Y-595073D01*
X123317Y-595913D01*
X123160Y-596753D01*
X122690Y-597278D01*
X122142Y-597593D01*
X120183D01*
G01X122142D02*
X123317Y-600638D01*
G01X126327D02*
Y-594338D01*
X127893D01*
X128520Y-594653D01*
X128990Y-595073D01*
X129382Y-595703D01*
X129695Y-596438D01*
X129773Y-597488D01*
X129695Y-598538D01*
X129382Y-599273D01*
X128990Y-599903D01*
X128520Y-600323D01*
X127893Y-600638D01*
X126327D01*
G01X134350Y-600848D02*
X134193Y-600743D01*
Y-600533D01*
X134350Y-600428D01*
X134507Y-600533D01*
Y-600743D01*
X134350Y-600848D01*
G01X30650Y-589938D02*
X28130Y-589521D01*
X25925Y-587855D01*
X24035Y-585355D01*
X22775Y-582438D01*
X22145Y-579105D01*
Y-575771D01*
X22775Y-572438D01*
X24035Y-569521D01*
X25925Y-567022D01*
X28130Y-565355D01*
X30650Y-564938D01*
X33170Y-565355D01*
X35375Y-567022D01*
X37265Y-569521D01*
X38525Y-572438D01*
X39155Y-575771D01*
Y-579105D01*
X38525Y-582438D01*
X37265Y-585355D01*
X35375Y-587855D01*
X33170Y-589521D01*
X30650Y-589938D01*
G01X33170Y-583271D02*
X36950Y-589938D01*
G01X50495Y-573272D02*
Y-584938D01*
X51755Y-587855D01*
X53645Y-589521D01*
X55850Y-589938D01*
X58055Y-589521D01*
X59945Y-587855D01*
X61205Y-584938D01*
G01Y-589938D02*
Y-573272D01*
G01X86720Y-589938D02*
Y-573272D01*
G01Y-576188D02*
X85460Y-574522D01*
X83570Y-573688D01*
X81365Y-573272D01*
X79160Y-574105D01*
X77270Y-575771D01*
X76010Y-578272D01*
X75380Y-581605D01*
X76010Y-584938D01*
X77270Y-587439D01*
X79160Y-589105D01*
X81365Y-589938D01*
X83570Y-589521D01*
X85460Y-588272D01*
X86720Y-586605D01*
G01X100895Y-589938D02*
Y-573272D01*
G01Y-577438D02*
X102155Y-575355D01*
X104045Y-573688D01*
X106565Y-573272D01*
X108770Y-573688D01*
X110660Y-575355D01*
X111605Y-578272D01*
Y-589938D01*
G01X131450Y-564938D02*
Y-589938D01*
G01X127040Y-573272D02*
X135860D01*
G01X162320Y-589938D02*
Y-573272D01*
G01Y-576188D02*
X161060Y-574522D01*
X159170Y-573688D01*
X156965Y-573272D01*
X154760Y-574105D01*
X152870Y-575771D01*
X151610Y-578272D01*
X150980Y-581605D01*
X151610Y-584938D01*
X152870Y-587439D01*
X154760Y-589105D01*
X156965Y-589938D01*
X159170Y-589521D01*
X161060Y-588272D01*
X162320Y-586605D01*
G01X59039Y1549644D02*
Y1546233D01*
X60914Y1544358D01*
Y1542339D01*
G01X61621Y1552869D02*
X59039Y1550287D01*
Y1549644D01*
G01X66229Y1549536D02*
Y1542339D01*
G01X61110Y1598146D02*
Y1601373D01*
X63704Y1603967D01*
Y1605956D01*
G01X57811Y1598061D02*
Y1600074D01*
X62129Y1604392D01*
Y1605956D01*
G01X76806Y1599482D02*
X72660Y1595336D01*
Y1593471D01*
G01X76806Y1599482D02*
Y1599934D01*
X72375Y1604365D01*
G01X81006Y1599482D02*
X76806D01*
G01X72375Y1604365D02*
X71860Y1604880D01*
Y1608594D01*
X70561Y1609893D01*
X69216D01*
G01Y1611468D02*
X70612D01*
X74233Y1607847D01*
G01D02*
X74298Y1607782D01*
X78406D01*
G01X79058Y1611896D02*
X76733D01*
X74233Y1614396D01*
G01D02*
X74011Y1614618D01*
X69216D01*
G01X69775Y1622492D02*
X69216D01*
G01X79058Y1616396D02*
X76634D01*
X76177Y1616853D01*
X72378D01*
X72255Y1616730D01*
G01X79058Y1620896D02*
X74634D01*
X74134Y1621396D01*
G01X95436Y1552796D02*
X93296Y1550656D01*
Y1549142D01*
G01D02*
X94562Y1547876D01*
Y1545876D01*
X96657Y1543781D01*
Y1542339D01*
G01X82606Y1604632D02*
X91443Y1613469D01*
X141154D01*
X142564Y1614879D01*
X146453D01*
G01X113500Y1455600D02*
X112312D01*
X109900Y1453188D01*
Y1447300D01*
X111339Y1445861D01*
Y1444819D01*
G01X112481Y1452424D02*
X111300Y1451243D01*
Y1448000D01*
X112913Y1446387D01*
Y1444819D01*
G01X102011Y1550242D02*
X102096D01*
X101972Y1550118D01*
Y1542339D01*
G01X113600Y1449100D02*
X114488Y1448212D01*
Y1444819D01*
G01X116063D02*
Y1448163D01*
X116900Y1449000D01*
G01X118658Y1455464D02*
X119600Y1454522D01*
Y1448422D01*
X117638Y1446460D01*
Y1444819D01*
G01X119100Y1460300D02*
X121500Y1457900D01*
Y1448335D01*
X119213Y1446048D01*
Y1444819D01*
G01X121500Y1467400D02*
Y1464100D01*
X125512Y1460088D01*
Y1444819D01*
G01X112100Y1467500D02*
X115600D01*
X123937Y1459163D01*
Y1444819D01*
G01X116122Y1458000D02*
X118658Y1455464D01*
G01X124600Y1465100D02*
Y1463000D01*
X127087Y1460513D01*
Y1444819D01*
G01X128661Y1464000D02*
Y1444819D01*
G01X202000Y-569638D02*
Y-577638D01*
X206000D01*
G01X213800D02*
Y-572305D01*
G01Y-573238D02*
X213400Y-572705D01*
X212800Y-572438D01*
X212100Y-572305D01*
X211400Y-572571D01*
X210800Y-573105D01*
X210400Y-573905D01*
X210200Y-574971D01*
X210400Y-576038D01*
X210800Y-576838D01*
X211400Y-577371D01*
X212100Y-577638D01*
X212800Y-577505D01*
X213400Y-577105D01*
X213800Y-576572D01*
G01X217900Y-580038D02*
X218500Y-580305D01*
X219300Y-580038D01*
X219800Y-579505D01*
X220200Y-578838D01*
X220800Y-576705D01*
X222100Y-572305D01*
G01X218900D02*
X220800Y-576705D01*
G01X226500Y-574038D02*
X229700D01*
X229400Y-573105D01*
X228900Y-572571D01*
X228200Y-572305D01*
X227500Y-572438D01*
X226900Y-572838D01*
X226500Y-573771D01*
X226300Y-574572D01*
Y-575371D01*
X226500Y-576171D01*
X227000Y-576971D01*
X227600Y-577505D01*
X228300Y-577638D01*
X229000Y-577371D01*
X229700Y-576572D01*
G01X234600Y-577638D02*
Y-572305D01*
G01Y-573371D02*
X235100Y-572838D01*
X235600Y-572438D01*
X236300Y-572305D01*
X236800Y-572438D01*
X237400Y-572838D01*
G01X226000Y-626038D02*
X226500Y-626838D01*
X227100Y-627371D01*
X227800Y-627638D01*
X228600Y-627371D01*
X229200Y-626838D01*
X229800Y-626038D01*
X230000Y-624971D01*
Y-619638D01*
G01X237800Y-627638D02*
Y-622305D01*
G01Y-623238D02*
X237400Y-622705D01*
X236800Y-622438D01*
X236100Y-622305D01*
X235400Y-622571D01*
X234800Y-623105D01*
X234400Y-623905D01*
X234200Y-624971D01*
X234400Y-626038D01*
X234800Y-626838D01*
X235400Y-627371D01*
X236100Y-627638D01*
X236800Y-627505D01*
X237400Y-627105D01*
X237800Y-626572D01*
G01X245600Y-622971D02*
X244900Y-622438D01*
X244300Y-622305D01*
X243500Y-622571D01*
X242900Y-623105D01*
X242500Y-624038D01*
X242400Y-624971D01*
X242500Y-625905D01*
X242900Y-626705D01*
X243500Y-627371D01*
X244300Y-627638D01*
X245000Y-627371D01*
X245600Y-626838D01*
G01X250300Y-627638D02*
Y-619638D01*
G01X253500Y-622305D02*
X250300Y-625371D01*
G01X251600Y-624171D02*
X253700Y-627638D01*
G01X235500Y-594638D02*
Y-602638D01*
G01X233200Y-594638D02*
X237800D01*
G01X243500Y-602638D02*
X242700Y-602505D01*
X242000Y-601971D01*
X241400Y-601171D01*
X241000Y-600238D01*
X240800Y-599171D01*
Y-598105D01*
X241000Y-597038D01*
X241400Y-596105D01*
X242000Y-595305D01*
X242700Y-594771D01*
X243500Y-594638D01*
X244300Y-594771D01*
X245000Y-595305D01*
X245600Y-596105D01*
X246000Y-597038D01*
X246200Y-598105D01*
Y-599171D01*
X246000Y-600238D01*
X245600Y-601171D01*
X245000Y-601971D01*
X244300Y-602505D01*
X243500Y-602638D01*
G01X249500D02*
Y-594638D01*
X251900D01*
X252700Y-595038D01*
X253300Y-595971D01*
X253500Y-597038D01*
X253300Y-598105D01*
X252800Y-598905D01*
X251900Y-599305D01*
X249500D01*
G01X255500Y-577638D02*
Y-569638D01*
X254300Y-571238D01*
G01Y-577638D02*
X256700D01*
G01X258751Y647987D02*
X257431Y649307D01*
Y653656D01*
G01X264213Y649037D02*
Y650559D01*
X262746Y652026D01*
Y653656D01*
G01X265166Y644555D02*
Y645007D01*
X264213Y645960D01*
Y649037D01*
G01X296957Y683158D02*
Y684818D01*
X295476Y686299D01*
Y687897D01*
G01X297896Y678796D02*
X296957Y679735D01*
Y683158D01*
G01X328600Y-620971D02*
X329200Y-620171D01*
X329900Y-619771D01*
X330700Y-619638D01*
X331700Y-619905D01*
X332400Y-620571D01*
X332600Y-621371D01*
X332500Y-622172D01*
X332100Y-622838D01*
X330100Y-624171D01*
X329200Y-625105D01*
X328600Y-626438D01*
X328400Y-627638D01*
X332600D01*
G01X338500Y-619638D02*
X337700Y-619905D01*
X337100Y-620571D01*
X336700Y-621371D01*
X336400Y-622438D01*
X336300Y-623638D01*
X336400Y-624838D01*
X336700Y-625905D01*
X337100Y-626705D01*
X337700Y-627371D01*
X338500Y-627638D01*
X339300Y-627371D01*
X339900Y-626705D01*
X340300Y-625905D01*
X340600Y-624838D01*
X340700Y-623638D01*
X340600Y-622438D01*
X340300Y-621371D01*
X339900Y-620571D01*
X339300Y-619905D01*
X338500Y-619638D01*
G01X344600Y-620971D02*
X345200Y-620171D01*
X345900Y-619771D01*
X346700Y-619638D01*
X347700Y-619905D01*
X348400Y-620571D01*
X348600Y-621371D01*
X348500Y-622172D01*
X348100Y-622838D01*
X346100Y-624171D01*
X345200Y-625105D01*
X344600Y-626438D01*
X344400Y-627638D01*
X348600D01*
G01X352300Y-626038D02*
X352900Y-626971D01*
X353700Y-627505D01*
X354600Y-627638D01*
X355400Y-627505D01*
X356200Y-626838D01*
X356700Y-626038D01*
X356800Y-625238D01*
X356600Y-624305D01*
X355900Y-623638D01*
X355200Y-623371D01*
X354300D01*
G01X355200D02*
X355800Y-622971D01*
X356300Y-622305D01*
X356500Y-621505D01*
X356300Y-620705D01*
X355800Y-620038D01*
X354900Y-619638D01*
X354000Y-619771D01*
X353100Y-620305D01*
G01X360700Y-627905D02*
X364300Y-619638D01*
G01X370500D02*
X369700Y-619905D01*
X369100Y-620571D01*
X368700Y-621371D01*
X368400Y-622438D01*
X368300Y-623638D01*
X368400Y-624838D01*
X368700Y-625905D01*
X369100Y-626705D01*
X369700Y-627371D01*
X370500Y-627638D01*
X371300Y-627371D01*
X371900Y-626705D01*
X372300Y-625905D01*
X372600Y-624838D01*
X372700Y-623638D01*
X372600Y-622438D01*
X372300Y-621371D01*
X371900Y-620571D01*
X371300Y-619905D01*
X370500Y-619638D01*
G01X379700Y-627638D02*
Y-619638D01*
X376000Y-625371D01*
X381000D01*
G01X384700Y-627905D02*
X388300Y-619638D01*
G01X394500Y-627638D02*
Y-619638D01*
X393300Y-621238D01*
G01Y-627638D02*
X395700D01*
G01X402300D02*
X402500Y-625905D01*
X402800Y-624438D01*
X403200Y-623105D01*
X403700Y-621638D01*
X404500Y-619638D01*
X400500D01*
G01X328300Y-602638D02*
Y-594638D01*
X330300D01*
X331100Y-595038D01*
X331700Y-595571D01*
X332200Y-596371D01*
X332600Y-597305D01*
X332700Y-598638D01*
X332600Y-599971D01*
X332200Y-600905D01*
X331700Y-601705D01*
X331100Y-602238D01*
X330300Y-602638D01*
X328300D01*
G01X336000D02*
X338500Y-594638D01*
X341000Y-602638D01*
G01X340100Y-599838D02*
X336900D01*
G01X344600Y-602638D02*
Y-594638D01*
X348400D01*
G01X347000Y-598505D02*
X344600D01*
G01X354500Y-594638D02*
X353700Y-594905D01*
X353100Y-595571D01*
X352700Y-596371D01*
X352400Y-597438D01*
X352300Y-598638D01*
X352400Y-599838D01*
X352700Y-600905D01*
X353100Y-601705D01*
X353700Y-602371D01*
X354500Y-602638D01*
X355300Y-602371D01*
X355900Y-601705D01*
X356300Y-600905D01*
X356600Y-599838D01*
X356700Y-598638D01*
X356600Y-597438D01*
X356300Y-596371D01*
X355900Y-595571D01*
X355300Y-594905D01*
X354500Y-594638D01*
G01X362500D02*
Y-602638D01*
G01X360200Y-594638D02*
X364800D01*
G01X367900Y-602638D02*
Y-594638D01*
X370500Y-601305D01*
X373100Y-594638D01*
Y-602638D01*
G01X379300Y-598371D02*
X379700Y-597971D01*
X380000Y-597305D01*
X380200Y-596371D01*
X380000Y-595571D01*
X379600Y-595038D01*
X378900Y-594638D01*
X376200D01*
Y-602638D01*
X379500D01*
X380200Y-602105D01*
X380600Y-601305D01*
X380800Y-600371D01*
X380600Y-599438D01*
X380000Y-598638D01*
X379300Y-598371D01*
X376200D01*
G01X384300Y-601038D02*
X384900Y-601971D01*
X385700Y-602505D01*
X386600Y-602638D01*
X387400Y-602505D01*
X388200Y-601838D01*
X388700Y-601038D01*
X388800Y-600238D01*
X388600Y-599305D01*
X387900Y-598638D01*
X387200Y-598371D01*
X386300D01*
G01X387200D02*
X387800Y-597971D01*
X388300Y-597305D01*
X388500Y-596505D01*
X388300Y-595705D01*
X387800Y-595038D01*
X386900Y-594638D01*
X386000Y-594771D01*
X385100Y-595305D01*
G01X393300Y-594638D02*
X395700D01*
G01X394500D02*
Y-602638D01*
G01X393300D02*
X395700D01*
G01X404700Y-595305D02*
X404100Y-594905D01*
X403400Y-594638D01*
X402600D01*
X401700Y-595038D01*
X401000Y-595705D01*
X400500Y-596505D01*
X400100Y-597838D01*
X400000Y-599038D01*
X400200Y-600238D01*
X400500Y-601038D01*
X401100Y-601838D01*
X401800Y-602371D01*
X402500Y-602638D01*
X403200D01*
X403900Y-602371D01*
X404500Y-601971D01*
X405000Y-601438D01*
G01X410500Y-594638D02*
X409700Y-594905D01*
X409100Y-595571D01*
X408700Y-596371D01*
X408400Y-597438D01*
X408300Y-598638D01*
X408400Y-599838D01*
X408700Y-600905D01*
X409100Y-601705D01*
X409700Y-602371D01*
X410500Y-602638D01*
X411300Y-602371D01*
X411900Y-601705D01*
X412300Y-600905D01*
X412600Y-599838D01*
X412700Y-598638D01*
X412600Y-597438D01*
X412300Y-596371D01*
X411900Y-595571D01*
X411300Y-594905D01*
X410500Y-594638D01*
G01X322931Y708047D02*
Y703698D01*
X324251Y702378D01*
G01X346100Y-577638D02*
Y-569638D01*
X349900D01*
G01X348500Y-573505D02*
X346100D01*
G01X356000Y-569638D02*
X355200Y-569905D01*
X354600Y-570571D01*
X354200Y-571371D01*
X353900Y-572438D01*
X353800Y-573638D01*
X353900Y-574838D01*
X354200Y-575905D01*
X354600Y-576705D01*
X355200Y-577371D01*
X356000Y-577638D01*
X356800Y-577371D01*
X357400Y-576705D01*
X357800Y-575905D01*
X358100Y-574838D01*
X358200Y-573638D01*
X358100Y-572438D01*
X357800Y-571371D01*
X357400Y-570571D01*
X356800Y-569905D01*
X356000Y-569638D01*
G01X364000D02*
Y-577638D01*
G01X361700Y-569638D02*
X366300D01*
G01X372600Y-573638D02*
X374600D01*
Y-576038D01*
X374000Y-576838D01*
X373300Y-577371D01*
X372300Y-577638D01*
X371300Y-577371D01*
X370600Y-576838D01*
X370000Y-576038D01*
X369600Y-575105D01*
X369400Y-574038D01*
Y-573105D01*
X369600Y-572305D01*
X370000Y-571371D01*
X370600Y-570571D01*
X371200Y-570038D01*
X372000Y-569638D01*
X372700D01*
X373500Y-569905D01*
X374100Y-570438D01*
G01X377000Y-580305D02*
X383000D01*
G01X385400Y-577638D02*
Y-569638D01*
X388000Y-576305D01*
X390600Y-569638D01*
Y-577638D01*
G01X396800Y-573371D02*
X397200Y-572971D01*
X397500Y-572305D01*
X397700Y-571371D01*
X397500Y-570571D01*
X397100Y-570038D01*
X396400Y-569638D01*
X393700D01*
Y-577638D01*
X397000D01*
X397700Y-577105D01*
X398100Y-576305D01*
X398300Y-575371D01*
X398100Y-574438D01*
X397500Y-573638D01*
X396800Y-573371D01*
X393700D01*
G01X417000Y-630638D02*
Y-622638D01*
X415800Y-624238D01*
G01Y-630638D02*
X418200D01*
G01X423100Y-627305D02*
X423800Y-626371D01*
X424400Y-625838D01*
X425200Y-625571D01*
X425900Y-625838D01*
X426400Y-626371D01*
X426800Y-627171D01*
X426900Y-628105D01*
X426800Y-628905D01*
X426400Y-629705D01*
X425800Y-630371D01*
X425100Y-630638D01*
X424300Y-630371D01*
X423600Y-629572D01*
X423200Y-628371D01*
X423100Y-627038D01*
X423300Y-625305D01*
X423600Y-624371D01*
X424100Y-623438D01*
X424800Y-622771D01*
X425500Y-622638D01*
X426200Y-622905D01*
X426700Y-623571D01*
G01X433000Y-630905D02*
X432800Y-630771D01*
Y-630505D01*
X433000Y-630371D01*
X433200Y-630505D01*
Y-630771D01*
X433000Y-630905D01*
G01X439100Y-627305D02*
X439800Y-626371D01*
X440400Y-625838D01*
X441200Y-625571D01*
X441900Y-625838D01*
X442400Y-626371D01*
X442800Y-627171D01*
X442900Y-628105D01*
X442800Y-628905D01*
X442400Y-629705D01*
X441800Y-630371D01*
X441100Y-630638D01*
X440300Y-630371D01*
X439600Y-629572D01*
X439200Y-628371D01*
X439100Y-627038D01*
X439300Y-625305D01*
X439600Y-624371D01*
X440100Y-623438D01*
X440800Y-622771D01*
X441500Y-622638D01*
X442200Y-622905D01*
X442700Y-623571D01*
G01X462000Y-630638D02*
Y-622638D01*
X460800Y-624238D01*
G01Y-630638D02*
X463200D01*
G01X469800D02*
X470000Y-628905D01*
X470300Y-627438D01*
X470700Y-626105D01*
X471200Y-624638D01*
X472000Y-622638D01*
X468000D01*
G01X478000Y-630905D02*
X477800Y-630771D01*
Y-630505D01*
X478000Y-630371D01*
X478200Y-630505D01*
Y-630771D01*
X478000Y-630905D01*
G01X484100Y-623971D02*
X484700Y-623171D01*
X485400Y-622771D01*
X486200Y-622638D01*
X487200Y-622905D01*
X487900Y-623571D01*
X488100Y-624371D01*
X488000Y-625172D01*
X487600Y-625838D01*
X485600Y-627171D01*
X484700Y-628105D01*
X484100Y-629438D01*
X483900Y-630638D01*
X488100D01*
G01X486200Y-598305D02*
X485600Y-597905D01*
X484900Y-597638D01*
X484100D01*
X483200Y-598038D01*
X482500Y-598705D01*
X482000Y-599505D01*
X481600Y-600838D01*
X481500Y-602038D01*
X481700Y-603238D01*
X482000Y-604038D01*
X482600Y-604838D01*
X483300Y-605371D01*
X484000Y-605638D01*
X484700D01*
X485400Y-605371D01*
X486000Y-604971D01*
X486500Y-604438D01*
G01X622434Y1362366D02*
Y1367166D01*
G01X629246Y1373044D02*
X627928D01*
X626486Y1371602D01*
Y1365078D01*
X623774Y1362366D01*
X622434D01*
G01X642925Y449862D02*
X639002D01*
G01X638436Y1356512D02*
Y1357996D01*
X637908Y1358524D01*
Y1362808D01*
G01X639482D02*
Y1359466D01*
X642436Y1356512D01*
G01X641057Y1362808D02*
Y1359447D01*
X642207Y1358297D01*
X644451D01*
X646236Y1356512D01*
G01X642632Y1362808D02*
Y1359800D01*
X642965Y1359467D01*
X644670D01*
X648786Y1357762D01*
X650036Y1356512D01*
G01X644207Y1362808D02*
Y1361135D01*
X644735Y1360607D01*
X645637D01*
X652643Y1357705D01*
X653836Y1356512D01*
G01X645782Y1362808D02*
Y1362360D01*
X646395Y1361747D01*
X656990Y1357358D01*
X657836Y1356512D01*
G01X648144Y1369895D02*
X649798D01*
X653376Y1366317D01*
Y1365793D01*
G01X648144Y1371470D02*
X650982D01*
X652590Y1369862D01*
X653101D01*
G01X634758Y1381706D02*
Y1384220D01*
X634995Y1384457D01*
G01X636333Y1381706D02*
Y1382923D01*
X637901Y1384491D01*
X638053D01*
G01X648144Y1373044D02*
X652605D01*
X653149Y1372500D01*
G01X648144Y1376194D02*
X650548D01*
X652391Y1378037D01*
X653117D01*
G01X648144Y1374619D02*
X651962D01*
X652651Y1375308D01*
G01X653376Y1365793D02*
X654189D01*
X655679Y1367283D01*
G01X658797Y1363394D02*
X661719D01*
G01X653117Y1378037D02*
X654011Y1378931D01*
X655593D01*
G01X652651Y1375308D02*
X652898Y1375061D01*
X655627D01*
G01X674711Y504895D02*
X672699Y506907D01*
G01X666711Y504895D02*
X664741Y506865D01*
G01X696283Y543862D02*
Y546530D01*
G01X704598Y732288D02*
Y728416D01*
X698756Y722574D01*
Y676388D01*
G01X702553Y735811D02*
Y728872D01*
X697359Y723678D01*
Y678934D01*
X694837Y676412D01*
G01X705075Y1556500D02*
Y1560433D01*
X705215Y1560573D01*
G01D02*
X708427D01*
X708500Y1560500D01*
G01X705185Y1564523D02*
Y1568523D01*
G01Y1572523D02*
X708600D01*
G01X705185Y1568523D02*
X708978D01*
X708994Y1568507D01*
G01X705185Y1576523D02*
X710550D01*
G01X698500Y1590925D02*
X700575D01*
X701000Y1590500D01*
X706500D01*
X708000Y1589000D01*
Y1587000D01*
X709827Y1585173D01*
X710420D01*
G01X705075Y1596500D02*
Y1592633D01*
X705185Y1592523D01*
G01D02*
X707133D01*
X710360Y1589296D01*
G01X708500Y1560500D02*
X712500Y1564500D01*
Y1567500D01*
X713873Y1568873D01*
X716544D01*
X720585Y1572914D01*
Y1573552D01*
G01X724110Y1561825D02*
Y1563022D01*
X722210Y1564922D01*
Y1566722D01*
X724128Y1571353D01*
Y1573552D01*
G01X708600Y1572523D02*
X710150Y1574073D01*
X711548D01*
X715407Y1577932D01*
X716697D01*
G01X708994Y1568507D02*
X711660Y1571173D01*
Y1572053D01*
X715767Y1576160D01*
X716697D01*
G01X714900Y1571273D02*
X716534D01*
X718813Y1573552D01*
G01X710550Y1576523D02*
X711980D01*
X714980Y1579523D01*
X716516D01*
X716697Y1579704D01*
G01Y1585018D02*
X715481D01*
X715326Y1585173D01*
X710420D01*
G01X710360Y1589296D02*
X712947D01*
X715453Y1586790D01*
X716697D01*
G01X750074Y648739D02*
Y650366D01*
X727618Y672822D01*
Y680601D01*
X772738Y725721D01*
X779948D01*
X788537Y734310D01*
Y734410D01*
G01X793131Y734310D02*
X781799Y722978D01*
X771762D01*
X728867Y680083D01*
Y673365D01*
X753483Y648749D01*
G01X730837Y678940D02*
X771842Y719945D01*
X799769D01*
X811438Y731614D01*
X818777Y749333D01*
Y796910D01*
X821878Y800011D01*
X822794D01*
G01X726475Y1571293D02*
X725547Y1570365D01*
X724175Y1567054D01*
Y1566333D01*
G01X725900Y1573552D02*
Y1571868D01*
X726475Y1571293D01*
G01X723050Y1599358D02*
X725900Y1596508D01*
Y1591170D01*
G01X725175Y1606733D02*
Y1603149D01*
X726550Y1601774D01*
Y1599358D01*
G01D02*
X723050D01*
G01X742579Y676093D02*
Y678839D01*
X778137Y714397D01*
X802069D01*
X816982Y729310D01*
X824118Y746538D01*
Y758630D01*
X822579Y760169D01*
G01X742189Y1579704D02*
X743859D01*
X747109Y1576457D01*
X747110Y1575863D01*
G01D02*
X751875D01*
X752035Y1576023D01*
G01Y1580023D02*
X747270D01*
X747110Y1579863D01*
G01D02*
X745498Y1581475D01*
X742189D01*
G01X747150Y1583247D02*
X742189D01*
G01X752035Y1584023D02*
X747926D01*
X747150Y1583247D01*
G01X752035Y1589023D02*
Y1589099D01*
X749167Y1591967D01*
G01D02*
X747326D01*
X744325Y1588966D01*
Y1587516D01*
X743599Y1586790D01*
X742189D01*
G01X766225Y1574733D02*
X768241Y1572717D01*
X771592D01*
G01X755185Y1576023D02*
X757610D01*
G01X766225Y1578733D02*
X767350D01*
X768750Y1577333D01*
X771450D01*
G01X766212Y1570633D02*
Y1568043D01*
G01D02*
X770960D01*
X774650Y1571733D01*
Y1573877D01*
X776246Y1575473D01*
X776718D01*
G01X755185Y1580023D02*
X757650D01*
G01X763075Y1591733D02*
X761121D01*
X760521Y1592333D01*
Y1595500D01*
G01X766225Y1591733D02*
X771650D01*
G01X766225Y1587733D02*
X769233D01*
X769833Y1587133D01*
X771550D01*
G01X768700Y543575D02*
Y558692D01*
X773463Y563455D01*
G01X771592Y1572717D02*
X776317Y1577442D01*
X776768D01*
G01X771450Y1577333D02*
X773527Y1579410D01*
X776768D01*
G01X771650Y1591733D02*
X773462D01*
X775942Y1589253D01*
X776718D01*
G01X771550Y1587133D02*
Y1586349D01*
X772999Y1584900D01*
X775668D01*
X776084Y1585316D01*
X776768D01*
G01Y1587284D02*
X774420D01*
G01X794386Y1579410D02*
X795973D01*
X799150Y1576233D01*
Y1575233D01*
G01X794386Y1581379D02*
X799150D01*
G01X794386Y1583347D02*
X796650D01*
G01X794436Y1589253D02*
X794942D01*
X795542Y1589853D01*
Y1599487D01*
X799888Y1603833D01*
G01X807725Y1578633D02*
X808850D01*
X812000Y1575483D01*
X813400D01*
G01X799150Y1575233D02*
X799750Y1574633D01*
X804575D01*
G01X807725D02*
X810150D01*
G01X807725Y1582633D02*
X808249D01*
X811472Y1579410D01*
X813150D01*
G01X807725Y1570633D02*
X813150D01*
G01X799150Y1581379D02*
Y1586886D01*
X802897Y1590633D01*
X804575D01*
G01X807725Y1594633D02*
X809439D01*
X813049Y1591023D01*
Y1590633D01*
G01X807725Y1598633D02*
X810150D01*
G01X799888Y1603833D02*
X800588Y1603133D01*
X804075D01*
X804575Y1602633D01*
G01Y1606633D02*
X802150D01*
G01X807725D02*
X810498D01*
X813571Y1603560D01*
Y1597534D01*
G01X813400Y1575483D02*
X814903D01*
X816862Y1577442D01*
X818768D01*
G01X813150Y1579410D02*
X818768D01*
G01X813150Y1570633D02*
X817990Y1575473D01*
X818718D01*
G01X813571Y1597534D02*
Y1596812D01*
X816650Y1593733D01*
Y1590633D01*
X818030Y1589253D01*
X818718D01*
G01X813049Y1590633D02*
Y1587533D01*
X815266Y1585316D01*
X818768D01*
G01Y1587284D02*
X816150D01*
G01X836386Y1579410D02*
X837973D01*
X841150Y1576233D01*
Y1575233D01*
G01D02*
X841750Y1574633D01*
X846575D01*
G01Y1590633D02*
X844883D01*
X841150Y1586900D01*
Y1581379D01*
G01D02*
X836386D01*
G01Y1583347D02*
X838650D01*
G01X841924Y1603879D02*
X837428Y1599383D01*
Y1589853D01*
X836828Y1589253D01*
X836436D01*
G01X846575Y1602633D02*
X846075Y1603133D01*
X842670D01*
X841924Y1603879D01*
G01X860768Y1577442D02*
X858862D01*
X856903Y1575483D01*
X855400D01*
G01D02*
X852250Y1578633D01*
X849725D01*
G01Y1574633D02*
X852150D01*
G01X855150Y1579410D02*
X853774D01*
X850551Y1582633D01*
X849725D01*
G01X860768Y1579410D02*
X855150D01*
G01Y1570633D02*
X849725D01*
G01X860718Y1575473D02*
X860098D01*
X855258Y1570633D01*
X855150D01*
G01X856015Y1596916D02*
Y1596368D01*
X858650Y1593733D01*
Y1590633D01*
X860030Y1589253D01*
X860718D01*
G01X849725Y1594633D02*
X851439D01*
X855049Y1591023D01*
Y1590633D01*
G01D02*
X855050Y1590632D01*
Y1587532D01*
X857266Y1585316D01*
X860768D01*
G01X846575Y1606633D02*
X844150D01*
G01X849725D02*
X852498D01*
X855007Y1604124D01*
Y1597924D01*
X856015Y1596916D01*
G01X860768Y1587284D02*
X858150D01*
G01X888575Y1574633D02*
X883750D01*
X883150Y1575233D01*
G01D02*
Y1576233D01*
X879973Y1579410D01*
X878386D01*
G01X883150Y1581379D02*
Y1586886D01*
X886897Y1590633D01*
X888575D01*
G01X878386Y1581379D02*
X883150D01*
G01X878386Y1583347D02*
X880650D01*
G01X883905Y1603864D02*
X879523Y1599482D01*
Y1589853D01*
X878923Y1589253D01*
X878436D01*
G01X888575Y1602633D02*
X888075Y1603133D01*
X884636D01*
X883905Y1603864D01*
G01X888575Y1606633D02*
X886150D01*
G01X891725Y1578633D02*
X893536D01*
X897381Y1574788D01*
G01D02*
X898208D01*
X900862Y1577442D01*
X902768D01*
G01X891725Y1574633D02*
X894150D01*
G01X897150Y1579410D02*
X902768D01*
G01X891725Y1582633D02*
X892551D01*
X895774Y1579410D01*
X897150D01*
G01Y1570633D02*
X897258D01*
X902098Y1575473D01*
X902718D01*
G01X891725Y1570633D02*
X897150D01*
G01X891725Y1606633D02*
X894498D01*
X897007Y1604124D01*
Y1597376D01*
X898065Y1596318D01*
G01D02*
X900650Y1593733D01*
Y1590633D01*
X902030Y1589253D01*
X902718D01*
G01X891725Y1594633D02*
X893439D01*
X897049Y1591023D01*
Y1590633D01*
G01D02*
X897050Y1590632D01*
Y1587532D01*
X899266Y1585316D01*
X902768D01*
G01Y1587284D02*
X900150D01*
G01X902482Y1140558D02*
X903900Y1141976D01*
X905618D01*
G01X920386Y1579410D02*
X922473D01*
X925650Y1576233D01*
G01D02*
X927650Y1578233D01*
X930575D01*
G01X925650Y1581379D02*
X926504Y1582233D01*
X930575D01*
G01X920386Y1581379D02*
X925650D01*
G01X920386Y1583347D02*
X922650D01*
G01X925726Y1592261D02*
X928547D01*
X930575Y1590233D01*
G01X920436Y1589253D02*
X921248D01*
X924256Y1592261D01*
X925726D01*
G01X933725Y1578233D02*
X936150D01*
G01X949507Y1140558D02*
X950925Y1141976D01*
X952643D01*
G01X1210100Y1436500D02*
Y1434600D01*
X1212339Y1432361D01*
Y1431319D01*
G01X1213000Y1435000D02*
X1213913Y1434087D01*
Y1431319D01*
G01X1210400Y1440000D02*
X1211936Y1439364D01*
X1215488Y1435812D01*
Y1431319D01*
G01X1214900Y1439800D02*
X1217063Y1437637D01*
Y1431319D01*
G01X1219500Y1436000D02*
X1218638Y1435138D01*
Y1431319D01*
G01X1221837Y1438800D02*
X1221800Y1438763D01*
Y1434899D01*
X1220213Y1433312D01*
Y1431319D01*
G01X1226200Y1444300D02*
X1228087Y1439743D01*
Y1431319D01*
G01X1222700Y1446300D02*
Y1444134D01*
X1225796Y1441038D01*
X1226512Y1439309D01*
Y1431319D01*
G01X1220200Y1449100D02*
Y1444420D01*
X1224230Y1440390D01*
X1224937Y1438682D01*
Y1431319D01*
G01X1229661D02*
Y1442000D01*
G01X1468011Y886001D02*
X1466173Y887048D01*
G01X1475413Y879623D02*
X1473575Y880670D01*
G01X1471712Y886001D02*
X1469874Y887048D01*
G01X1510682Y547977D02*
Y543977D01*
G01X1507109Y550059D02*
X1509191Y547977D01*
X1510682D01*
G01X1504598Y708215D02*
Y706449D01*
G01X1545728Y879623D02*
X1545961D01*
X1547460Y878124D01*
G01X1632824Y1420450D02*
Y1416970D01*
X1634065Y1415729D01*
G01D02*
X1637100Y1418764D01*
Y1424820D01*
X1638608Y1426328D01*
X1639834D01*
G01X1645346Y1434990D02*
Y1437317D01*
X1645979Y1437950D01*
G01X1650400Y1437820D02*
X1648630D01*
X1647254Y1436444D01*
X1646921Y1435641D01*
Y1434990D01*
G01X1661179Y1402860D02*
X1662137Y1401902D01*
Y1398599D01*
G01X1666235Y1416678D02*
X1664177D01*
X1664147Y1416708D01*
X1663847D01*
X1663607Y1416948D01*
X1661807D01*
G01D02*
Y1420011D01*
X1660214Y1421604D01*
X1658732D01*
G01Y1423179D02*
X1660427D01*
X1662038Y1421568D01*
X1663777D01*
G01X1658732Y1426328D02*
X1664187D01*
X1664237Y1426278D01*
G01X1658732Y1424754D02*
X1661570D01*
X1662146Y1424178D01*
X1662487D01*
G01X1666181Y1432215D02*
X1663873D01*
X1661136Y1429478D01*
X1658732D01*
G01Y1427903D02*
X1662550D01*
X1663239Y1428592D01*
G01X1662137Y1398599D02*
Y1396819D01*
X1663599Y1395357D01*
Y1393759D01*
G01X1663777Y1421568D02*
X1664778Y1420567D01*
X1666267D01*
G01X1663239Y1428592D02*
X1663486Y1428345D01*
X1666215D01*
G01X1693961Y1402960D02*
X1694919Y1402002D01*
Y1398699D01*
G01D02*
Y1396919D01*
X1696381Y1395457D01*
Y1393859D01*
G01X1720845Y1673759D02*
Y1668498D01*
G01X1735463Y1651965D02*
X1736463Y1652965D01*
Y1659465D01*
X1738867Y1661869D01*
X1739880D01*
G01X1730038Y1672465D02*
X1732363D01*
X1735085Y1669743D01*
X1739880D01*
G01X1730038Y1667965D02*
X1732462D01*
G01X1730038Y1663465D02*
X1734462D01*
X1734962Y1662965D01*
G01X1734763Y1680465D02*
X1733763Y1681465D01*
X1730038D01*
G01X1734763Y1680465D02*
X1737236Y1677992D01*
Y1675767D01*
X1738535Y1674468D01*
X1739880D01*
G01X1730038Y1681465D02*
Y1684347D01*
X1729436Y1684949D01*
Y1687090D01*
G01D02*
X1729427Y1687081D01*
X1725423D01*
G01X1748904Y1585905D02*
X1748403Y1585404D01*
X1744879D01*
X1744379Y1584904D01*
Y1582976D01*
X1747289Y1580066D01*
Y1578302D01*
X1748197Y1577394D01*
Y1575375D01*
G01X1747986Y1686215D02*
Y1682988D01*
X1745392Y1680394D01*
Y1678405D01*
G01X1751340Y1686140D02*
Y1684342D01*
X1746967Y1679969D01*
Y1678405D01*
G01X1753512Y1583478D02*
Y1575375D01*
G01X1783940D02*
Y1577065D01*
X1781845Y1579160D01*
Y1580912D01*
X1780579Y1582178D01*
G01D02*
Y1583692D01*
X1782719Y1585832D01*
G01X1789811Y183719D02*
X1789260D01*
X1785051Y179510D01*
Y177578D01*
G01X1789255Y1575375D02*
Y1583154D01*
X1789379Y1583278D01*
X1789294D01*
G01X1806547Y192193D02*
Y191347D01*
X1807029Y190865D01*
Y187425D01*
X1806470Y186866D01*
G01D02*
X1807711Y185625D01*
Y183719D01*
G54D285*
X1004868Y194419D03*
G36*
G01X453843Y1698263D02*
G02X441043Y1711068I-12800J5D01*
G02X453843Y1698273I0J-12800D01*
G01X449293D01*
G03X441043Y1690017I-8250J-5D01*
G03X449293Y1698263I0J8251D01*
G01X453843D01*
G37*
G36*
G01X1429237D02*
G02X1416437Y1711068I-12800J5D01*
G02X1429237Y1698273I0J-12800D01*
G01X1424687D01*
G03X1416437Y1690017I-8250J-5D01*
G03X1424687Y1698263I0J8251D01*
G01X1429237D01*
G37*
G54D267*
X900590Y175177D03*
X945078Y155197D03*
G54D84*
X139770Y445819D03*
X154770D03*
X149770D03*
X144770D03*
X171550Y445279D03*
X166550D03*
X181550D03*
X176550D03*
X943902Y1505029D03*
X958902D03*
X953902D03*
X948902D03*
X977268D03*
X972268D03*
X967268D03*
X982268D03*
X990634D03*
X1005634D03*
X1000634D03*
X995634D03*
X1019000D03*
X1014000D03*
X1029000D03*
X1024000D03*
X1047366D03*
X1042366D03*
X1037366D03*
X1065732D03*
X1060732D03*
X1052366D03*
X1075732D03*
X1070732D03*
X1094098D03*
X1089098D03*
X1084098D03*
X1099098D03*
X1730571Y286855D03*
X1735571D03*
X1740571D03*
X1745571D03*
G54D249*
X805690Y204724D03*
X1057659D03*
G54D39*
X50773Y754595D03*
Y775855D03*
G54D159*
X366588Y283311D03*
X773766Y270763D03*
G54D168*
X410379Y1569803D03*
X405379D03*
X400379D03*
Y1590275D03*
X405379D03*
X410379D03*
X415379Y1569803D03*
X425374D03*
X415379Y1590275D03*
X425374D03*
X440374Y1569803D03*
X435374D03*
X430374D03*
Y1590275D03*
X435374D03*
X440374D03*
X649284Y1658333D03*
X644284D03*
X639284D03*
Y1678805D03*
X644284D03*
X649284D03*
X654284Y1658333D03*
X662971Y1658547D03*
X654284Y1678805D03*
X662971Y1679019D03*
X677971Y1658547D03*
X672971D03*
X667971D03*
Y1679019D03*
X672971D03*
X677971D03*
X1169187Y1662159D03*
Y1682631D03*
X1184187Y1662159D03*
X1179187D03*
X1174187D03*
Y1682631D03*
X1179187D03*
X1184187D03*
X1661101Y1675927D03*
X1656101D03*
X1651101D03*
Y1696399D03*
X1656101D03*
X1661101D03*
X1666101Y1675927D03*
Y1696399D03*
G54D258*
X821993Y539872D03*
X821347Y557607D03*
Y565087D03*
X829867Y536132D03*
Y543612D03*
X829221Y561347D03*
X1160163Y1441260D03*
Y1448740D03*
X1168037Y1445000D03*
X1667635Y210191D03*
X1675509Y206451D03*
Y213931D03*
G54D186*
X481156Y297251D03*
Y299219D03*
X474464Y297251D03*
X481156Y301187D03*
X474464D03*
X568156Y310187D03*
Y306251D03*
Y308219D03*
X561464Y306251D03*
Y310187D03*
G54D276*
X916642Y1147586D03*
X963667D03*
X1326435Y553526D03*
X1632560Y553181D03*
G54D93*
X131703Y1663229D03*
G54D195*
X474070Y303156D03*
X561070Y312156D03*
G54D294*
X1156378Y133866D03*
X1173858Y207205D03*
X1391260Y174213D03*
G54D75*
X113065Y1323736D03*
Y1332988D03*
X145665Y1323736D03*
Y1332988D03*
X178165Y1323736D03*
Y1332988D03*
X210765Y1323736D03*
Y1332988D03*
X243365Y1323736D03*
Y1332988D03*
X257991Y697129D03*
Y706381D03*
X277665Y1277590D03*
Y1286842D03*
X290721Y731370D03*
Y740622D03*
X310561Y1277505D03*
Y1286757D03*
X323491Y760772D03*
Y751520D03*
X343465Y1277505D03*
Y1286757D03*
X356551Y760684D03*
Y751432D03*
X375961Y1277562D03*
Y1286814D03*
X389591Y760572D03*
Y751320D03*
X408847Y1297036D03*
Y1306288D03*
X425562Y733535D03*
Y742787D03*
X457090Y718172D03*
Y708920D03*
X489462Y682420D03*
Y691672D03*
X522062Y657572D03*
Y648320D03*
X1084803Y1323717D03*
Y1332969D03*
X1117403Y1323717D03*
Y1332969D03*
X1150103Y1323717D03*
Y1332969D03*
X1183003Y1323717D03*
Y1332969D03*
X1215803Y1323717D03*
Y1332969D03*
X1253794Y1277571D03*
Y1286823D03*
X1286690Y1277486D03*
Y1286738D03*
X1319594Y1277486D03*
Y1286738D03*
X1352090Y1277543D03*
Y1286795D03*
X1368861Y666465D03*
Y675717D03*
X1384976Y1297017D03*
Y1306269D03*
X1401243Y699363D03*
Y708615D03*
X1433843Y731943D03*
Y741195D03*
X1466761Y760772D03*
Y751520D03*
X1499843Y760772D03*
Y751520D03*
X1532643Y760772D03*
Y751520D03*
X1567114Y729580D03*
Y738832D03*
X1600244Y695811D03*
Y705063D03*
X1633043Y686063D03*
Y676811D03*
G54D48*
X64823Y756832D03*
Y760178D03*
X64923Y795316D03*
Y832127D03*
Y868938D03*
Y905750D03*
Y942561D03*
Y1089805D03*
Y1126616D03*
Y1163427D03*
Y1200238D03*
Y1237049D03*
X80915Y756766D03*
X73873D03*
Y760266D03*
X69323Y776911D03*
X80915Y763766D03*
X73933Y768706D03*
X73960Y766090D03*
X80015Y786950D03*
X69323Y783604D03*
X74773Y790297D03*
X81065Y791970D03*
X69323Y780257D03*
Y786950D03*
X80015Y796989D03*
X69323Y807029D03*
X74773Y800336D03*
X69323Y803682D03*
Y793643D03*
Y796989D03*
Y813722D03*
Y820415D03*
Y817068D03*
Y810375D03*
X80015Y823761D03*
Y833800D03*
X81065Y828781D03*
X74773Y827108D03*
Y837147D03*
X69323Y823761D03*
Y830454D03*
Y833800D03*
Y843840D03*
Y850533D03*
Y840493D03*
Y847186D03*
X80015Y860572D03*
X81065Y865592D03*
X69323Y857226D03*
X74773Y863919D03*
X69323Y853879D03*
Y860572D03*
X80015Y870611D03*
X69323Y880651D03*
X74773Y873958D03*
X69323Y877304D03*
Y867265D03*
Y870611D03*
Y887344D03*
Y894037D03*
Y883997D03*
Y890690D03*
X74773Y900730D03*
X80015Y907423D03*
X74773Y910769D03*
X80015Y897383D03*
X81065Y902403D03*
X69323Y897383D03*
Y904076D03*
Y907423D03*
Y924155D03*
Y917462D03*
Y914115D03*
Y920808D03*
X81065Y939214D03*
X80015Y934194D03*
X74773Y937541D03*
X69323Y930848D03*
Y927501D03*
Y934194D03*
Y940887D03*
X80015Y944234D03*
X69323Y954273D03*
X74773Y947580D03*
X69323Y950926D03*
Y944234D03*
Y960966D03*
Y967659D03*
Y964312D03*
Y957619D03*
Y971005D03*
Y974352D03*
Y981045D03*
Y977698D03*
Y984391D03*
Y987737D03*
Y994430D03*
Y1001123D03*
Y997777D03*
Y991084D03*
Y1004470D03*
Y1034588D03*
Y1041281D03*
Y1031241D03*
Y1037934D03*
Y1044627D03*
Y1047974D03*
Y1054667D03*
Y1058013D03*
Y1051320D03*
Y1071399D03*
Y1061360D03*
Y1074745D03*
Y1068052D03*
Y1064706D03*
X80015Y1081438D03*
X81065Y1086458D03*
X74773Y1084785D03*
X69323Y1078092D03*
Y1081438D03*
Y1088131D03*
X80015Y1091478D03*
X69323Y1101517D03*
X74773Y1094824D03*
X69323Y1098171D03*
Y1104863D03*
Y1091478D03*
X80015Y1118249D03*
X69323Y1114903D03*
Y1108210D03*
Y1111556D03*
Y1118249D03*
X80015Y1128289D03*
X81065Y1123269D03*
X74773Y1121596D03*
Y1131635D03*
X69323Y1134982D03*
Y1124942D03*
Y1128289D03*
Y1145021D03*
Y1138328D03*
Y1148367D03*
Y1141675D03*
X80015Y1165100D03*
X81065Y1160080D03*
X80015Y1155060D03*
X69323Y1151714D03*
X74773Y1158407D03*
X69323Y1155060D03*
Y1161753D03*
Y1165100D03*
Y1175139D03*
X74773Y1168446D03*
X69323Y1171793D03*
Y1178486D03*
Y1181832D03*
X80015Y1191871D03*
X69323Y1188525D03*
Y1185178D03*
Y1191871D03*
X81065Y1196891D03*
X80015Y1201911D03*
X74773Y1195218D03*
Y1205257D03*
X69323Y1208604D03*
Y1198564D03*
Y1201911D03*
Y1211950D03*
Y1218643D03*
Y1215297D03*
Y1221989D03*
X80015Y1238722D03*
Y1228682D03*
X81065Y1233702D03*
X69323Y1225336D03*
X74773Y1232029D03*
X69323Y1228682D03*
Y1235375D03*
Y1238722D03*
X74773Y1242068D03*
X69323Y1248761D03*
Y1245415D03*
Y1252108D03*
Y1255454D03*
X94524Y760178D03*
Y756832D03*
X89965D03*
X85465Y773564D03*
X90015Y766871D03*
X85465Y776911D03*
X89965Y763525D03*
X94474D03*
X90015Y770218D03*
X85465Y780257D03*
Y783604D03*
Y790297D03*
Y803682D03*
X94624Y795316D03*
X85465Y800336D03*
Y807029D03*
Y793643D03*
Y810375D03*
Y817068D03*
Y813722D03*
Y820415D03*
X94624Y832127D03*
X85465Y837147D03*
Y830454D03*
Y827108D03*
Y840493D03*
Y847186D03*
Y843840D03*
Y850533D03*
Y853879D03*
Y857226D03*
Y863919D03*
Y877304D03*
X94624Y868938D03*
X85465Y873958D03*
Y880651D03*
Y867265D03*
Y890690D03*
Y883997D03*
Y887344D03*
Y894037D03*
X94624Y905750D03*
X85465Y910769D03*
Y904076D03*
Y900730D03*
Y920808D03*
Y914115D03*
Y924155D03*
Y917462D03*
Y927501D03*
Y930848D03*
Y940887D03*
Y937541D03*
Y950926D03*
X94624Y942561D03*
X85465Y947580D03*
Y954273D03*
Y957619D03*
Y971005D03*
Y964312D03*
Y960966D03*
Y967659D03*
Y984391D03*
Y977698D03*
Y974352D03*
Y981045D03*
Y991084D03*
Y997777D03*
Y987737D03*
Y994430D03*
Y1001123D03*
Y1004470D03*
Y1027895D03*
Y1044627D03*
Y1031241D03*
Y1037934D03*
Y1034588D03*
Y1041281D03*
Y1051320D03*
Y1058013D03*
Y1047974D03*
Y1054667D03*
Y1068052D03*
Y1074745D03*
Y1061360D03*
Y1071399D03*
Y1064706D03*
X94624Y1089805D03*
X85465Y1078092D03*
Y1088131D03*
Y1084785D03*
Y1098171D03*
Y1104863D03*
Y1094824D03*
Y1101517D03*
Y1111556D03*
Y1108210D03*
Y1114903D03*
X94624Y1126616D03*
X85465Y1134982D03*
Y1131635D03*
Y1124942D03*
Y1121596D03*
Y1148367D03*
Y1141675D03*
Y1138328D03*
Y1145021D03*
X94624Y1163427D03*
X85465Y1151714D03*
Y1161753D03*
Y1158407D03*
Y1178486D03*
Y1171793D03*
Y1168446D03*
Y1175139D03*
Y1185178D03*
Y1181832D03*
Y1188525D03*
Y1208604D03*
X94624Y1200238D03*
X85465Y1205257D03*
Y1198564D03*
Y1195218D03*
Y1215297D03*
Y1221989D03*
Y1211950D03*
Y1218643D03*
X94624Y1237049D03*
X85465Y1225336D03*
Y1235375D03*
Y1232029D03*
Y1252108D03*
Y1245415D03*
Y1242068D03*
Y1248761D03*
X110616Y756766D03*
X103574D03*
Y760266D03*
X99024Y776911D03*
X110616Y763766D03*
X103574Y767266D03*
Y763766D03*
X104474Y790297D03*
X99024Y783604D03*
X109716Y786950D03*
X110766Y791970D03*
X99024Y780257D03*
Y786950D03*
Y807029D03*
X104474Y800336D03*
X109716Y796989D03*
X99024Y803682D03*
Y793643D03*
Y796989D03*
Y813722D03*
Y820415D03*
Y817068D03*
Y810375D03*
X104474Y827108D03*
Y837147D03*
X109716Y823761D03*
Y833800D03*
X110766Y828781D03*
X99024Y823761D03*
Y830454D03*
Y833800D03*
Y843840D03*
Y850533D03*
Y840493D03*
Y847186D03*
Y857226D03*
X104474Y863919D03*
X109716Y860572D03*
X110766Y865592D03*
X99024Y853879D03*
Y860572D03*
Y880651D03*
X104474Y873958D03*
X109716Y870611D03*
X99024Y877304D03*
Y867265D03*
Y870611D03*
Y887344D03*
Y894037D03*
Y883997D03*
Y890690D03*
X104474Y900730D03*
X109716Y897383D03*
X110766Y902403D03*
X104474Y910769D03*
X109716Y907423D03*
X99024Y897383D03*
Y904076D03*
Y907423D03*
Y924155D03*
Y917462D03*
Y914115D03*
Y920808D03*
X104474Y937541D03*
X99024Y930848D03*
X110766Y939214D03*
X109716Y934194D03*
X99024Y927501D03*
Y934194D03*
Y940887D03*
Y954273D03*
X104474Y947580D03*
X109716Y944234D03*
X99024Y950926D03*
Y944234D03*
Y960966D03*
Y967659D03*
Y964312D03*
Y957619D03*
Y971005D03*
Y974352D03*
Y981045D03*
Y977698D03*
Y984391D03*
Y987737D03*
Y994430D03*
Y1001123D03*
Y997777D03*
Y991084D03*
Y1004470D03*
Y1034588D03*
Y1041281D03*
Y1031241D03*
Y1037934D03*
Y1044627D03*
Y1047974D03*
Y1054667D03*
Y1058013D03*
Y1051320D03*
Y1071399D03*
Y1061360D03*
Y1074745D03*
Y1068052D03*
Y1064706D03*
Y1078092D03*
X109716Y1081438D03*
X110766Y1086458D03*
X104474Y1084785D03*
X99024Y1081438D03*
Y1088131D03*
Y1101517D03*
X104474Y1094824D03*
X109716Y1091478D03*
X99024Y1098171D03*
Y1104863D03*
Y1091478D03*
Y1114903D03*
Y1108210D03*
X109716Y1118249D03*
X99024Y1111556D03*
Y1118249D03*
X104474Y1121596D03*
X109716Y1128289D03*
X110766Y1123269D03*
X104474Y1131635D03*
X99024Y1134982D03*
Y1124942D03*
Y1128289D03*
Y1145021D03*
Y1138328D03*
Y1148367D03*
Y1141675D03*
X104474Y1158407D03*
X99024Y1151714D03*
X109716Y1165100D03*
X110766Y1160080D03*
X109716Y1155060D03*
X99024D03*
Y1161753D03*
Y1165100D03*
Y1175139D03*
X104474Y1168446D03*
X99024Y1171793D03*
Y1178486D03*
Y1181832D03*
Y1188525D03*
X109716Y1191871D03*
X99024Y1185178D03*
Y1191871D03*
X104474Y1195218D03*
Y1205257D03*
X110766Y1196891D03*
X109716Y1201911D03*
X99024Y1208604D03*
Y1198564D03*
Y1201911D03*
Y1211950D03*
Y1218643D03*
Y1215297D03*
Y1221989D03*
X104474Y1232029D03*
X99024Y1225336D03*
X109716Y1228682D03*
Y1238722D03*
X110766Y1233702D03*
X99024Y1228682D03*
Y1235375D03*
Y1238722D03*
X104474Y1242068D03*
X99024Y1248761D03*
Y1245415D03*
Y1252108D03*
Y1255454D03*
X124224Y760178D03*
Y756832D03*
X119666D03*
X115166Y773564D03*
X119616Y767166D03*
X115166Y776911D03*
X119666Y763525D03*
X124174D03*
X119716Y770218D03*
X115166Y780257D03*
Y783604D03*
Y790297D03*
X124324Y795316D03*
X115166Y803682D03*
Y800336D03*
Y807029D03*
Y793643D03*
Y810375D03*
Y817068D03*
Y813722D03*
Y820415D03*
X124324Y832127D03*
X115166Y837147D03*
Y830454D03*
Y827108D03*
Y840493D03*
Y847186D03*
Y843840D03*
Y850533D03*
Y853879D03*
Y857226D03*
Y863919D03*
Y877304D03*
X124324Y868938D03*
X115166Y873958D03*
Y880651D03*
Y867265D03*
Y890690D03*
Y883997D03*
Y887344D03*
Y894037D03*
X124324Y905750D03*
X115166Y910769D03*
Y904076D03*
Y900730D03*
Y920808D03*
Y914115D03*
Y924155D03*
Y917462D03*
Y927501D03*
Y930848D03*
Y940887D03*
Y937541D03*
Y950926D03*
X124324Y942561D03*
X115166Y947580D03*
Y954273D03*
Y957619D03*
Y971005D03*
Y964312D03*
Y960966D03*
Y967659D03*
Y984391D03*
Y977698D03*
Y974352D03*
Y981045D03*
Y991084D03*
Y997777D03*
Y987737D03*
Y994430D03*
Y1001123D03*
Y1004470D03*
Y1027895D03*
Y1031241D03*
Y1037934D03*
Y1044627D03*
Y1034588D03*
Y1041281D03*
Y1051320D03*
Y1058013D03*
Y1047974D03*
Y1054667D03*
Y1068052D03*
Y1074745D03*
Y1061360D03*
Y1071399D03*
Y1064706D03*
X124324Y1089805D03*
X115166Y1078092D03*
Y1088131D03*
Y1084785D03*
Y1098171D03*
Y1104863D03*
Y1094824D03*
Y1101517D03*
Y1111556D03*
Y1108210D03*
Y1114903D03*
X124324Y1126616D03*
X115166Y1134982D03*
Y1131635D03*
Y1124942D03*
Y1121596D03*
Y1148367D03*
Y1141675D03*
Y1138328D03*
Y1145021D03*
X124324Y1163427D03*
X115166Y1151714D03*
Y1161753D03*
Y1158407D03*
Y1178486D03*
Y1171793D03*
Y1168446D03*
Y1175139D03*
Y1185178D03*
Y1181832D03*
Y1188525D03*
Y1208604D03*
X124324Y1200238D03*
X115166Y1205257D03*
Y1198564D03*
Y1195218D03*
Y1215297D03*
Y1221989D03*
Y1211950D03*
Y1218643D03*
X124324Y1237049D03*
X115166Y1225336D03*
Y1235375D03*
Y1232029D03*
Y1252108D03*
Y1245415D03*
Y1242068D03*
Y1248761D03*
X140316Y756766D03*
X133124D03*
Y760266D03*
X128724Y776911D03*
X140316Y763766D03*
X133124Y767266D03*
Y763766D03*
X134174Y790297D03*
X139416Y786950D03*
X128724Y783604D03*
X140466Y791970D03*
X128724Y780257D03*
Y786950D03*
Y807029D03*
X134174Y800336D03*
X139416Y796989D03*
X128724Y803682D03*
Y793643D03*
Y796989D03*
Y813722D03*
Y820415D03*
Y817068D03*
Y810375D03*
X134174Y837147D03*
X139416Y823761D03*
Y833800D03*
X140466Y828781D03*
X134174Y827108D03*
X128724Y823761D03*
Y830454D03*
Y833800D03*
Y843840D03*
Y850533D03*
Y840493D03*
Y847186D03*
Y857226D03*
X134174Y863919D03*
X139416Y860572D03*
X140466Y865592D03*
X128724Y853879D03*
Y860572D03*
X134174Y873958D03*
X128724Y880651D03*
X139416Y870611D03*
X128724Y877304D03*
Y867265D03*
Y870611D03*
Y887344D03*
Y894037D03*
Y883997D03*
Y890690D03*
X134174Y900730D03*
X139416Y897383D03*
X140466Y902403D03*
X134174Y910769D03*
X139416Y907423D03*
X128724Y897383D03*
Y904076D03*
Y907423D03*
Y924155D03*
Y917462D03*
Y914115D03*
Y920808D03*
X134174Y937541D03*
X140466Y939214D03*
X139416Y934194D03*
X128724Y930848D03*
Y927501D03*
Y934194D03*
Y940887D03*
Y954273D03*
X134174Y947580D03*
X139416Y944234D03*
X128724Y950926D03*
Y944234D03*
Y960966D03*
Y967659D03*
Y964312D03*
Y957619D03*
Y971005D03*
Y974352D03*
Y981045D03*
Y977698D03*
Y984391D03*
Y987737D03*
Y994430D03*
Y1001123D03*
Y997777D03*
Y991084D03*
Y1004470D03*
Y1034588D03*
Y1041281D03*
Y1031241D03*
Y1037934D03*
Y1044627D03*
Y1047974D03*
Y1054667D03*
Y1058013D03*
Y1051320D03*
Y1071399D03*
Y1061360D03*
Y1074745D03*
Y1068052D03*
Y1064706D03*
X139416Y1081438D03*
X134174Y1084785D03*
X140466Y1086458D03*
X128724Y1078092D03*
Y1081438D03*
Y1088131D03*
Y1101517D03*
X139416Y1091478D03*
X134174Y1094824D03*
X128724Y1098171D03*
Y1104863D03*
Y1091478D03*
Y1114903D03*
X139416Y1118249D03*
X128724Y1108210D03*
Y1111556D03*
Y1118249D03*
X139416Y1128289D03*
X134174Y1121596D03*
X140466Y1123269D03*
X134174Y1131635D03*
X128724Y1134982D03*
Y1124942D03*
Y1128289D03*
Y1145021D03*
Y1138328D03*
Y1148367D03*
Y1141675D03*
X139416Y1165100D03*
X140466Y1160080D03*
X134174Y1158407D03*
X139416Y1155060D03*
X128724Y1151714D03*
Y1155060D03*
Y1161753D03*
Y1165100D03*
Y1175139D03*
X134174Y1168446D03*
X128724Y1171793D03*
Y1178486D03*
Y1181832D03*
X139416Y1191871D03*
X128724Y1188525D03*
Y1185178D03*
Y1191871D03*
X134174Y1195218D03*
X140466Y1196891D03*
X134174Y1205257D03*
X139416Y1201911D03*
X128724Y1208604D03*
Y1198564D03*
Y1201911D03*
Y1211950D03*
Y1218643D03*
Y1215297D03*
Y1221989D03*
Y1225336D03*
X134174Y1232029D03*
X139416Y1228682D03*
X140466Y1233702D03*
X139416Y1238722D03*
X128724Y1228682D03*
Y1235375D03*
Y1238722D03*
X134174Y1242068D03*
X128724Y1248761D03*
Y1245415D03*
Y1252108D03*
Y1255454D03*
X153925Y760178D03*
Y756832D03*
X149366D03*
X144866Y773564D03*
X149416Y766871D03*
X144866Y776911D03*
X149366Y763525D03*
X153875D03*
X149416Y770218D03*
X144866Y780257D03*
Y783604D03*
Y790297D03*
X154025Y795316D03*
X144866Y803682D03*
Y800336D03*
Y807029D03*
Y793643D03*
Y810375D03*
Y817068D03*
Y813722D03*
Y820415D03*
X154025Y832127D03*
X144866Y837147D03*
Y830454D03*
Y827108D03*
Y840493D03*
Y847186D03*
Y843840D03*
Y850533D03*
Y853879D03*
Y857226D03*
Y863919D03*
Y877304D03*
X154025Y868938D03*
X144866Y873958D03*
Y880651D03*
Y867265D03*
Y890690D03*
Y883997D03*
Y887344D03*
Y894037D03*
X154025Y905750D03*
X144866Y910769D03*
Y904076D03*
Y900730D03*
Y920808D03*
Y914115D03*
Y924155D03*
Y917462D03*
Y927501D03*
Y930848D03*
Y940887D03*
Y937541D03*
X154025Y942561D03*
X144866Y950926D03*
Y947580D03*
Y954273D03*
Y957619D03*
Y971005D03*
Y964312D03*
Y960966D03*
Y967659D03*
Y984391D03*
Y977698D03*
Y974352D03*
Y981045D03*
Y991084D03*
Y997777D03*
Y987737D03*
Y994430D03*
Y1001123D03*
Y1004470D03*
Y1027895D03*
Y1031241D03*
Y1037934D03*
Y1044627D03*
Y1034588D03*
Y1041281D03*
Y1051320D03*
Y1058013D03*
Y1047974D03*
Y1054667D03*
Y1068052D03*
Y1074745D03*
Y1061360D03*
Y1071399D03*
Y1064706D03*
X154025Y1089805D03*
X144866Y1078092D03*
Y1088131D03*
Y1084785D03*
Y1098171D03*
Y1104863D03*
Y1094824D03*
Y1101517D03*
Y1111556D03*
Y1108210D03*
Y1114903D03*
X154025Y1126616D03*
X144866Y1134982D03*
Y1131635D03*
Y1124942D03*
Y1121596D03*
Y1148367D03*
Y1141675D03*
Y1138328D03*
Y1145021D03*
X154025Y1163427D03*
X144866Y1151714D03*
Y1161753D03*
Y1158407D03*
Y1178486D03*
Y1171793D03*
Y1168446D03*
Y1175139D03*
Y1185178D03*
Y1181832D03*
Y1188525D03*
Y1208604D03*
X154025Y1200238D03*
X144866Y1205257D03*
Y1198564D03*
Y1195218D03*
Y1215297D03*
Y1221989D03*
Y1211950D03*
Y1218643D03*
X154025Y1237049D03*
X144866Y1225336D03*
Y1235375D03*
Y1232029D03*
Y1252108D03*
Y1245415D03*
Y1242068D03*
Y1248761D03*
X162975Y760266D03*
Y756766D03*
X170017D03*
X158425Y776911D03*
X170017Y763766D03*
X162975Y767266D03*
Y763766D03*
X163875Y790297D03*
X158425Y783604D03*
X169117Y786950D03*
X170167Y791970D03*
X158425Y780257D03*
Y786950D03*
X163875Y800336D03*
X158425Y807029D03*
X169117Y796989D03*
X158425Y803682D03*
Y793643D03*
Y796989D03*
Y813722D03*
Y820415D03*
Y817068D03*
Y810375D03*
X163875Y837147D03*
X169117Y823761D03*
Y833800D03*
X170167Y828781D03*
X163875Y827108D03*
X158425Y823761D03*
Y830454D03*
Y833800D03*
Y843840D03*
Y850533D03*
Y840493D03*
Y847186D03*
X163875Y863919D03*
X158425Y857226D03*
X169117Y860572D03*
X170167Y865592D03*
X158425Y853879D03*
Y860572D03*
X163875Y873958D03*
X158425Y880651D03*
X169117Y870611D03*
X158425Y877304D03*
Y867265D03*
Y870611D03*
Y887344D03*
Y894037D03*
Y883997D03*
Y890690D03*
X163875Y900730D03*
X169117Y897383D03*
X170167Y902403D03*
X163875Y910769D03*
X169117Y907423D03*
X158425Y897383D03*
Y904076D03*
Y907423D03*
Y924155D03*
Y917462D03*
Y914115D03*
Y920808D03*
X163875Y937541D03*
X158425Y930848D03*
X170167Y939214D03*
X169117Y934194D03*
X158425Y927501D03*
Y934194D03*
Y940887D03*
X163875Y947580D03*
X158425Y954273D03*
X169117Y944234D03*
X158425Y950926D03*
Y944234D03*
Y960966D03*
Y967659D03*
Y964312D03*
Y957619D03*
Y971005D03*
Y974352D03*
Y981045D03*
Y977698D03*
Y984391D03*
Y987737D03*
Y994430D03*
Y1001123D03*
Y997777D03*
Y991084D03*
Y1004470D03*
Y1034588D03*
Y1041281D03*
Y1031241D03*
Y1037934D03*
Y1044627D03*
Y1047974D03*
Y1054667D03*
Y1058013D03*
Y1051320D03*
Y1071399D03*
Y1061360D03*
Y1074745D03*
Y1068052D03*
Y1064706D03*
X163875Y1084785D03*
X158425Y1078092D03*
X169117Y1081438D03*
X170167Y1086458D03*
X158425Y1081438D03*
Y1088131D03*
X163875Y1094824D03*
X158425Y1101517D03*
X169117Y1091478D03*
X158425Y1098171D03*
Y1104863D03*
Y1091478D03*
Y1114903D03*
Y1108210D03*
X169117Y1118249D03*
X158425Y1111556D03*
Y1118249D03*
X163875Y1121596D03*
X169117Y1128289D03*
X170167Y1123269D03*
X163875Y1131635D03*
X158425Y1134982D03*
Y1124942D03*
Y1128289D03*
Y1145021D03*
Y1138328D03*
Y1148367D03*
Y1141675D03*
X169117Y1165100D03*
X170167Y1160080D03*
X169117Y1155060D03*
X163875Y1158407D03*
X158425Y1151714D03*
Y1155060D03*
Y1161753D03*
Y1165100D03*
X163875Y1168446D03*
X158425Y1175139D03*
Y1171793D03*
Y1178486D03*
Y1181832D03*
Y1188525D03*
X169117Y1191871D03*
X158425Y1185178D03*
Y1191871D03*
X163875Y1195218D03*
Y1205257D03*
X170167Y1196891D03*
X169117Y1201911D03*
X158425Y1208604D03*
Y1198564D03*
Y1201911D03*
Y1211950D03*
Y1218643D03*
Y1215297D03*
Y1221989D03*
X163875Y1232029D03*
X158425Y1225336D03*
X169117Y1238722D03*
Y1228682D03*
X170167Y1233702D03*
X158425Y1228682D03*
Y1235375D03*
Y1238722D03*
X163875Y1242068D03*
X158425Y1248761D03*
Y1245415D03*
Y1252108D03*
Y1255454D03*
X183626Y760178D03*
Y756832D03*
X179067D03*
X174567Y773564D03*
X179117Y766871D03*
X174567Y776911D03*
X179067Y763525D03*
X183576D03*
X179117Y770218D03*
X174567Y780257D03*
Y783604D03*
Y790297D03*
Y803682D03*
X183726Y795316D03*
X174567Y800336D03*
Y807029D03*
Y793643D03*
Y810375D03*
Y817068D03*
Y813722D03*
Y820415D03*
X183726Y832127D03*
X174567Y837147D03*
Y830454D03*
Y827108D03*
Y840493D03*
Y847186D03*
Y843840D03*
Y850533D03*
Y853879D03*
Y857226D03*
Y863919D03*
Y877304D03*
X183726Y868938D03*
X174567Y873958D03*
Y880651D03*
Y867265D03*
Y890690D03*
Y883997D03*
Y887344D03*
Y894037D03*
X183726Y905750D03*
X174567Y910769D03*
Y904076D03*
Y900730D03*
Y920808D03*
Y914115D03*
Y924155D03*
Y917462D03*
Y927501D03*
Y930848D03*
Y940887D03*
Y937541D03*
Y950926D03*
X183726Y942561D03*
X174567Y947580D03*
Y954273D03*
Y957619D03*
Y971005D03*
Y964312D03*
Y960966D03*
Y967659D03*
Y984391D03*
Y977698D03*
Y974352D03*
Y981045D03*
Y991084D03*
Y997777D03*
Y987737D03*
Y994430D03*
Y1001123D03*
Y1004470D03*
Y1027895D03*
Y1031241D03*
Y1037934D03*
Y1044627D03*
Y1034588D03*
Y1041281D03*
Y1051320D03*
Y1058013D03*
Y1047974D03*
Y1054667D03*
Y1068052D03*
Y1074745D03*
Y1061360D03*
Y1071399D03*
Y1064706D03*
X183726Y1089805D03*
X174567Y1078092D03*
Y1088131D03*
Y1084785D03*
Y1098171D03*
Y1104863D03*
Y1094824D03*
Y1101517D03*
Y1111556D03*
Y1108210D03*
Y1114903D03*
Y1134982D03*
X183726Y1126616D03*
X174567Y1131635D03*
Y1124942D03*
Y1121596D03*
Y1148367D03*
Y1141675D03*
Y1138328D03*
Y1145021D03*
X183726Y1163427D03*
X174567Y1151714D03*
Y1161753D03*
Y1158407D03*
Y1178486D03*
Y1171793D03*
Y1168446D03*
Y1175139D03*
Y1185178D03*
Y1181832D03*
Y1188525D03*
Y1208604D03*
X183726Y1200238D03*
X174567Y1205257D03*
Y1198564D03*
Y1195218D03*
Y1215297D03*
Y1221989D03*
Y1211950D03*
Y1218643D03*
X183726Y1237049D03*
X174567Y1225336D03*
Y1235375D03*
Y1232029D03*
Y1252108D03*
Y1245415D03*
Y1242068D03*
Y1248761D03*
X192676Y760266D03*
Y756766D03*
X199718D03*
X192676Y767266D03*
X199718Y763766D03*
X188126Y776911D03*
X192676Y763766D03*
X199868Y791970D03*
X198818Y786950D03*
X193576Y790297D03*
X188126Y783604D03*
Y780257D03*
Y786950D03*
X198818Y796989D03*
X193576Y800336D03*
X188126Y807029D03*
Y803682D03*
Y793643D03*
Y796989D03*
Y813722D03*
Y820415D03*
Y817068D03*
Y810375D03*
X199868Y828781D03*
X198818Y823761D03*
Y833800D03*
X193576Y827108D03*
Y837147D03*
X188126Y823761D03*
Y830454D03*
Y833800D03*
Y843840D03*
Y850533D03*
Y840493D03*
Y847186D03*
X199868Y865592D03*
X198818Y860572D03*
X193576Y863919D03*
X188126Y857226D03*
Y853879D03*
Y860572D03*
X198818Y870611D03*
X193576Y873958D03*
X188126Y880651D03*
Y877304D03*
Y867265D03*
Y870611D03*
Y887344D03*
Y894037D03*
Y883997D03*
Y890690D03*
X199868Y902403D03*
X198818Y897383D03*
X193576Y900730D03*
X198818Y907423D03*
X193576Y910769D03*
X188126Y897383D03*
Y904076D03*
Y907423D03*
Y917462D03*
Y924155D03*
Y914115D03*
Y920808D03*
X199868Y939214D03*
X198818Y934194D03*
X193576Y937541D03*
X188126Y930848D03*
Y927501D03*
Y934194D03*
Y940887D03*
X198818Y944234D03*
X193576Y947580D03*
X188126Y954273D03*
Y950926D03*
Y944234D03*
Y960966D03*
Y967659D03*
Y964312D03*
Y957619D03*
Y971005D03*
Y974352D03*
Y981045D03*
Y977698D03*
Y984391D03*
Y987737D03*
Y994430D03*
Y1001123D03*
Y997777D03*
Y991084D03*
Y1004470D03*
Y1034588D03*
Y1041281D03*
Y1031241D03*
Y1037934D03*
Y1044627D03*
Y1047974D03*
Y1054667D03*
Y1058013D03*
Y1051320D03*
Y1061360D03*
Y1071399D03*
Y1074745D03*
Y1068052D03*
Y1064706D03*
X199868Y1086458D03*
X193576Y1084785D03*
X198818Y1081438D03*
X188126Y1078092D03*
Y1081438D03*
Y1088131D03*
X198818Y1091478D03*
X193576Y1094824D03*
X188126Y1101517D03*
Y1098171D03*
Y1104863D03*
Y1091478D03*
X198818Y1118249D03*
X188126Y1108210D03*
Y1114903D03*
Y1111556D03*
Y1118249D03*
X199868Y1123269D03*
X193576Y1121596D03*
X198818Y1128289D03*
X193576Y1131635D03*
X188126Y1134982D03*
Y1124942D03*
Y1128289D03*
Y1138328D03*
Y1145021D03*
Y1148367D03*
Y1141675D03*
X199868Y1160080D03*
X198818Y1155060D03*
X193576Y1158407D03*
X198818Y1165100D03*
X188126Y1151714D03*
Y1155060D03*
Y1161753D03*
Y1165100D03*
X193576Y1168446D03*
X188126Y1175139D03*
Y1171793D03*
Y1178486D03*
X198818Y1191871D03*
X188126Y1181832D03*
Y1188525D03*
Y1185178D03*
Y1191871D03*
X199868Y1196891D03*
X198818Y1201911D03*
X193576Y1205257D03*
Y1195218D03*
X188126Y1208604D03*
Y1198564D03*
Y1201911D03*
Y1211950D03*
Y1218643D03*
Y1215297D03*
Y1221989D03*
X199868Y1233702D03*
X198818Y1228682D03*
X193576Y1232029D03*
X198818Y1238722D03*
X188126Y1225336D03*
Y1228682D03*
Y1235375D03*
Y1238722D03*
X193576Y1242068D03*
X188126Y1248761D03*
Y1245415D03*
Y1252108D03*
Y1255454D03*
X213327Y760178D03*
Y756832D03*
X208768D03*
X204268Y773564D03*
Y776911D03*
X208768Y763525D03*
X212772Y766871D03*
X213277Y763525D03*
X208818Y770218D03*
X204268Y780257D03*
Y783604D03*
Y790297D03*
X213427Y795316D03*
X204268Y803682D03*
Y800336D03*
Y807029D03*
Y793643D03*
Y810375D03*
Y817068D03*
Y813722D03*
Y820415D03*
X213427Y832127D03*
X204268Y837147D03*
Y830454D03*
Y827108D03*
Y840493D03*
Y847186D03*
Y843840D03*
Y850533D03*
Y853879D03*
Y857226D03*
Y863919D03*
X213427Y868938D03*
X204268Y877304D03*
Y873958D03*
Y880651D03*
Y867265D03*
Y883997D03*
Y890690D03*
Y887344D03*
Y894037D03*
X213427Y905750D03*
X204268Y910769D03*
Y904076D03*
Y900730D03*
Y914115D03*
Y920808D03*
Y924155D03*
Y917462D03*
Y927501D03*
Y930848D03*
Y940887D03*
Y937541D03*
X213427Y942561D03*
X204268Y950926D03*
Y947580D03*
Y954273D03*
Y957619D03*
Y964312D03*
Y971005D03*
Y960966D03*
Y967659D03*
Y977698D03*
Y984391D03*
Y974352D03*
Y981045D03*
Y991084D03*
Y997777D03*
Y987737D03*
Y994430D03*
Y1001123D03*
Y1004470D03*
Y1027895D03*
Y1031241D03*
Y1037934D03*
Y1044627D03*
Y1034588D03*
Y1041281D03*
Y1051320D03*
Y1058013D03*
Y1047974D03*
Y1054667D03*
Y1068052D03*
Y1074745D03*
Y1061360D03*
Y1071399D03*
Y1064706D03*
X213427Y1089805D03*
X204268Y1078092D03*
Y1088131D03*
Y1084785D03*
Y1098171D03*
Y1104863D03*
Y1094824D03*
Y1101517D03*
Y1111556D03*
Y1108210D03*
Y1114903D03*
X213427Y1126616D03*
X204268Y1134982D03*
Y1131635D03*
Y1124942D03*
Y1121596D03*
Y1141675D03*
Y1148367D03*
Y1138328D03*
Y1145021D03*
X213427Y1163427D03*
X204268Y1151714D03*
Y1161753D03*
Y1158407D03*
Y1171793D03*
Y1178486D03*
Y1168446D03*
Y1175139D03*
Y1185178D03*
Y1181832D03*
Y1188525D03*
X213427Y1200238D03*
X204268Y1208604D03*
Y1205257D03*
Y1198564D03*
Y1195218D03*
Y1215297D03*
Y1221989D03*
Y1211950D03*
Y1218643D03*
X213427Y1237049D03*
X204268Y1225336D03*
Y1235375D03*
Y1232029D03*
Y1245415D03*
Y1252108D03*
Y1242068D03*
Y1248761D03*
X222377Y760266D03*
Y756766D03*
X229419D03*
X222377Y767266D03*
X229419Y763119D03*
X217827Y776911D03*
X222377Y763766D03*
X229569Y791970D03*
X228519Y786950D03*
X223277Y790297D03*
X217827Y783604D03*
X228519Y796989D03*
X223277Y800336D03*
X217827Y807029D03*
Y813722D03*
Y820415D03*
X229569Y828781D03*
X223277Y837147D03*
X228519Y823761D03*
Y833800D03*
X223277Y827108D03*
X217827Y843840D03*
Y850533D03*
X229569Y865592D03*
X228519Y860572D03*
X223277Y863919D03*
X217827Y857226D03*
X228519Y870611D03*
X223277Y873958D03*
X217827Y880651D03*
Y887344D03*
Y894037D03*
X229569Y902403D03*
X228519Y897383D03*
X223277Y900730D03*
X228519Y907423D03*
X223277Y910769D03*
X217827Y917462D03*
Y924155D03*
X229569Y939214D03*
X228519Y934194D03*
X223277Y937541D03*
X217827Y930848D03*
X228519Y944234D03*
X223277Y947580D03*
X217827Y954273D03*
Y960966D03*
Y967659D03*
X227540Y960966D03*
X217827Y974352D03*
Y981045D03*
Y987737D03*
Y994430D03*
Y1004470D03*
Y1034588D03*
Y1041281D03*
Y1047974D03*
Y1054667D03*
Y1061360D03*
Y1071399D03*
X229569Y1086458D03*
X223277Y1084785D03*
X228519Y1081438D03*
X217827Y1078092D03*
Y1101517D03*
X228519Y1091478D03*
X223277Y1094824D03*
X228519Y1118249D03*
X217827Y1108210D03*
Y1114903D03*
X229569Y1123269D03*
X223277Y1121596D03*
X228519Y1128289D03*
X223277Y1131635D03*
X217827Y1138328D03*
Y1145021D03*
X229569Y1160080D03*
X228519Y1155060D03*
X223277Y1158407D03*
X228519Y1165100D03*
X217827Y1151714D03*
X223277Y1168446D03*
X217827Y1175139D03*
X228519Y1191871D03*
X217827Y1181832D03*
Y1188525D03*
X229569Y1196891D03*
X228519Y1201911D03*
X223277Y1205257D03*
Y1195218D03*
X217827Y1211950D03*
Y1218643D03*
X229569Y1233702D03*
X228519Y1228682D03*
X223277Y1232029D03*
X228519Y1238722D03*
X217827Y1225336D03*
X223277Y1242068D03*
X217827Y1248761D03*
Y1255454D03*
X238469Y756832D03*
X233969Y773564D03*
X238469Y763525D03*
X238519Y770218D03*
X233969Y780257D03*
Y803682D03*
Y810375D03*
Y817068D03*
Y840493D03*
Y847186D03*
Y853879D03*
Y877304D03*
Y883997D03*
Y890690D03*
Y914115D03*
Y920808D03*
Y927501D03*
Y950926D03*
Y957619D03*
Y964312D03*
Y971005D03*
Y960966D03*
Y977698D03*
Y984391D03*
Y991084D03*
Y997777D03*
Y1004470D03*
Y1031241D03*
Y1037934D03*
Y1044627D03*
Y1051320D03*
Y1058013D03*
Y1068052D03*
Y1074745D03*
Y1098171D03*
Y1104863D03*
Y1111556D03*
Y1134982D03*
Y1141675D03*
Y1148367D03*
Y1171793D03*
Y1178486D03*
Y1185178D03*
Y1208604D03*
Y1215297D03*
Y1221989D03*
Y1245415D03*
Y1252108D03*
X389981Y1015474D03*
X386381D03*
X393861D03*
X389981Y1022560D03*
Y1019017D03*
X386381Y1022560D03*
Y1019017D03*
X393861Y1022560D03*
Y1019017D03*
X397461Y1015474D03*
X404941D03*
X401341D03*
X397461Y1022560D03*
X404941Y1019017D03*
Y1022560D03*
X397461Y1019017D03*
X401341D03*
Y1022560D03*
X418918Y1006025D03*
Y1013505D03*
X423811Y1009400D03*
X418918Y1009765D03*
X415318D03*
Y1006025D03*
X424873Y1014745D03*
X423811Y1005800D03*
X415318Y1013505D03*
X418918Y1024726D03*
Y1020986D03*
Y1028466D03*
Y1017245D03*
X423811Y1028831D03*
X424873Y1023013D03*
Y1018879D03*
X415318Y1028466D03*
Y1020986D03*
Y1024726D03*
Y1017245D03*
Y1032206D03*
X418918D03*
X423811Y1032431D03*
X440159Y966741D03*
Y970341D03*
Y981741D03*
Y974241D03*
Y977841D03*
Y985341D03*
X438359Y993766D03*
X438434Y989766D03*
X438359Y997766D03*
X431291Y1009400D03*
X438316Y1014745D03*
X427551Y1009400D03*
X435031D03*
X438771D03*
X428473Y1014745D03*
X427551Y1005800D03*
X434716Y1014745D03*
X431291Y1005800D03*
X435031D03*
X438771D03*
X438359Y1001766D03*
X438771Y1028831D03*
X438316Y1023013D03*
X427551Y1028831D03*
X435031D03*
X438316Y1018879D03*
X428473D03*
Y1023013D03*
X431291Y1028831D03*
X434716Y1018879D03*
Y1023013D03*
X439284Y1038766D03*
Y1042766D03*
X431291Y1032431D03*
X435031D03*
X438771D03*
X427551D03*
X441959Y993766D03*
Y997766D03*
X442034Y989766D03*
X442511Y1009400D03*
X449992D03*
X446252D03*
X453732D03*
X441959Y1001766D03*
X447174Y1014745D03*
X453810D03*
X449992Y1005800D03*
X453732D03*
X443574Y1014745D03*
X446252Y1005800D03*
X442511D03*
X446252Y1028831D03*
X453732D03*
X449992D03*
X447174Y1023013D03*
X442511Y1028831D03*
X447174Y1018879D03*
X453810Y1023013D03*
X443574D03*
X453810Y1018879D03*
X443574D03*
X453732Y1032431D03*
X442884Y1038766D03*
X442511Y1032431D03*
X442884Y1042766D03*
X446252Y1032431D03*
X449992D03*
X441159Y1055141D03*
Y1051541D03*
X457472Y1009400D03*
X462365Y1006025D03*
X457410Y1014745D03*
X462365Y1009765D03*
Y1013505D03*
X457472Y1005800D03*
X465965Y1009765D03*
Y1006025D03*
Y1013505D03*
X462365Y1020986D03*
X457410Y1018879D03*
X462365Y1028466D03*
Y1024726D03*
Y1017245D03*
X457410Y1023013D03*
X457472Y1028831D03*
X465965Y1020986D03*
Y1024726D03*
Y1028466D03*
Y1017245D03*
X462365Y1032206D03*
X465965D03*
X457472Y1032431D03*
X477203Y1015474D03*
X484784D03*
X480803D03*
X477203Y1019017D03*
X484784D03*
X477203Y1022560D03*
X484784D03*
X480803D03*
Y1019017D03*
X492284Y1015474D03*
X488384D03*
X495884D03*
X492284Y1019017D03*
Y1022560D03*
X488384D03*
Y1019017D03*
X495884Y1022560D03*
Y1019017D03*
X642854Y760178D03*
Y756832D03*
X647354Y776911D03*
X642804Y763525D03*
X647354Y783604D03*
Y807029D03*
Y813722D03*
Y820415D03*
Y843840D03*
Y850533D03*
Y857226D03*
Y880651D03*
Y887344D03*
Y894037D03*
Y917462D03*
Y924155D03*
Y930848D03*
Y954273D03*
Y960966D03*
Y967659D03*
Y974352D03*
Y981045D03*
Y987737D03*
Y994430D03*
Y1004470D03*
Y1034588D03*
Y1041281D03*
Y1047974D03*
Y1054667D03*
Y1061360D03*
Y1071399D03*
Y1078092D03*
Y1101517D03*
Y1108210D03*
Y1114903D03*
Y1138328D03*
Y1145021D03*
Y1151714D03*
Y1175139D03*
Y1181832D03*
Y1188525D03*
Y1211950D03*
Y1218643D03*
Y1225336D03*
Y1248761D03*
Y1255454D03*
X658946Y756766D03*
X651904D03*
Y760266D03*
X663496Y773564D03*
X658946Y763766D03*
X651904Y767266D03*
X651905Y763766D03*
X652804Y790297D03*
X658046Y786950D03*
X663496Y780257D03*
X651754Y795316D03*
X652804Y800336D03*
X658046Y796989D03*
X663496Y803682D03*
Y810375D03*
Y817068D03*
X651754Y832127D03*
X652804Y837147D03*
Y827108D03*
X658046Y833800D03*
Y823761D03*
X663496Y840493D03*
Y847186D03*
X652804Y863919D03*
X658046Y860572D03*
X663496Y853879D03*
X651754Y868938D03*
X652804Y873958D03*
X658046Y870611D03*
X663496Y877304D03*
Y883997D03*
Y890690D03*
X651754Y905750D03*
X652804Y900730D03*
Y910769D03*
X658046Y897383D03*
Y907423D03*
X663496Y914115D03*
Y920808D03*
X652804Y937541D03*
X658046Y934194D03*
X663496Y927501D03*
X651754Y942561D03*
X652804Y947580D03*
X658046Y944234D03*
X663496Y950926D03*
Y957619D03*
Y964312D03*
Y971005D03*
Y960966D03*
X657996D03*
X663496Y977698D03*
Y984391D03*
Y991084D03*
Y997777D03*
Y1004470D03*
Y1031241D03*
Y1037934D03*
Y1044627D03*
Y1051320D03*
Y1058013D03*
Y1068052D03*
Y1074745D03*
X651754Y1089805D03*
X652804Y1084785D03*
X658046Y1081438D03*
X652804Y1094824D03*
X658046Y1091478D03*
X663496Y1098171D03*
Y1104863D03*
X658046Y1118249D03*
X663496Y1111556D03*
X651754Y1126616D03*
X652804Y1121596D03*
Y1131635D03*
X658046Y1128289D03*
X663496Y1134982D03*
Y1141675D03*
Y1148367D03*
X651754Y1163427D03*
X652804Y1158407D03*
X658046Y1155060D03*
Y1165100D03*
X652804Y1168446D03*
X663496Y1171793D03*
Y1178486D03*
X658046Y1191871D03*
X663496Y1185178D03*
X651754Y1200238D03*
X652804Y1205257D03*
Y1195218D03*
X658046Y1201911D03*
X663496Y1208604D03*
Y1215297D03*
Y1221989D03*
X651754Y1237049D03*
X652804Y1232029D03*
X658046Y1238722D03*
Y1228682D03*
X652804Y1242068D03*
X663496Y1245415D03*
Y1252108D03*
X667996Y756832D03*
X672555D03*
Y760178D03*
X677055Y776911D03*
X668046Y766871D03*
X667996Y763525D03*
X672505D03*
X668046Y770218D03*
X667896Y791970D03*
X677055Y783604D03*
Y780257D03*
Y786950D03*
Y807029D03*
Y803682D03*
Y793643D03*
Y796989D03*
Y813722D03*
Y820415D03*
Y817068D03*
Y810375D03*
X667896Y828781D03*
X677055Y823761D03*
Y830454D03*
Y833800D03*
Y843840D03*
Y850533D03*
Y840493D03*
Y847186D03*
X667896Y865592D03*
X677055Y857226D03*
Y853879D03*
Y860572D03*
Y880651D03*
Y877304D03*
Y867265D03*
Y870611D03*
Y887344D03*
Y894037D03*
Y883997D03*
Y890690D03*
X667896Y902403D03*
X677055Y897383D03*
Y904076D03*
Y907423D03*
Y917462D03*
Y924155D03*
Y914115D03*
Y920808D03*
X667896Y939214D03*
X677055Y930848D03*
Y927501D03*
Y934194D03*
Y940887D03*
Y954273D03*
Y950926D03*
Y944234D03*
Y960966D03*
Y967659D03*
Y964312D03*
Y957619D03*
Y971005D03*
Y974352D03*
Y981045D03*
Y977698D03*
Y984391D03*
Y987737D03*
Y994430D03*
Y1001123D03*
Y997777D03*
Y991084D03*
Y1004470D03*
Y1034588D03*
Y1041281D03*
Y1031241D03*
Y1037934D03*
Y1044627D03*
Y1047974D03*
Y1054667D03*
Y1058013D03*
Y1051320D03*
Y1061360D03*
Y1071399D03*
Y1074745D03*
Y1068052D03*
Y1064706D03*
X667896Y1086458D03*
X677055Y1078092D03*
Y1081438D03*
Y1088131D03*
Y1101517D03*
Y1098171D03*
Y1104863D03*
Y1091478D03*
Y1108210D03*
Y1114903D03*
Y1111556D03*
Y1118249D03*
X667896Y1123269D03*
X677055Y1134982D03*
Y1124942D03*
Y1128289D03*
Y1138328D03*
Y1145021D03*
Y1148367D03*
Y1141675D03*
X667896Y1160080D03*
X677055Y1151714D03*
Y1155060D03*
Y1161753D03*
Y1165100D03*
Y1175139D03*
Y1171793D03*
Y1178486D03*
Y1181832D03*
Y1188525D03*
Y1185178D03*
Y1191871D03*
X667896Y1196891D03*
X677055Y1208604D03*
Y1198564D03*
Y1201911D03*
Y1211950D03*
Y1218643D03*
Y1215297D03*
Y1221989D03*
X667896Y1233702D03*
X677055Y1225336D03*
Y1228682D03*
Y1235375D03*
Y1238722D03*
Y1248761D03*
Y1245415D03*
Y1252108D03*
Y1255454D03*
X681605Y756766D03*
X681671Y760178D03*
X688647Y756766D03*
X693197Y773564D03*
X688647Y763766D03*
X681605Y767266D03*
X693197Y776911D03*
X681606Y763766D03*
X682505Y790297D03*
X687747Y786950D03*
X693197Y780257D03*
Y783604D03*
Y790297D03*
X681455Y795316D03*
X682505Y800336D03*
X687747Y796989D03*
X693197Y803682D03*
Y800336D03*
Y807029D03*
Y793643D03*
Y810375D03*
Y817068D03*
Y813722D03*
Y820415D03*
X681455Y832127D03*
X682505Y837147D03*
Y827108D03*
X687747Y833800D03*
Y823761D03*
X693197Y837147D03*
Y830454D03*
Y827108D03*
Y840493D03*
Y847186D03*
Y843840D03*
Y850533D03*
X682505Y863919D03*
X687747Y860572D03*
X693197Y853879D03*
Y857226D03*
Y863919D03*
X681455Y868938D03*
X682505Y873958D03*
X687747Y870611D03*
X693197Y877304D03*
Y873958D03*
Y880651D03*
Y867265D03*
Y883997D03*
Y890690D03*
Y887344D03*
Y894037D03*
X681455Y905750D03*
X682505Y900730D03*
Y910769D03*
X687747Y897383D03*
Y907423D03*
X693197Y910769D03*
Y904076D03*
Y900730D03*
Y914115D03*
Y920808D03*
Y924155D03*
Y917462D03*
X682505Y937541D03*
X687747Y934194D03*
X693197Y927501D03*
Y930848D03*
Y940887D03*
Y937541D03*
X681455Y942561D03*
X682505Y947580D03*
X687747Y944234D03*
X693197Y950926D03*
Y947580D03*
Y954273D03*
Y957619D03*
Y964312D03*
Y971005D03*
Y960966D03*
Y967659D03*
Y977698D03*
Y984391D03*
Y974352D03*
Y981045D03*
Y991084D03*
Y997777D03*
Y987737D03*
Y994430D03*
Y1001123D03*
Y1004470D03*
Y1027895D03*
Y1031241D03*
Y1037934D03*
Y1044627D03*
Y1034588D03*
Y1041281D03*
Y1051320D03*
Y1058013D03*
Y1047974D03*
Y1054667D03*
Y1068052D03*
Y1074745D03*
Y1061360D03*
Y1071399D03*
Y1064706D03*
X681455Y1089805D03*
X682505Y1084785D03*
X687747Y1081438D03*
X693197Y1078092D03*
Y1088131D03*
Y1084785D03*
X682505Y1094824D03*
X687747Y1091478D03*
X693197Y1098171D03*
Y1104863D03*
Y1094824D03*
Y1101517D03*
X687747Y1118249D03*
X693197Y1111556D03*
Y1108210D03*
Y1114903D03*
X681455Y1126616D03*
X682505Y1121596D03*
Y1131635D03*
X687747Y1128289D03*
X693197Y1134982D03*
Y1131635D03*
Y1124942D03*
Y1121596D03*
Y1141675D03*
Y1148367D03*
Y1138328D03*
Y1145021D03*
X681455Y1163427D03*
X682505Y1158407D03*
X687747Y1155060D03*
Y1165100D03*
X693197Y1151714D03*
Y1161753D03*
Y1158407D03*
X682505Y1168446D03*
X693197Y1171793D03*
Y1178486D03*
Y1168446D03*
Y1175139D03*
X687747Y1191871D03*
X693197Y1185178D03*
Y1181832D03*
Y1188525D03*
X681455Y1200238D03*
X682505Y1205257D03*
Y1195218D03*
X687747Y1201911D03*
X693197Y1208604D03*
Y1205257D03*
Y1198564D03*
Y1195218D03*
Y1215297D03*
Y1221989D03*
Y1211950D03*
Y1218643D03*
X681455Y1237049D03*
X682505Y1232029D03*
X687747Y1238722D03*
Y1228682D03*
X693197Y1225336D03*
Y1235375D03*
Y1232029D03*
X682505Y1242068D03*
X693197Y1245415D03*
Y1252108D03*
Y1242068D03*
Y1248761D03*
X697642Y733401D03*
X697697Y756832D03*
X702256D03*
Y760178D03*
X706756Y776911D03*
X697747Y766871D03*
X697697Y763525D03*
X702206D03*
X697747Y770218D03*
X697597Y791970D03*
X706756Y783604D03*
Y780257D03*
Y786950D03*
Y807029D03*
Y803682D03*
Y793643D03*
Y796989D03*
Y813722D03*
Y820415D03*
Y817068D03*
Y810375D03*
X697597Y828781D03*
X706756Y823761D03*
Y830454D03*
Y833800D03*
Y843840D03*
Y850533D03*
Y840493D03*
Y847186D03*
X697597Y865592D03*
X706756Y857226D03*
Y853879D03*
Y860572D03*
Y880651D03*
Y877304D03*
Y867265D03*
Y870611D03*
Y887344D03*
Y894037D03*
Y883997D03*
Y890690D03*
X697597Y902403D03*
X706756Y897383D03*
Y904076D03*
Y907423D03*
Y924155D03*
Y917462D03*
Y914115D03*
Y920808D03*
X697597Y939214D03*
X706756Y930848D03*
Y927501D03*
Y934194D03*
Y940887D03*
Y954273D03*
Y950926D03*
Y944234D03*
Y960966D03*
Y967659D03*
Y964312D03*
Y957619D03*
Y971005D03*
Y974352D03*
Y981045D03*
Y977698D03*
Y984391D03*
Y987737D03*
Y994430D03*
Y1001123D03*
Y997777D03*
Y991084D03*
Y1004470D03*
Y1041281D03*
Y1034588D03*
Y1031241D03*
Y1037934D03*
Y1044627D03*
Y1047974D03*
Y1054667D03*
Y1058013D03*
Y1051320D03*
Y1071399D03*
Y1061360D03*
Y1074745D03*
Y1068052D03*
Y1064706D03*
Y1078092D03*
X697597Y1086458D03*
X706756Y1081438D03*
Y1088131D03*
Y1101517D03*
Y1098171D03*
Y1104863D03*
Y1091478D03*
Y1114903D03*
Y1108210D03*
Y1111556D03*
Y1118249D03*
X697597Y1123269D03*
X706756Y1134982D03*
Y1124942D03*
Y1128289D03*
Y1145021D03*
Y1138328D03*
Y1148367D03*
Y1141675D03*
Y1151714D03*
X697597Y1160080D03*
X706756Y1155060D03*
Y1161753D03*
Y1165100D03*
Y1175139D03*
Y1171793D03*
Y1178486D03*
Y1181832D03*
Y1188525D03*
Y1185178D03*
Y1191871D03*
X697597Y1196891D03*
X706756Y1208604D03*
Y1198564D03*
Y1201911D03*
Y1211950D03*
Y1218643D03*
Y1215297D03*
Y1221989D03*
Y1225336D03*
X697597Y1233702D03*
X706756Y1228682D03*
Y1235375D03*
Y1238722D03*
Y1248761D03*
Y1245415D03*
Y1252108D03*
Y1255454D03*
X711306Y756766D03*
Y760178D03*
X718348Y756766D03*
X722898Y773564D03*
X718348Y763766D03*
X711306Y767266D03*
X722898Y776911D03*
X711307Y763766D03*
X722898Y780257D03*
X717448Y786950D03*
X712206Y790297D03*
X722898Y783604D03*
Y790297D03*
Y803682D03*
X712206Y800336D03*
X711156Y795316D03*
X717448Y796989D03*
X722898Y800336D03*
Y807029D03*
Y793643D03*
Y810375D03*
Y817068D03*
Y813722D03*
Y820415D03*
X717448Y823761D03*
Y833800D03*
X712206Y827108D03*
Y837147D03*
X711156Y832127D03*
X722898Y837147D03*
Y830454D03*
Y827108D03*
Y847186D03*
Y840493D03*
Y843840D03*
Y850533D03*
Y853879D03*
X717448Y860572D03*
X712206Y863919D03*
X722898Y857226D03*
Y863919D03*
Y877304D03*
X712206Y873958D03*
X717448Y870611D03*
X711156Y868938D03*
X722898Y873958D03*
Y880651D03*
Y867265D03*
Y883997D03*
Y890690D03*
Y887344D03*
Y894037D03*
X717448Y897383D03*
X712206Y900730D03*
X717448Y907423D03*
X712206Y910769D03*
X711156Y905750D03*
X722898Y910769D03*
Y904076D03*
Y900730D03*
Y920808D03*
Y914115D03*
Y924155D03*
Y917462D03*
Y927501D03*
X712206Y937541D03*
X717448Y934194D03*
X722898Y930848D03*
Y940887D03*
Y937541D03*
Y950926D03*
X717448Y944234D03*
X712206Y947580D03*
X711156Y942561D03*
X722898Y947580D03*
Y954273D03*
Y957619D03*
Y971005D03*
Y964312D03*
Y960966D03*
Y967659D03*
Y984391D03*
Y977698D03*
Y974352D03*
Y981045D03*
Y991084D03*
Y997777D03*
Y987737D03*
Y994430D03*
Y1001123D03*
Y1004470D03*
Y1027895D03*
Y1031241D03*
Y1037934D03*
Y1044627D03*
Y1034588D03*
Y1041281D03*
Y1051320D03*
Y1058013D03*
Y1047974D03*
Y1054667D03*
Y1068052D03*
Y1074745D03*
Y1061360D03*
Y1071399D03*
Y1064706D03*
X717448Y1081438D03*
X712206Y1084785D03*
X711156Y1089805D03*
X722898Y1078092D03*
Y1088131D03*
Y1084785D03*
X712206Y1094824D03*
X717448Y1091478D03*
X722898Y1098171D03*
Y1104863D03*
Y1094824D03*
Y1101517D03*
Y1111556D03*
X717448Y1118249D03*
X722898Y1108210D03*
Y1114903D03*
X717448Y1128289D03*
X712206Y1121596D03*
X711156Y1126616D03*
X722898Y1134982D03*
X712206Y1131635D03*
X722898D03*
Y1124942D03*
Y1121596D03*
Y1148367D03*
Y1141675D03*
Y1138328D03*
Y1145021D03*
X717448Y1165100D03*
X711156Y1163427D03*
X717448Y1155060D03*
X712206Y1158407D03*
X722898Y1151714D03*
Y1161753D03*
Y1158407D03*
Y1178486D03*
Y1171793D03*
X712206Y1168446D03*
X722898D03*
Y1175139D03*
Y1185178D03*
X717448Y1191871D03*
X722898Y1181832D03*
Y1188525D03*
Y1208604D03*
X712206Y1195218D03*
X711156Y1200238D03*
X717448Y1201911D03*
X712206Y1205257D03*
X722898D03*
Y1198564D03*
Y1195218D03*
Y1215297D03*
Y1221989D03*
Y1211950D03*
Y1218643D03*
X717448Y1228682D03*
X712206Y1232029D03*
X717448Y1238722D03*
X711156Y1237049D03*
X722898Y1225336D03*
Y1235375D03*
Y1232029D03*
X712206Y1242068D03*
X722898Y1252108D03*
Y1245415D03*
Y1242068D03*
Y1248761D03*
X727398Y756832D03*
X731957D03*
Y760178D03*
X736457Y776911D03*
X727398Y763525D03*
X731462Y766871D03*
X731907Y763525D03*
X727448Y770218D03*
X736457Y783604D03*
X727298Y791970D03*
X736457Y780257D03*
Y786950D03*
Y807029D03*
Y803682D03*
Y793643D03*
Y796989D03*
Y813722D03*
Y820415D03*
Y817068D03*
Y810375D03*
X727298Y828781D03*
X736457Y823761D03*
Y830454D03*
Y833800D03*
Y843840D03*
Y850533D03*
Y840493D03*
Y847186D03*
X727298Y865592D03*
X736457Y857226D03*
Y853879D03*
Y860572D03*
Y880651D03*
Y877304D03*
Y867265D03*
Y870611D03*
Y887344D03*
Y894037D03*
Y883997D03*
Y890690D03*
X727298Y902403D03*
X736457Y897383D03*
Y904076D03*
Y907423D03*
Y924155D03*
Y917462D03*
Y914115D03*
Y920808D03*
X727298Y939214D03*
X736457Y930848D03*
Y927501D03*
Y934194D03*
Y940887D03*
Y954273D03*
Y950926D03*
Y944234D03*
Y960966D03*
Y967659D03*
Y964312D03*
Y957619D03*
Y971005D03*
Y974352D03*
Y981045D03*
Y977698D03*
Y984391D03*
Y987737D03*
Y994430D03*
Y1001123D03*
Y997777D03*
Y991084D03*
Y1004470D03*
Y1034588D03*
Y1041281D03*
Y1031241D03*
Y1037934D03*
Y1044627D03*
Y1047974D03*
Y1054667D03*
Y1058013D03*
Y1051320D03*
Y1071399D03*
Y1061360D03*
Y1074745D03*
Y1068052D03*
Y1064706D03*
X727298Y1086458D03*
X736457Y1078092D03*
Y1081438D03*
Y1088131D03*
Y1101517D03*
Y1098171D03*
Y1104863D03*
Y1091478D03*
Y1114903D03*
Y1108210D03*
Y1111556D03*
Y1118249D03*
X727298Y1123269D03*
X736457Y1134982D03*
Y1124942D03*
Y1128289D03*
Y1145021D03*
Y1138328D03*
Y1148367D03*
Y1141675D03*
X727298Y1160080D03*
X736457Y1151714D03*
Y1155060D03*
Y1161753D03*
Y1165100D03*
Y1175139D03*
Y1171793D03*
Y1178486D03*
Y1181832D03*
Y1188525D03*
Y1185178D03*
Y1191871D03*
X727298Y1196891D03*
X736457Y1208604D03*
Y1198564D03*
Y1201911D03*
Y1211950D03*
Y1218643D03*
Y1215297D03*
Y1221989D03*
X727298Y1233702D03*
X736457Y1225336D03*
Y1228682D03*
Y1235375D03*
Y1238722D03*
Y1248761D03*
Y1245415D03*
Y1252108D03*
Y1255454D03*
X748049Y756766D03*
X741007D03*
Y760266D03*
X752599Y773564D03*
X741007Y767266D03*
X748049Y763766D03*
X752599Y776911D03*
X741007Y763766D03*
X752599Y780257D03*
X747149Y786950D03*
X741907Y790297D03*
X752599Y783604D03*
Y790297D03*
Y803682D03*
X747149Y796989D03*
X741907Y800336D03*
X740857Y795316D03*
X752599Y800336D03*
Y807029D03*
Y793643D03*
Y810375D03*
Y817068D03*
Y813722D03*
Y820415D03*
X747149Y823761D03*
Y833800D03*
X741907Y827108D03*
Y837147D03*
X740857Y832127D03*
X752599Y837147D03*
Y830454D03*
Y827108D03*
Y840493D03*
Y847186D03*
Y843840D03*
Y850533D03*
Y853879D03*
X747149Y860572D03*
X741907Y863919D03*
X752599Y857226D03*
Y863919D03*
Y877304D03*
X741907Y873958D03*
X747149Y870611D03*
X740857Y868938D03*
X752599Y873958D03*
Y880651D03*
Y867265D03*
Y890690D03*
Y883997D03*
Y887344D03*
Y894037D03*
X747149Y897383D03*
X741907Y900730D03*
X747149Y907423D03*
X741907Y910769D03*
X740857Y905750D03*
X752599Y910769D03*
Y904076D03*
Y900730D03*
Y920808D03*
Y914115D03*
Y924155D03*
Y917462D03*
X747149Y934194D03*
X752599Y927501D03*
X741907Y937541D03*
X752599Y930848D03*
Y940887D03*
Y937541D03*
Y950926D03*
X747149Y944234D03*
X741907Y947580D03*
X740857Y942561D03*
X752599Y947580D03*
Y954273D03*
Y957619D03*
Y971005D03*
Y964312D03*
Y960966D03*
Y967659D03*
Y984391D03*
Y977698D03*
Y974352D03*
Y981045D03*
Y991084D03*
Y997777D03*
Y987737D03*
Y994430D03*
Y1001123D03*
Y1004470D03*
Y1027895D03*
Y1031241D03*
Y1037934D03*
Y1044627D03*
Y1034588D03*
Y1041281D03*
Y1051320D03*
Y1058013D03*
Y1047974D03*
Y1054667D03*
Y1068052D03*
Y1074745D03*
Y1061360D03*
Y1071399D03*
Y1064706D03*
X747149Y1081438D03*
X741907Y1084785D03*
X740857Y1089805D03*
X752599Y1078092D03*
Y1088131D03*
Y1084785D03*
Y1098171D03*
Y1104863D03*
X741907Y1094824D03*
X747149Y1091478D03*
X752599Y1094824D03*
Y1101517D03*
Y1111556D03*
X747149Y1118249D03*
X752599Y1108210D03*
Y1114903D03*
X747149Y1128289D03*
X740857Y1126616D03*
X741907Y1121596D03*
X752599Y1134982D03*
X741907Y1131635D03*
X752599D03*
Y1124942D03*
Y1121596D03*
Y1148367D03*
Y1141675D03*
Y1138328D03*
Y1145021D03*
X740857Y1163427D03*
X747149Y1165100D03*
X741907Y1158407D03*
X747149Y1155060D03*
X752599Y1151714D03*
Y1161753D03*
Y1158407D03*
Y1178486D03*
Y1171793D03*
X741907Y1168446D03*
X752599D03*
Y1175139D03*
Y1185178D03*
X747149Y1191871D03*
X752599Y1181832D03*
Y1188525D03*
Y1208604D03*
X741907Y1195218D03*
X740857Y1200238D03*
X747149Y1201911D03*
X741907Y1205257D03*
X752599D03*
Y1198564D03*
Y1195218D03*
Y1215297D03*
Y1221989D03*
Y1211950D03*
Y1218643D03*
X747149Y1228682D03*
X741907Y1232029D03*
X747149Y1238722D03*
X740857Y1237049D03*
X752599Y1225336D03*
Y1235375D03*
Y1232029D03*
X741907Y1242068D03*
X752599Y1252108D03*
Y1245415D03*
Y1242068D03*
Y1248761D03*
X757099Y756832D03*
X761658D03*
Y760178D03*
X766158Y776911D03*
X757149Y766871D03*
X757099Y763525D03*
X761608D03*
X757149Y770218D03*
X766158Y783604D03*
X756999Y791970D03*
X766158Y780257D03*
Y786950D03*
Y807029D03*
Y803682D03*
Y793643D03*
Y796989D03*
Y813722D03*
Y820415D03*
Y817068D03*
Y810375D03*
X756999Y828781D03*
X766158Y823761D03*
Y830454D03*
Y833800D03*
Y843840D03*
Y850533D03*
Y840493D03*
Y847186D03*
Y857226D03*
X756999Y865592D03*
X766158Y853879D03*
Y860572D03*
Y880651D03*
Y877304D03*
Y867265D03*
Y870611D03*
Y887344D03*
Y894037D03*
Y883997D03*
Y890690D03*
X756999Y902403D03*
X766158Y897383D03*
Y904076D03*
Y907423D03*
Y924155D03*
Y917462D03*
Y914115D03*
Y920808D03*
X756999Y939214D03*
X766158Y930848D03*
Y927501D03*
Y934194D03*
Y940887D03*
Y954273D03*
Y950926D03*
Y944234D03*
Y960966D03*
Y967659D03*
Y964312D03*
Y957619D03*
Y971005D03*
Y974352D03*
Y981045D03*
Y977698D03*
Y984391D03*
Y987737D03*
Y994430D03*
Y1001123D03*
Y997777D03*
Y991084D03*
Y1004470D03*
Y1041281D03*
Y1034588D03*
Y1031241D03*
Y1037934D03*
Y1044627D03*
Y1047974D03*
Y1054667D03*
Y1058013D03*
Y1051320D03*
Y1071399D03*
Y1061360D03*
Y1074745D03*
Y1068052D03*
Y1064706D03*
X756999Y1086458D03*
X766158Y1078092D03*
Y1081438D03*
Y1088131D03*
Y1101517D03*
Y1098171D03*
Y1104863D03*
Y1091478D03*
Y1114903D03*
Y1108210D03*
Y1111556D03*
Y1118249D03*
X756999Y1123269D03*
X766158Y1134982D03*
Y1124942D03*
Y1128289D03*
Y1145021D03*
Y1138328D03*
Y1148367D03*
Y1141675D03*
X756999Y1160080D03*
X766158Y1151714D03*
Y1155060D03*
Y1161753D03*
Y1165100D03*
Y1175139D03*
Y1171793D03*
Y1178486D03*
Y1181832D03*
Y1188525D03*
Y1185178D03*
Y1191871D03*
X756999Y1196891D03*
X766158Y1208604D03*
Y1198564D03*
Y1201911D03*
Y1211950D03*
Y1218643D03*
Y1215297D03*
Y1221989D03*
Y1225336D03*
X756999Y1233702D03*
X766158Y1228682D03*
Y1235375D03*
Y1238722D03*
Y1248761D03*
Y1245415D03*
Y1252108D03*
Y1255454D03*
X777900Y756766D03*
X770708D03*
Y760266D03*
X782300Y773564D03*
X770708Y767266D03*
X777900Y763766D03*
X782300Y776911D03*
X770708Y763766D03*
X776850Y786950D03*
X771608Y790297D03*
X782300Y780257D03*
Y783604D03*
Y790297D03*
X776850Y796989D03*
X771608Y800336D03*
X770558Y795316D03*
X782300Y803682D03*
Y800336D03*
Y807029D03*
Y793643D03*
Y810375D03*
Y817068D03*
Y813722D03*
Y820415D03*
X771608Y837147D03*
X770558Y832127D03*
X776850Y823761D03*
Y833800D03*
X771608Y827108D03*
X782300Y837147D03*
Y830454D03*
Y827108D03*
Y847186D03*
Y840493D03*
Y843840D03*
Y850533D03*
X776850Y860572D03*
X771608Y863919D03*
X782300Y853879D03*
Y857226D03*
Y863919D03*
X771608Y873958D03*
X782300Y877304D03*
X776850Y870611D03*
X770558Y868938D03*
X782300Y873958D03*
Y880651D03*
Y867265D03*
Y890690D03*
Y883997D03*
Y887344D03*
Y894037D03*
X776850Y897383D03*
X771608Y900730D03*
X776850Y907423D03*
X771608Y910769D03*
X770558Y905750D03*
X782300Y910769D03*
Y904076D03*
Y900730D03*
Y920808D03*
Y914115D03*
Y924155D03*
Y917462D03*
X771608Y937541D03*
X776850Y934194D03*
X782300Y927501D03*
Y930848D03*
Y940887D03*
Y937541D03*
X776850Y944234D03*
X771608Y947580D03*
X770558Y942561D03*
X782300Y950926D03*
Y947580D03*
Y954273D03*
Y957619D03*
Y971005D03*
Y964312D03*
Y960966D03*
Y967659D03*
Y984391D03*
Y977698D03*
Y974352D03*
Y981045D03*
Y991084D03*
Y997777D03*
Y987737D03*
Y994430D03*
Y1001123D03*
Y1004470D03*
Y1027895D03*
Y1031241D03*
Y1037934D03*
Y1044627D03*
Y1034588D03*
Y1041281D03*
Y1051320D03*
Y1058013D03*
Y1047974D03*
Y1054667D03*
Y1068052D03*
Y1074745D03*
Y1061360D03*
Y1071399D03*
Y1064706D03*
X776850Y1081438D03*
X771608Y1084785D03*
X770558Y1089805D03*
X782300Y1078092D03*
Y1088131D03*
Y1084785D03*
Y1098171D03*
Y1104863D03*
X776850Y1091478D03*
X771608Y1094824D03*
X782300D03*
Y1101517D03*
X776850Y1118249D03*
X782300Y1111556D03*
Y1108210D03*
Y1114903D03*
X776850Y1128289D03*
X770558Y1126616D03*
X771608Y1121596D03*
Y1131635D03*
X782300Y1134982D03*
Y1131635D03*
Y1124942D03*
Y1121596D03*
Y1148367D03*
Y1141675D03*
Y1138328D03*
Y1145021D03*
X776850Y1165100D03*
X770558Y1163427D03*
X776850Y1155060D03*
X771608Y1158407D03*
X782300Y1151714D03*
Y1161753D03*
Y1158407D03*
Y1178486D03*
X771608Y1168446D03*
X782300Y1171793D03*
Y1168446D03*
Y1175139D03*
Y1185178D03*
X776850Y1191871D03*
X782300Y1181832D03*
Y1188525D03*
Y1208604D03*
X771608Y1195218D03*
X770558Y1200238D03*
X776850Y1201911D03*
X771608Y1205257D03*
X782300D03*
Y1198564D03*
Y1195218D03*
Y1215297D03*
Y1221989D03*
Y1211950D03*
Y1218643D03*
X776850Y1228682D03*
X771608Y1232029D03*
X776850Y1238722D03*
X770558Y1237049D03*
X782300Y1225336D03*
Y1235375D03*
Y1232029D03*
X771608Y1242068D03*
X782300Y1252108D03*
Y1245415D03*
Y1242068D03*
Y1248761D03*
X786800Y756832D03*
X791358Y760178D03*
Y756832D03*
X795858Y776911D03*
X786850Y766871D03*
X786800Y763525D03*
X791308D03*
X786850Y770218D03*
X795858Y783604D03*
X786700Y791970D03*
X795858Y780257D03*
Y786950D03*
Y807029D03*
Y803682D03*
Y793643D03*
Y796989D03*
Y820415D03*
Y813722D03*
Y817068D03*
Y810375D03*
X786700Y828781D03*
X795858Y823761D03*
Y830454D03*
Y833800D03*
Y843840D03*
Y850533D03*
Y840493D03*
Y847186D03*
X786700Y865592D03*
X795858Y857226D03*
Y853879D03*
Y860572D03*
Y880651D03*
Y877304D03*
Y867265D03*
Y870611D03*
Y894037D03*
Y887344D03*
Y883997D03*
Y890690D03*
X786700Y902403D03*
X795858Y897383D03*
Y904076D03*
Y907423D03*
Y924155D03*
Y917462D03*
Y914115D03*
Y920808D03*
X786700Y939214D03*
X795858Y930848D03*
Y927501D03*
Y934194D03*
Y940887D03*
Y954273D03*
Y950926D03*
Y944234D03*
Y960966D03*
Y967659D03*
Y964312D03*
Y957619D03*
Y971005D03*
Y981045D03*
Y974352D03*
Y977698D03*
Y984391D03*
Y994430D03*
Y987737D03*
Y1001123D03*
Y997777D03*
Y991084D03*
Y1004470D03*
Y1041281D03*
Y1034588D03*
Y1031241D03*
Y1037934D03*
Y1044627D03*
Y1054667D03*
Y1047974D03*
Y1058013D03*
Y1051320D03*
Y1071399D03*
Y1061360D03*
Y1074745D03*
Y1068052D03*
Y1064706D03*
X786700Y1086458D03*
X795858Y1078092D03*
Y1081438D03*
Y1088131D03*
Y1101517D03*
Y1098171D03*
Y1104863D03*
Y1091478D03*
Y1114903D03*
Y1108210D03*
Y1111556D03*
Y1118249D03*
X786700Y1123269D03*
X795858Y1134982D03*
Y1124942D03*
Y1128289D03*
Y1145021D03*
Y1138328D03*
Y1148367D03*
Y1141675D03*
X786700Y1160080D03*
X795858Y1151714D03*
Y1155060D03*
Y1161753D03*
Y1165100D03*
Y1175139D03*
Y1171793D03*
Y1178486D03*
Y1181832D03*
Y1188525D03*
Y1185178D03*
Y1191871D03*
X786700Y1196891D03*
X795858Y1208604D03*
Y1198564D03*
Y1201911D03*
Y1218643D03*
Y1211950D03*
Y1215297D03*
Y1221989D03*
X786700Y1233702D03*
X795858Y1225336D03*
Y1228682D03*
Y1235375D03*
Y1238722D03*
Y1248761D03*
Y1245415D03*
Y1252108D03*
Y1255454D03*
X807450Y756766D03*
X800408D03*
Y760266D03*
X812000Y773564D03*
X807451Y763765D03*
X800408Y767266D03*
X812000Y776911D03*
X800409Y763765D03*
X812000Y780257D03*
X806550Y786950D03*
X801308Y790297D03*
X812000Y783604D03*
Y790297D03*
Y803682D03*
X806550Y796989D03*
X800258Y795316D03*
X801308Y800336D03*
X812000D03*
Y807029D03*
Y793643D03*
Y817068D03*
Y810375D03*
Y813722D03*
Y820415D03*
X800258Y832127D03*
X801308Y837147D03*
Y827108D03*
X806550Y833800D03*
Y823761D03*
X812000Y837147D03*
Y830454D03*
Y827108D03*
Y847186D03*
Y840493D03*
Y843840D03*
Y850533D03*
X806550Y860572D03*
X801308Y863919D03*
X812000Y853879D03*
Y857226D03*
Y863919D03*
Y877304D03*
X801308Y873958D03*
X806550Y870611D03*
X800258Y868938D03*
X812000Y873958D03*
Y880651D03*
Y867265D03*
Y890690D03*
Y883997D03*
Y887344D03*
Y894037D03*
X806550Y897383D03*
X801308Y900730D03*
X806550Y907423D03*
X800258Y905750D03*
X801308Y910769D03*
X812000D03*
Y904076D03*
Y900730D03*
Y920808D03*
Y914115D03*
Y924155D03*
Y917462D03*
X801308Y937541D03*
X812000Y927501D03*
X806550Y934194D03*
X812000Y930848D03*
Y940887D03*
Y937541D03*
Y950926D03*
X800258Y942561D03*
X801308Y947580D03*
X806550Y944234D03*
X812000Y947580D03*
Y954273D03*
Y957619D03*
Y971005D03*
Y964312D03*
Y960966D03*
Y967659D03*
Y984391D03*
Y977698D03*
Y974352D03*
Y981045D03*
Y997777D03*
Y991084D03*
Y987737D03*
Y994430D03*
Y1001123D03*
Y1004470D03*
Y1027895D03*
Y1044627D03*
Y1037934D03*
Y1031241D03*
Y1034588D03*
Y1041281D03*
Y1058013D03*
Y1051320D03*
Y1047974D03*
Y1054667D03*
Y1068052D03*
Y1074745D03*
Y1061360D03*
Y1071399D03*
Y1064706D03*
X806550Y1081438D03*
X800258Y1089805D03*
X801308Y1084785D03*
X812000Y1078092D03*
Y1088131D03*
Y1084785D03*
Y1098171D03*
Y1104863D03*
X806550Y1091478D03*
X801308Y1094824D03*
X812000D03*
Y1101517D03*
Y1111556D03*
X806550Y1118249D03*
X812000Y1108210D03*
Y1114903D03*
X806550Y1128289D03*
X800258Y1126616D03*
X801308Y1121596D03*
X812000Y1134982D03*
X801308Y1131635D03*
X812000D03*
Y1124942D03*
Y1121596D03*
Y1148367D03*
Y1141675D03*
Y1138328D03*
Y1145021D03*
X806550Y1165100D03*
X800258Y1163427D03*
X806550Y1155060D03*
X801308Y1158407D03*
X812000Y1151714D03*
Y1161753D03*
Y1158407D03*
Y1178486D03*
Y1171793D03*
X801308Y1168446D03*
X812000D03*
Y1175139D03*
Y1185178D03*
X806550Y1191871D03*
X812000Y1181832D03*
Y1188525D03*
Y1208604D03*
X801308Y1195218D03*
X806550Y1201911D03*
X801308Y1205257D03*
X800258Y1200238D03*
X812000Y1205257D03*
Y1198564D03*
Y1195218D03*
Y1221989D03*
Y1215297D03*
Y1211950D03*
Y1218643D03*
X806550Y1228682D03*
X801308Y1232029D03*
X806550Y1238722D03*
X800258Y1237049D03*
X812000Y1225336D03*
Y1235375D03*
Y1232029D03*
Y1245415D03*
Y1252108D03*
X801308Y1242068D03*
X812000D03*
Y1248761D03*
X816500Y756832D03*
X816550Y770218D03*
X816500Y763525D03*
X816400Y828781D03*
Y865592D03*
Y902403D03*
Y939214D03*
Y1086458D03*
Y1123269D03*
Y1160080D03*
Y1196891D03*
Y1233702D03*
X831756Y901318D03*
X897824Y909093D03*
X904719Y921792D03*
X909890Y950217D03*
X910066Y960332D03*
X909203Y970709D03*
X908799Y985291D03*
X923916Y843990D03*
X931948Y891397D03*
X919916Y908916D03*
X920276Y900554D03*
X931877Y918168D03*
X928535Y913454D03*
X920409Y918274D03*
X926062Y938727D03*
X926004Y952716D03*
X940391Y859947D03*
X940514Y918134D03*
X939670Y945169D03*
X942924Y982547D03*
X943135Y977129D03*
X958051Y859384D03*
X948060Y891468D03*
X951367Y913648D03*
X1050015Y756765D03*
Y760265D03*
X1040965Y756831D03*
Y760177D03*
X1045465Y776910D03*
X1050015Y767265D03*
Y763765D03*
X1040915Y763524D03*
X1050915Y790296D03*
X1045465Y783603D03*
Y780256D03*
Y786949D03*
X1050915Y800335D03*
X1041065Y795315D03*
X1045465Y807028D03*
Y803681D03*
Y793642D03*
Y796988D03*
Y813721D03*
Y820414D03*
Y817067D03*
Y810374D03*
X1050915Y827107D03*
Y837146D03*
X1041065Y832126D03*
X1045465Y823760D03*
Y830453D03*
Y833799D03*
Y850532D03*
Y843839D03*
Y840492D03*
Y847185D03*
X1050915Y863918D03*
X1045465Y857225D03*
Y853878D03*
Y860571D03*
X1041065Y868937D03*
X1050915Y873957D03*
X1045465Y880650D03*
Y877303D03*
Y867264D03*
Y870610D03*
Y887343D03*
Y894036D03*
Y883996D03*
Y890689D03*
X1050915Y910768D03*
X1041065Y905749D03*
X1050915Y900729D03*
X1045465Y897382D03*
Y904075D03*
Y907422D03*
Y917461D03*
Y924154D03*
Y914114D03*
Y920807D03*
Y930847D03*
X1050915Y937540D03*
X1045465Y927500D03*
Y934193D03*
Y940886D03*
X1050915Y947579D03*
X1041065Y942560D03*
X1045465Y954272D03*
Y950925D03*
Y944233D03*
Y967658D03*
Y960965D03*
Y964311D03*
Y957618D03*
Y971004D03*
Y974351D03*
Y981044D03*
Y977697D03*
Y984390D03*
Y987736D03*
Y994429D03*
Y1001122D03*
Y997776D03*
Y991083D03*
Y1004469D03*
Y1041280D03*
Y1034587D03*
Y1031240D03*
Y1037933D03*
Y1044626D03*
Y1047973D03*
Y1054666D03*
Y1058012D03*
Y1051319D03*
Y1061359D03*
Y1071398D03*
Y1074744D03*
Y1068051D03*
Y1064705D03*
Y1078091D03*
X1050915Y1084784D03*
X1041065Y1089804D03*
X1045465Y1081437D03*
Y1088130D03*
X1050915Y1094823D03*
X1045465Y1101516D03*
Y1098170D03*
Y1104862D03*
Y1091477D03*
Y1108209D03*
Y1114902D03*
Y1111555D03*
Y1118248D03*
X1050915Y1131634D03*
Y1121595D03*
X1041065Y1126615D03*
X1045465Y1134981D03*
Y1124941D03*
Y1128288D03*
Y1138327D03*
Y1145020D03*
Y1148366D03*
Y1141674D03*
X1050915Y1158406D03*
X1045465Y1151713D03*
X1041065Y1163426D03*
X1045465Y1155059D03*
Y1161752D03*
Y1165099D03*
X1050915Y1168445D03*
X1045465Y1175138D03*
Y1171792D03*
Y1178485D03*
Y1188524D03*
Y1181831D03*
Y1185177D03*
Y1191870D03*
X1041065Y1200237D03*
X1050915Y1205256D03*
Y1195217D03*
X1045465Y1208603D03*
Y1198563D03*
Y1201910D03*
Y1211949D03*
Y1218642D03*
Y1215296D03*
Y1221988D03*
X1041065Y1237048D03*
X1045465Y1225335D03*
X1050915Y1232028D03*
X1045465Y1228681D03*
Y1235374D03*
Y1238721D03*
Y1248760D03*
X1050915Y1242067D03*
X1045465Y1245414D03*
Y1252107D03*
Y1255453D03*
X1057057Y756765D03*
X1066107Y756831D03*
X1061607Y773563D03*
X1057057Y763765D03*
X1066157Y766870D03*
X1061607Y776910D03*
X1066107Y763524D03*
X1066157Y770217D03*
X1057207Y791969D03*
X1056157Y786949D03*
X1061607Y780256D03*
Y783603D03*
Y790296D03*
Y803681D03*
X1056157Y796988D03*
X1061607Y800335D03*
Y807028D03*
Y793642D03*
Y810374D03*
Y817067D03*
Y813721D03*
Y820414D03*
X1056157Y823760D03*
Y833799D03*
X1057207Y828780D03*
X1061607Y837146D03*
Y830453D03*
Y827107D03*
Y847185D03*
Y840492D03*
Y843839D03*
Y850532D03*
Y853878D03*
X1056157Y860571D03*
X1057207Y865591D03*
X1061607Y857225D03*
Y863918D03*
X1056157Y870610D03*
X1061607Y877303D03*
Y873957D03*
Y880650D03*
Y867264D03*
Y883996D03*
Y890689D03*
Y887343D03*
Y894036D03*
X1056157Y907422D03*
Y897382D03*
X1057207Y902402D03*
X1061607Y910768D03*
Y904075D03*
Y900729D03*
Y914114D03*
Y920807D03*
Y924154D03*
Y917461D03*
Y927500D03*
X1056157Y934193D03*
X1057207Y939213D03*
X1061607Y930847D03*
Y940886D03*
Y937540D03*
Y950925D03*
X1056157Y944233D03*
X1061607Y947579D03*
Y954272D03*
Y964311D03*
Y971004D03*
Y957618D03*
Y960965D03*
Y967658D03*
Y977697D03*
Y984390D03*
Y974351D03*
Y981044D03*
Y991083D03*
Y997776D03*
Y987736D03*
Y994429D03*
Y1001122D03*
Y1004469D03*
Y1027894D03*
Y1037933D03*
Y1044626D03*
Y1031240D03*
Y1034587D03*
Y1041280D03*
Y1051319D03*
Y1058012D03*
Y1047973D03*
Y1054666D03*
Y1074744D03*
Y1068051D03*
Y1061359D03*
Y1071398D03*
Y1064705D03*
X1057207Y1086457D03*
X1056157Y1081437D03*
X1061607Y1078091D03*
Y1088130D03*
Y1084784D03*
X1056157Y1091477D03*
X1061607Y1098170D03*
Y1104862D03*
Y1094823D03*
Y1101516D03*
X1056157Y1118248D03*
X1061607Y1111555D03*
Y1108209D03*
Y1114902D03*
Y1134981D03*
X1057207Y1123268D03*
X1056157Y1128288D03*
X1061607Y1131634D03*
Y1124941D03*
Y1121595D03*
Y1141674D03*
Y1148366D03*
Y1138327D03*
Y1145020D03*
X1056157Y1155059D03*
Y1165099D03*
X1057207Y1160079D03*
X1061607Y1151713D03*
Y1161752D03*
Y1158406D03*
Y1171792D03*
Y1178485D03*
Y1168445D03*
Y1175138D03*
X1056157Y1191870D03*
X1061607Y1185177D03*
Y1181831D03*
Y1188524D03*
X1056157Y1201910D03*
X1057207Y1196890D03*
X1061607Y1208603D03*
Y1205256D03*
Y1198563D03*
Y1195217D03*
Y1215296D03*
Y1221988D03*
Y1211949D03*
Y1218642D03*
X1056157Y1238721D03*
X1057207Y1233701D03*
X1056157Y1228681D03*
X1061607Y1225335D03*
Y1235374D03*
Y1232028D03*
Y1245414D03*
Y1252107D03*
Y1242067D03*
Y1248760D03*
X1079716Y756765D03*
Y760265D03*
X1070666Y756831D03*
Y760177D03*
X1079716Y767265D03*
X1075166Y776910D03*
X1079716Y763765D03*
X1070616Y763524D03*
X1080616Y790296D03*
X1075166Y783603D03*
Y780256D03*
Y786949D03*
X1070766Y795315D03*
X1080616Y800335D03*
X1075166Y807028D03*
Y803681D03*
Y793642D03*
Y796988D03*
Y813721D03*
Y820414D03*
Y817067D03*
Y810374D03*
X1070766Y832126D03*
X1080616Y827107D03*
Y837146D03*
X1075166Y823760D03*
Y830453D03*
Y833799D03*
Y850532D03*
Y843839D03*
Y840492D03*
Y847185D03*
X1080616Y863918D03*
X1075166Y857225D03*
Y853878D03*
Y860571D03*
X1070766Y868937D03*
X1080616Y873957D03*
X1075166Y880650D03*
Y877303D03*
Y867264D03*
Y870610D03*
Y887343D03*
Y894036D03*
Y883996D03*
Y890689D03*
X1080616Y910768D03*
X1070766Y905749D03*
X1080616Y900729D03*
X1075166Y897382D03*
Y904075D03*
Y907422D03*
Y917461D03*
Y924154D03*
Y914114D03*
Y920807D03*
Y930847D03*
X1080616Y937540D03*
X1075166Y927500D03*
Y934193D03*
Y940886D03*
X1070766Y942560D03*
X1080616Y947579D03*
X1075166Y954272D03*
Y950925D03*
Y944233D03*
Y967658D03*
Y960965D03*
Y964311D03*
Y957618D03*
Y971004D03*
Y974351D03*
Y981044D03*
Y977697D03*
Y984390D03*
Y987736D03*
Y994429D03*
Y1001122D03*
Y997776D03*
Y991083D03*
Y1004469D03*
Y1034587D03*
Y1041280D03*
Y1031240D03*
Y1037933D03*
Y1044626D03*
Y1047973D03*
Y1054666D03*
Y1058012D03*
Y1051319D03*
Y1061359D03*
Y1071398D03*
Y1074744D03*
Y1068051D03*
Y1064705D03*
Y1078091D03*
X1070766Y1089804D03*
X1080616Y1084784D03*
X1075166Y1081437D03*
Y1088130D03*
X1080616Y1094823D03*
X1075166Y1101516D03*
Y1098170D03*
Y1104862D03*
Y1091477D03*
Y1108209D03*
Y1114902D03*
Y1111555D03*
Y1118248D03*
X1080616Y1131634D03*
Y1121595D03*
X1070766Y1126615D03*
X1075166Y1134981D03*
Y1124941D03*
Y1128288D03*
Y1138327D03*
Y1145020D03*
Y1148366D03*
Y1141674D03*
X1080616Y1158406D03*
X1075166Y1151713D03*
X1070766Y1163426D03*
X1075166Y1155059D03*
Y1161752D03*
Y1165099D03*
X1080616Y1168445D03*
X1075166Y1175138D03*
Y1171792D03*
Y1178485D03*
Y1188524D03*
Y1181831D03*
Y1185177D03*
Y1191870D03*
X1080616Y1205256D03*
X1070766Y1200237D03*
X1080616Y1195217D03*
X1075166Y1208603D03*
Y1198563D03*
Y1201910D03*
Y1211949D03*
Y1218642D03*
Y1215296D03*
Y1221988D03*
X1070766Y1237048D03*
X1080616Y1232028D03*
X1075166Y1225335D03*
Y1228681D03*
Y1235374D03*
Y1238721D03*
Y1248760D03*
X1080616Y1242067D03*
X1075166Y1245414D03*
Y1252107D03*
Y1255453D03*
X1086758Y756765D03*
X1095808Y756831D03*
X1091308Y773563D03*
X1086758Y763765D03*
X1095858Y766870D03*
X1091308Y776910D03*
X1095808Y763524D03*
X1095858Y770217D03*
X1086908Y791969D03*
X1091308Y780256D03*
X1085858Y786949D03*
X1091308Y783603D03*
Y790296D03*
Y803681D03*
X1085858Y796988D03*
X1091308Y800335D03*
Y807028D03*
Y793642D03*
Y810374D03*
Y817067D03*
Y813721D03*
Y820414D03*
X1085858Y823760D03*
Y833799D03*
X1086908Y828780D03*
X1091308Y837146D03*
Y830453D03*
Y827107D03*
Y840492D03*
Y847185D03*
Y843839D03*
Y850532D03*
Y853878D03*
X1085858Y860571D03*
X1086908Y865591D03*
X1091308Y857225D03*
Y863918D03*
X1085858Y870610D03*
X1091308Y877303D03*
Y873957D03*
Y880650D03*
Y867264D03*
Y883996D03*
Y890689D03*
Y887343D03*
Y894036D03*
X1085858Y907422D03*
Y897382D03*
X1086908Y902402D03*
X1091308Y910768D03*
Y904075D03*
Y900729D03*
Y914114D03*
Y920807D03*
Y924154D03*
Y917461D03*
X1085858Y934193D03*
X1091308Y927500D03*
X1086908Y939213D03*
X1091308Y930847D03*
Y940886D03*
Y937540D03*
X1085858Y944233D03*
X1091308Y950925D03*
Y947579D03*
Y954272D03*
Y964311D03*
Y971004D03*
Y957618D03*
Y960965D03*
Y967658D03*
Y977697D03*
Y984390D03*
Y974351D03*
Y981044D03*
Y991083D03*
Y997776D03*
Y987736D03*
Y994429D03*
Y1001122D03*
Y1004469D03*
Y1027894D03*
Y1031240D03*
Y1037933D03*
Y1044626D03*
Y1034587D03*
Y1041280D03*
Y1051319D03*
Y1058012D03*
Y1047973D03*
Y1054666D03*
Y1074744D03*
Y1068051D03*
Y1061359D03*
Y1071398D03*
Y1064705D03*
X1086908Y1086457D03*
X1085858Y1081437D03*
X1091308Y1078091D03*
Y1088130D03*
Y1084784D03*
X1085858Y1091477D03*
X1091308Y1098170D03*
Y1104862D03*
Y1094823D03*
Y1101516D03*
X1085858Y1118248D03*
X1091308Y1111555D03*
Y1108209D03*
Y1114902D03*
Y1134981D03*
X1086908Y1123268D03*
X1085858Y1128288D03*
X1091308Y1131634D03*
Y1124941D03*
Y1121595D03*
Y1141674D03*
Y1148366D03*
Y1138327D03*
Y1145020D03*
X1085858Y1155059D03*
Y1165099D03*
X1086908Y1160079D03*
X1091308Y1151713D03*
Y1161752D03*
Y1158406D03*
Y1171792D03*
Y1178485D03*
Y1168445D03*
Y1175138D03*
X1085858Y1191870D03*
X1091308Y1185177D03*
Y1181831D03*
Y1188524D03*
X1085858Y1201910D03*
X1086908Y1196890D03*
X1091308Y1208603D03*
Y1205256D03*
Y1198563D03*
Y1195217D03*
Y1215296D03*
Y1221988D03*
Y1211949D03*
Y1218642D03*
X1085858Y1238721D03*
Y1228681D03*
X1086908Y1233701D03*
X1091308Y1225335D03*
Y1235374D03*
Y1232028D03*
Y1245414D03*
Y1252107D03*
Y1242067D03*
Y1248760D03*
X1109416Y756765D03*
Y760265D03*
X1100366Y756831D03*
Y760177D03*
X1109416Y767265D03*
X1104866Y776910D03*
X1109416Y763765D03*
X1100316Y763524D03*
X1104866Y783603D03*
X1110316Y790296D03*
X1104866Y780256D03*
Y786949D03*
X1110316Y800335D03*
X1100466Y795315D03*
X1104866Y807028D03*
Y803681D03*
Y793642D03*
Y796988D03*
Y813721D03*
Y820414D03*
Y817067D03*
Y810374D03*
X1110316Y827107D03*
Y837146D03*
X1100466Y832126D03*
X1104866Y823760D03*
Y830453D03*
Y833799D03*
Y850532D03*
Y843839D03*
Y840492D03*
Y847185D03*
Y857225D03*
X1110316Y863918D03*
X1104866Y853878D03*
Y860571D03*
X1100466Y868937D03*
X1110316Y873957D03*
X1104866Y880650D03*
Y877303D03*
Y867264D03*
Y870610D03*
Y887343D03*
Y894036D03*
Y883996D03*
Y890689D03*
X1110316Y910768D03*
X1100466Y905749D03*
X1110316Y900729D03*
X1104866Y897382D03*
Y904075D03*
Y907422D03*
Y917461D03*
Y924154D03*
Y914114D03*
Y920807D03*
Y930847D03*
X1110316Y937540D03*
X1104866Y927500D03*
Y934193D03*
Y940886D03*
X1110316Y947579D03*
X1100466Y942560D03*
X1104866Y954272D03*
Y950925D03*
Y944233D03*
Y967658D03*
Y960965D03*
Y964311D03*
Y957618D03*
Y971004D03*
Y974351D03*
Y981044D03*
Y977697D03*
Y984390D03*
Y987736D03*
Y994429D03*
Y1001122D03*
Y997776D03*
Y991083D03*
Y1004469D03*
Y1034587D03*
Y1041280D03*
Y1031240D03*
Y1037933D03*
Y1044626D03*
Y1047973D03*
Y1054666D03*
Y1058012D03*
Y1051319D03*
Y1071398D03*
Y1061359D03*
Y1074744D03*
Y1068051D03*
Y1064705D03*
Y1078091D03*
X1110316Y1084784D03*
X1100466Y1089804D03*
X1104866Y1081437D03*
Y1088130D03*
X1110316Y1094823D03*
X1104866Y1101516D03*
Y1098170D03*
Y1104862D03*
Y1091477D03*
Y1108209D03*
Y1114902D03*
Y1111555D03*
Y1118248D03*
X1110316Y1131634D03*
Y1121595D03*
X1100466Y1126615D03*
X1104866Y1134981D03*
Y1124941D03*
Y1128288D03*
Y1138327D03*
Y1145020D03*
Y1148366D03*
Y1141674D03*
X1110316Y1158406D03*
X1104866Y1151713D03*
X1100466Y1163426D03*
X1104866Y1155059D03*
Y1161752D03*
Y1165099D03*
X1110316Y1168445D03*
X1104866Y1175138D03*
Y1171792D03*
Y1178485D03*
Y1188524D03*
Y1181831D03*
Y1185177D03*
Y1191870D03*
X1110316Y1205256D03*
Y1195217D03*
X1100466Y1200237D03*
X1104866Y1208603D03*
Y1198563D03*
Y1201910D03*
Y1211949D03*
Y1218642D03*
Y1215296D03*
Y1221988D03*
X1100466Y1237048D03*
X1110316Y1232028D03*
X1104866Y1225335D03*
Y1228681D03*
Y1235374D03*
Y1238721D03*
Y1248760D03*
X1110316Y1242067D03*
X1104866Y1245414D03*
Y1252107D03*
Y1255453D03*
X1116458Y756765D03*
X1125508Y756831D03*
X1121008Y773563D03*
X1116459Y763765D03*
X1125558Y766870D03*
X1121008Y776910D03*
X1125508Y763524D03*
X1125558Y770217D03*
X1116608Y791969D03*
X1121008Y780256D03*
X1115558Y786949D03*
X1121008Y783603D03*
Y790296D03*
Y803681D03*
X1115558Y796988D03*
X1121008Y800335D03*
Y807028D03*
Y793642D03*
Y810374D03*
Y817067D03*
Y813721D03*
Y820414D03*
X1115558Y823760D03*
Y833799D03*
X1116608Y828780D03*
X1121008Y837146D03*
Y830453D03*
Y827107D03*
Y847185D03*
Y840492D03*
Y843839D03*
Y850532D03*
Y853878D03*
X1115558Y860571D03*
X1116608Y865591D03*
X1121008Y857225D03*
Y863918D03*
X1115558Y870610D03*
X1121008Y877303D03*
Y873957D03*
Y880650D03*
Y867264D03*
Y883996D03*
Y890689D03*
Y887343D03*
Y894036D03*
X1115558Y907422D03*
Y897382D03*
X1116608Y902402D03*
X1121008Y910768D03*
Y904075D03*
Y900729D03*
Y914114D03*
Y920807D03*
Y924154D03*
Y917461D03*
X1115558Y934193D03*
X1121008Y927500D03*
X1116608Y939213D03*
X1121008Y930847D03*
Y940886D03*
Y937540D03*
X1115558Y944233D03*
X1121008Y950925D03*
Y947579D03*
Y954272D03*
Y964311D03*
Y971004D03*
Y957618D03*
Y960965D03*
Y967658D03*
Y977697D03*
Y984390D03*
Y974351D03*
Y981044D03*
Y991083D03*
Y997776D03*
Y987736D03*
Y994429D03*
Y1001122D03*
Y1004469D03*
Y1027894D03*
Y1031240D03*
Y1037933D03*
Y1044626D03*
Y1034587D03*
Y1041280D03*
Y1051319D03*
Y1058012D03*
Y1047973D03*
Y1054666D03*
Y1074744D03*
Y1068051D03*
Y1061359D03*
Y1071398D03*
Y1064705D03*
X1116608Y1086457D03*
X1115558Y1081437D03*
X1121008Y1078091D03*
Y1088130D03*
Y1084784D03*
X1115558Y1091477D03*
X1121008Y1098170D03*
Y1104862D03*
Y1094823D03*
Y1101516D03*
X1115558Y1118248D03*
X1121008Y1111555D03*
Y1108209D03*
Y1114902D03*
Y1134981D03*
X1116608Y1123268D03*
X1115558Y1128288D03*
X1121008Y1131634D03*
Y1124941D03*
Y1121595D03*
Y1141674D03*
Y1148366D03*
Y1138327D03*
Y1145020D03*
X1115558Y1155059D03*
Y1165099D03*
X1116608Y1160079D03*
X1121008Y1151713D03*
Y1161752D03*
Y1158406D03*
Y1171792D03*
Y1178485D03*
Y1168445D03*
Y1175138D03*
X1115558Y1191870D03*
X1121008Y1185177D03*
Y1181831D03*
Y1188524D03*
X1115558Y1201910D03*
X1116608Y1196890D03*
X1121008Y1208603D03*
Y1205256D03*
Y1198563D03*
Y1195217D03*
Y1215296D03*
Y1221988D03*
Y1211949D03*
Y1218642D03*
X1115558Y1238721D03*
Y1228681D03*
X1116608Y1233701D03*
X1121008Y1225335D03*
Y1235374D03*
Y1232028D03*
Y1245414D03*
Y1252107D03*
Y1242067D03*
Y1248760D03*
X1139117Y756765D03*
Y760265D03*
X1130067Y756831D03*
Y760177D03*
X1139117Y767265D03*
X1134567Y776910D03*
X1139117Y763765D03*
X1130017Y763524D03*
X1140017Y790296D03*
X1134567Y783603D03*
Y780256D03*
Y786949D03*
X1130167Y795315D03*
X1140017Y800335D03*
X1134567Y807028D03*
Y803681D03*
Y793642D03*
Y796988D03*
Y813721D03*
Y820414D03*
Y817067D03*
Y810374D03*
X1130167Y832126D03*
X1140017Y827107D03*
Y837146D03*
X1134567Y823760D03*
Y830453D03*
Y833799D03*
Y850532D03*
Y843839D03*
Y840492D03*
Y847185D03*
X1140017Y863918D03*
X1134567Y857225D03*
Y853878D03*
Y860571D03*
X1130167Y868937D03*
X1140017Y873957D03*
X1134567Y880650D03*
Y877303D03*
Y867264D03*
Y870610D03*
Y887343D03*
Y894036D03*
Y883996D03*
Y890689D03*
X1130167Y905749D03*
X1140017Y910768D03*
Y900729D03*
X1134567Y897382D03*
Y904075D03*
Y907422D03*
Y917461D03*
Y924154D03*
Y914114D03*
Y920807D03*
Y930847D03*
X1140017Y937540D03*
X1134567Y927500D03*
Y934193D03*
Y940886D03*
X1130167Y942560D03*
X1140017Y947579D03*
X1134567Y954272D03*
Y950925D03*
Y944233D03*
Y967658D03*
Y960965D03*
Y964311D03*
Y957618D03*
Y971004D03*
Y974351D03*
Y981044D03*
Y977697D03*
Y984390D03*
Y987736D03*
Y994429D03*
Y1001122D03*
Y997776D03*
Y991083D03*
Y1004469D03*
Y1034587D03*
Y1041280D03*
Y1031240D03*
Y1037933D03*
Y1044626D03*
Y1047973D03*
Y1054666D03*
Y1058012D03*
Y1051319D03*
Y1061359D03*
Y1071398D03*
Y1074744D03*
Y1068051D03*
Y1064705D03*
X1130167Y1089804D03*
X1134567Y1078091D03*
X1140017Y1084784D03*
X1134567Y1081437D03*
Y1088130D03*
X1140017Y1094823D03*
X1134567Y1101516D03*
Y1098170D03*
Y1104862D03*
Y1091477D03*
Y1108209D03*
Y1114902D03*
Y1111555D03*
Y1118248D03*
X1140017Y1131634D03*
X1130167Y1126615D03*
X1140017Y1121595D03*
X1134567Y1134981D03*
Y1124941D03*
Y1128288D03*
Y1138327D03*
Y1145020D03*
Y1148366D03*
Y1141674D03*
X1130167Y1163426D03*
X1134567Y1151713D03*
X1140017Y1158406D03*
X1134567Y1155059D03*
Y1161752D03*
Y1165099D03*
X1140017Y1168445D03*
X1134567Y1175138D03*
Y1171792D03*
Y1178485D03*
Y1188524D03*
Y1181831D03*
Y1185177D03*
Y1191870D03*
X1130167Y1200237D03*
X1140017Y1205256D03*
Y1195217D03*
X1134567Y1208603D03*
Y1198563D03*
Y1201910D03*
Y1211949D03*
Y1218642D03*
Y1215296D03*
Y1221988D03*
X1130167Y1237048D03*
X1140017Y1232028D03*
X1134567Y1225335D03*
Y1228681D03*
Y1235374D03*
Y1238721D03*
Y1248760D03*
X1140017Y1242067D03*
X1134567Y1245414D03*
Y1252107D03*
Y1255453D03*
X1146159Y756765D03*
X1155209Y756831D03*
X1150709Y773563D03*
X1146160Y763765D03*
X1150709Y776910D03*
X1155209Y763524D03*
X1155259Y770217D03*
X1146309Y791969D03*
X1145259Y786949D03*
X1150709Y780256D03*
Y783603D03*
Y790296D03*
X1145259Y796988D03*
X1150709Y803681D03*
Y800335D03*
Y807028D03*
Y793642D03*
Y810374D03*
Y817067D03*
Y813721D03*
Y820414D03*
X1146309Y828780D03*
X1145259Y823760D03*
Y833799D03*
X1150709Y837146D03*
Y830453D03*
Y827107D03*
Y840492D03*
Y847185D03*
Y843839D03*
Y850532D03*
X1146309Y865591D03*
X1145259Y860571D03*
X1150709Y853878D03*
Y857225D03*
Y863918D03*
X1145259Y870610D03*
X1150709Y877303D03*
Y873957D03*
Y880650D03*
Y867264D03*
Y883996D03*
Y890689D03*
Y887343D03*
Y894036D03*
X1145259Y907422D03*
X1146309Y902402D03*
X1145259Y897382D03*
X1150709Y910768D03*
Y904075D03*
Y900729D03*
Y914114D03*
Y920807D03*
Y924154D03*
Y917461D03*
X1145259Y934193D03*
X1146309Y939213D03*
X1150709Y927500D03*
Y930847D03*
Y940886D03*
Y937540D03*
X1145259Y944233D03*
X1150709Y950925D03*
Y947579D03*
Y954272D03*
Y964311D03*
Y971004D03*
Y957618D03*
Y960965D03*
Y967658D03*
Y977697D03*
Y984390D03*
Y974351D03*
Y981044D03*
Y991083D03*
Y997776D03*
Y987736D03*
Y994429D03*
Y1001122D03*
Y1004469D03*
Y1027894D03*
Y1031240D03*
Y1037933D03*
Y1044626D03*
Y1034587D03*
Y1041280D03*
Y1051319D03*
Y1058012D03*
Y1047973D03*
Y1054666D03*
Y1074744D03*
Y1068051D03*
Y1061359D03*
Y1071398D03*
Y1064705D03*
X1146309Y1086457D03*
X1145259Y1081437D03*
X1150709Y1078091D03*
Y1088130D03*
Y1084784D03*
X1145259Y1091477D03*
X1150709Y1098170D03*
Y1104862D03*
Y1094823D03*
Y1101516D03*
X1145259Y1118248D03*
X1150709Y1111555D03*
Y1108209D03*
Y1114902D03*
Y1134981D03*
X1146309Y1123268D03*
X1145259Y1128288D03*
X1150709Y1131634D03*
Y1124941D03*
Y1121595D03*
Y1141674D03*
Y1148366D03*
Y1138327D03*
Y1145020D03*
X1145259Y1155059D03*
X1146309Y1160079D03*
X1145259Y1165099D03*
X1150709Y1151713D03*
Y1161752D03*
Y1158406D03*
Y1171792D03*
Y1178485D03*
Y1168445D03*
Y1175138D03*
X1145259Y1191870D03*
X1150709Y1185177D03*
Y1181831D03*
Y1188524D03*
X1145259Y1201910D03*
X1146309Y1196890D03*
X1150709Y1208603D03*
Y1205256D03*
Y1198563D03*
Y1195217D03*
Y1215296D03*
Y1221988D03*
Y1211949D03*
Y1218642D03*
X1145259Y1238721D03*
X1146309Y1233701D03*
X1145259Y1228681D03*
X1150709Y1225335D03*
Y1235374D03*
Y1232028D03*
Y1245414D03*
Y1252107D03*
Y1242067D03*
Y1248760D03*
X1168818Y756765D03*
Y760265D03*
X1159768Y756831D03*
Y760177D03*
X1164268Y776910D03*
X1168818Y767265D03*
Y763765D03*
X1159718Y763524D03*
X1164268Y783603D03*
X1169718Y790296D03*
X1164268Y780256D03*
Y786949D03*
X1159868Y795315D03*
X1164268Y807028D03*
X1169718Y800335D03*
X1164268Y803681D03*
Y793642D03*
Y796988D03*
Y820414D03*
Y813721D03*
Y817067D03*
Y810374D03*
X1159868Y832126D03*
X1169718Y837146D03*
Y827107D03*
X1164268Y823760D03*
Y830453D03*
Y833799D03*
Y850532D03*
Y843839D03*
Y840492D03*
Y847185D03*
Y857225D03*
X1169718Y863918D03*
X1164268Y853878D03*
Y860571D03*
X1159868Y868937D03*
X1164268Y880650D03*
X1169718Y873957D03*
X1164268Y877303D03*
Y867264D03*
Y870610D03*
Y887343D03*
Y894036D03*
Y883996D03*
Y890689D03*
X1159868Y905749D03*
X1169718Y900729D03*
Y910768D03*
X1164268Y897382D03*
Y904075D03*
Y907422D03*
Y917461D03*
Y924154D03*
Y914114D03*
Y920807D03*
X1169718Y937540D03*
X1164268Y930847D03*
Y927500D03*
Y934193D03*
Y940886D03*
X1159868Y942560D03*
X1169718Y947579D03*
X1164268Y954272D03*
Y950925D03*
Y944233D03*
Y960965D03*
Y967658D03*
Y964311D03*
Y957618D03*
Y971004D03*
Y974351D03*
Y981044D03*
Y977697D03*
Y984390D03*
Y987736D03*
Y994429D03*
Y1001122D03*
Y997776D03*
Y991083D03*
Y1004469D03*
Y1034587D03*
Y1041280D03*
Y1031240D03*
Y1037933D03*
Y1044626D03*
Y1047973D03*
Y1054666D03*
Y1058012D03*
Y1051319D03*
Y1061359D03*
Y1071398D03*
Y1074744D03*
Y1068051D03*
Y1064705D03*
X1159868Y1089804D03*
X1169718Y1084784D03*
X1164268Y1078091D03*
Y1081437D03*
Y1088130D03*
X1169718Y1094823D03*
X1164268Y1101516D03*
Y1098170D03*
Y1104862D03*
Y1091477D03*
Y1108209D03*
Y1114902D03*
Y1111555D03*
Y1118248D03*
X1159868Y1126615D03*
X1169718Y1121595D03*
Y1131634D03*
X1164268Y1134981D03*
Y1124941D03*
Y1128288D03*
Y1138327D03*
Y1145020D03*
Y1148366D03*
Y1141674D03*
X1159868Y1163426D03*
X1169718Y1158406D03*
X1164268Y1151713D03*
Y1155059D03*
Y1161752D03*
Y1165099D03*
X1169718Y1168445D03*
X1164268Y1175138D03*
Y1171792D03*
Y1178485D03*
Y1181831D03*
Y1188524D03*
Y1185177D03*
Y1191870D03*
X1159868Y1200237D03*
X1169718Y1205256D03*
Y1195217D03*
X1164268Y1208603D03*
Y1198563D03*
Y1201910D03*
Y1211949D03*
Y1218642D03*
Y1215296D03*
Y1221988D03*
X1159868Y1237048D03*
X1169718Y1232028D03*
X1164268Y1225335D03*
Y1228681D03*
Y1235374D03*
Y1238721D03*
X1169718Y1242067D03*
X1164268Y1248760D03*
Y1245414D03*
Y1252107D03*
Y1255453D03*
X1175860Y756765D03*
X1184910Y756831D03*
X1180410Y773563D03*
X1175860Y763765D03*
X1180410Y776910D03*
X1184910Y763524D03*
X1184960Y770217D03*
X1176010Y791969D03*
X1180410Y780256D03*
X1174960Y786949D03*
X1180410Y783603D03*
Y790296D03*
Y803681D03*
X1174960Y796988D03*
X1180410Y800335D03*
Y807028D03*
Y793642D03*
Y817067D03*
Y810374D03*
Y813721D03*
Y820414D03*
X1176010Y828780D03*
X1174960Y833799D03*
Y823760D03*
X1180410Y837146D03*
Y830453D03*
Y827107D03*
Y847185D03*
Y840492D03*
Y843839D03*
Y850532D03*
X1176010Y865591D03*
X1180410Y853878D03*
X1174960Y860571D03*
X1180410Y857225D03*
Y863918D03*
Y877303D03*
X1174960Y870610D03*
X1180410Y873957D03*
Y880650D03*
Y867264D03*
Y890689D03*
Y883996D03*
Y887343D03*
Y894036D03*
X1176010Y902402D03*
X1174960Y897382D03*
Y907422D03*
X1180410Y910768D03*
Y904075D03*
Y900729D03*
Y914114D03*
Y920807D03*
Y924154D03*
Y917461D03*
X1176010Y939213D03*
X1174960Y934193D03*
X1180410Y927500D03*
Y930847D03*
Y940886D03*
Y937540D03*
X1174960Y944233D03*
X1180410Y950925D03*
Y947579D03*
Y954272D03*
Y957618D03*
Y964311D03*
Y971004D03*
Y960965D03*
Y967658D03*
Y977697D03*
Y984390D03*
Y974351D03*
Y981044D03*
Y991083D03*
Y997776D03*
Y987736D03*
Y994429D03*
Y1001122D03*
Y1004469D03*
Y1027894D03*
Y1031240D03*
Y1037933D03*
Y1044626D03*
Y1034587D03*
Y1041280D03*
Y1051319D03*
Y1058012D03*
Y1047973D03*
Y1054666D03*
Y1068051D03*
Y1074744D03*
Y1061359D03*
Y1071398D03*
Y1064705D03*
X1176010Y1086457D03*
X1174960Y1081437D03*
X1180410Y1078091D03*
Y1088130D03*
Y1084784D03*
X1174960Y1091477D03*
X1180410Y1098170D03*
Y1104862D03*
Y1094823D03*
Y1101516D03*
X1174960Y1118248D03*
X1180410Y1111555D03*
Y1108209D03*
Y1114902D03*
X1176010Y1123268D03*
X1174960Y1128288D03*
X1180410Y1134981D03*
Y1131634D03*
Y1124941D03*
Y1121595D03*
Y1141674D03*
Y1148366D03*
Y1138327D03*
Y1145020D03*
X1176010Y1160079D03*
X1174960Y1155059D03*
Y1165099D03*
X1180410Y1151713D03*
Y1161752D03*
Y1158406D03*
Y1171792D03*
Y1178485D03*
Y1168445D03*
Y1175138D03*
X1174960Y1191870D03*
X1180410Y1185177D03*
Y1181831D03*
Y1188524D03*
X1176010Y1196890D03*
X1174960Y1201910D03*
X1180410Y1208603D03*
Y1205256D03*
Y1198563D03*
Y1195217D03*
Y1215296D03*
Y1221988D03*
Y1211949D03*
Y1218642D03*
X1176010Y1233701D03*
X1174960Y1238721D03*
Y1228681D03*
X1180410Y1225335D03*
Y1235374D03*
Y1232028D03*
Y1245414D03*
Y1252107D03*
Y1242067D03*
Y1248760D03*
X1198519Y756765D03*
Y760265D03*
X1189469Y760177D03*
Y756831D03*
X1193969Y776910D03*
X1198519Y767265D03*
Y763765D03*
X1188805Y766870D03*
X1189419Y763524D03*
X1193969Y783603D03*
X1199419Y790296D03*
X1189569Y795315D03*
X1193969Y807028D03*
X1199419Y800335D03*
X1193969Y820414D03*
Y813721D03*
X1189569Y832126D03*
X1199419Y837146D03*
Y827107D03*
X1193969Y850532D03*
Y843839D03*
Y857225D03*
X1199419Y863918D03*
X1189569Y868937D03*
X1193969Y880650D03*
X1199419Y873957D03*
X1193969Y887343D03*
Y894036D03*
X1189569Y905749D03*
X1199419Y900729D03*
Y910768D03*
X1193969Y917461D03*
Y924154D03*
X1199419Y937540D03*
X1193969Y930847D03*
Y954272D03*
X1189569Y942560D03*
X1199419Y947579D03*
X1193969Y960965D03*
Y967658D03*
Y974351D03*
Y981044D03*
Y987736D03*
Y994429D03*
Y1004469D03*
Y1034587D03*
Y1041280D03*
Y1047973D03*
Y1054666D03*
Y1061359D03*
Y1071398D03*
X1189569Y1089804D03*
X1199419Y1084784D03*
X1193969Y1078091D03*
X1199419Y1094823D03*
X1193969Y1101516D03*
Y1108209D03*
Y1114902D03*
X1189569Y1126615D03*
X1199419Y1121595D03*
Y1131634D03*
X1193969Y1138327D03*
Y1145020D03*
X1189569Y1163426D03*
X1199419Y1158406D03*
X1193969Y1151713D03*
X1199419Y1168445D03*
X1193969Y1175138D03*
Y1181831D03*
Y1188524D03*
X1189569Y1200237D03*
X1199419Y1195217D03*
Y1205256D03*
X1193969Y1211949D03*
Y1218642D03*
X1189569Y1237048D03*
X1193969Y1225335D03*
X1199419Y1232028D03*
X1193969Y1248760D03*
X1199419Y1242067D03*
X1193969Y1255453D03*
X1205561Y756765D03*
X1214600Y759562D03*
X1210111Y773563D03*
X1205561Y763765D03*
X1205448Y769914D03*
X1214661Y766870D03*
X1214611Y763524D03*
X1214841Y772277D03*
X1205711Y791969D03*
X1210111Y780256D03*
X1204661Y786949D03*
X1210111Y803681D03*
X1204661Y796988D03*
X1210111Y817067D03*
Y810374D03*
X1205711Y828780D03*
X1204661Y833799D03*
Y823760D03*
X1210111Y847185D03*
Y840492D03*
X1205711Y865591D03*
X1210111Y853878D03*
X1204661Y860571D03*
X1210111Y877303D03*
X1204661Y870610D03*
X1210111Y890689D03*
Y883996D03*
X1205711Y902402D03*
X1204661Y897382D03*
Y907422D03*
X1210111Y914114D03*
Y920807D03*
X1205711Y939213D03*
X1204661Y934193D03*
X1210111Y927500D03*
X1204661Y944233D03*
X1210111Y950925D03*
Y957618D03*
Y964311D03*
Y971004D03*
Y960965D03*
X1203682D03*
X1210111Y977697D03*
Y984390D03*
Y991083D03*
Y997776D03*
Y1004469D03*
Y1031240D03*
Y1037933D03*
Y1044626D03*
Y1051319D03*
Y1058012D03*
Y1068051D03*
Y1074744D03*
X1205711Y1086457D03*
X1204661Y1081437D03*
Y1091477D03*
X1210111Y1098170D03*
Y1104862D03*
X1204661Y1118248D03*
X1210111Y1111555D03*
X1205711Y1123268D03*
X1204661Y1128288D03*
X1210111Y1134981D03*
Y1141674D03*
Y1148366D03*
X1205711Y1160079D03*
X1204661Y1155059D03*
Y1165099D03*
X1210111Y1171792D03*
Y1178485D03*
X1204661Y1191870D03*
X1210111Y1185177D03*
X1205711Y1196890D03*
X1204661Y1201910D03*
X1210111Y1208603D03*
Y1215296D03*
Y1221988D03*
X1205711Y1233701D03*
X1204661Y1228681D03*
Y1238721D03*
X1210111Y1245414D03*
Y1252107D03*
X1362523Y1015473D03*
Y1022559D03*
Y1019016D03*
X1366123Y1015473D03*
X1373603D03*
X1377483D03*
X1370003D03*
X1373603Y1019016D03*
Y1022559D03*
X1366123D03*
Y1019016D03*
X1377483Y1022559D03*
Y1019016D03*
X1370003Y1022559D03*
Y1019016D03*
X1381083Y1015473D03*
X1391460Y1009764D03*
Y1006024D03*
Y1013504D03*
X1381083Y1022559D03*
Y1019016D03*
X1391460Y1020985D03*
Y1024725D03*
Y1028465D03*
Y1017244D03*
Y1032205D03*
X1395060Y1009764D03*
Y1006024D03*
X1403693Y1009399D03*
X1407433D03*
X1399953D03*
X1395060Y1013504D03*
X1404615Y1014744D03*
X1401015D03*
X1399953Y1005799D03*
X1403693D03*
X1407433D03*
X1399953Y1028830D03*
X1407433D03*
X1404615Y1023012D03*
X1395060Y1020985D03*
Y1024725D03*
Y1028465D03*
Y1017244D03*
X1404615Y1018878D03*
X1403693Y1028830D03*
X1401015Y1023012D03*
Y1018878D03*
X1407433Y1032430D03*
X1403693D03*
X1395060Y1032205D03*
X1399953Y1032430D03*
X1416301Y966740D03*
Y970340D03*
Y981740D03*
Y974240D03*
Y977840D03*
Y985340D03*
X1418101Y997765D03*
Y993765D03*
X1418176Y989765D03*
X1414576D03*
X1414501Y993765D03*
Y997765D03*
X1418653Y1009399D03*
X1418101Y1001765D03*
X1422394Y1009399D03*
X1414913D03*
X1411173D03*
X1423316Y1014744D03*
X1414458D03*
X1410858D03*
X1418653Y1005799D03*
X1414913D03*
X1411173D03*
X1414501Y1001765D03*
X1419716Y1014744D03*
X1422394Y1005799D03*
X1414458Y1023012D03*
X1418653Y1028830D03*
X1411173D03*
X1414913D03*
X1423316Y1023012D03*
Y1018878D03*
X1422394Y1028830D03*
X1414458Y1018878D03*
X1410858Y1023012D03*
X1419716D03*
X1410858Y1018878D03*
X1419716D03*
X1415426Y1042765D03*
Y1038765D03*
X1422394Y1032430D03*
X1419026Y1038765D03*
Y1042765D03*
X1414913Y1032430D03*
X1418653D03*
X1411173D03*
X1417301Y1055140D03*
Y1051540D03*
X1438507Y1006024D03*
X1433614Y1009399D03*
X1426134D03*
X1429874D03*
X1438507Y1009764D03*
Y1013504D03*
X1433552Y1014744D03*
X1429952D03*
X1433614Y1005799D03*
X1426134D03*
X1429874D03*
X1438507Y1024725D03*
Y1020985D03*
X1429874Y1028830D03*
X1438507Y1017244D03*
X1433552Y1018878D03*
X1438507Y1028465D03*
X1433552Y1023012D03*
X1426134Y1028830D03*
X1433614D03*
X1429952Y1023012D03*
Y1018878D03*
X1438507Y1032205D03*
X1426134Y1032430D03*
X1433614D03*
X1429874D03*
X1453345Y1015473D03*
X1442107Y1013504D03*
Y1009764D03*
Y1006024D03*
X1453345Y1019016D03*
Y1022559D03*
X1442107Y1020985D03*
Y1024725D03*
Y1028465D03*
Y1017244D03*
Y1032205D03*
X1460926Y1015473D03*
X1467926D03*
X1456945D03*
X1464526D03*
X1460926Y1019016D03*
Y1022559D03*
X1467926Y1019016D03*
Y1022559D03*
X1456945Y1019016D03*
Y1022559D03*
X1464526Y1019016D03*
Y1022559D03*
X1471526Y1015473D03*
Y1019016D03*
Y1022559D03*
X1628046Y756765D03*
Y760265D03*
X1618996Y760177D03*
Y756831D03*
X1628046Y767265D03*
X1623496Y776910D03*
X1618946Y763524D03*
X1628946Y790296D03*
X1623496Y783603D03*
X1627896Y795315D03*
X1628946Y800335D03*
X1623496Y807028D03*
Y813721D03*
Y820414D03*
X1627896Y832126D03*
X1628946Y827107D03*
Y837146D03*
X1623496Y843839D03*
Y850532D03*
X1628946Y863918D03*
X1623496Y857225D03*
X1627896Y868937D03*
X1628946Y873957D03*
X1623496Y880650D03*
Y887343D03*
Y894036D03*
X1627896Y905749D03*
X1628946Y900729D03*
Y910768D03*
X1623496Y917461D03*
Y924154D03*
X1628946Y937540D03*
X1623496Y930847D03*
X1627896Y942560D03*
X1628946Y947579D03*
X1623496Y954272D03*
Y960965D03*
Y967658D03*
Y974351D03*
Y981044D03*
Y987736D03*
Y994429D03*
Y1004469D03*
Y1034587D03*
Y1041280D03*
Y1047973D03*
Y1054666D03*
Y1061359D03*
Y1071398D03*
X1627896Y1089804D03*
X1628946Y1084784D03*
X1623496Y1078091D03*
X1628946Y1094823D03*
X1623496Y1101516D03*
Y1108209D03*
Y1114902D03*
X1627896Y1126615D03*
X1628946Y1121595D03*
Y1131634D03*
X1623496Y1138327D03*
Y1145020D03*
X1627896Y1163426D03*
X1628946Y1158406D03*
X1623496Y1151713D03*
X1628946Y1168445D03*
X1623496Y1175138D03*
Y1181831D03*
Y1188524D03*
X1627896Y1200237D03*
X1628946Y1195217D03*
Y1205256D03*
X1623496Y1211949D03*
Y1218642D03*
X1627896Y1237048D03*
X1628946Y1232028D03*
X1623496Y1225335D03*
X1628946Y1242067D03*
X1623496Y1248760D03*
Y1255453D03*
X1635088Y756765D03*
X1644138Y756831D03*
X1635088Y763765D03*
X1639638Y773563D03*
X1644138Y763524D03*
X1644188Y770217D03*
X1644038Y791969D03*
X1634188Y786949D03*
X1639638Y780256D03*
X1634188Y796988D03*
X1639638Y803681D03*
Y810374D03*
Y817067D03*
X1644038Y828780D03*
X1634188Y823760D03*
Y833799D03*
X1639638Y840492D03*
Y847185D03*
X1644038Y865591D03*
X1634188Y860571D03*
X1639638Y853878D03*
X1634188Y870610D03*
X1639638Y877303D03*
Y883996D03*
Y890689D03*
X1644038Y902402D03*
X1634188Y897382D03*
Y907422D03*
X1639638Y914114D03*
Y920807D03*
X1644038Y939213D03*
X1634188Y934193D03*
X1639638Y927500D03*
X1634188Y944233D03*
X1639638Y950925D03*
Y957618D03*
Y964311D03*
Y971004D03*
Y960965D03*
X1634138D03*
X1639638Y977697D03*
Y984390D03*
Y991083D03*
Y997776D03*
Y1004469D03*
Y1031240D03*
Y1037933D03*
Y1044626D03*
Y1051319D03*
Y1058012D03*
Y1068051D03*
Y1074744D03*
X1644038Y1086457D03*
X1634188Y1081437D03*
Y1091477D03*
X1639638Y1098170D03*
Y1104862D03*
X1634188Y1118248D03*
X1639638Y1111555D03*
X1644038Y1123268D03*
X1634188Y1128288D03*
X1639638Y1134981D03*
Y1141674D03*
Y1148366D03*
X1644038Y1160079D03*
X1634188Y1155059D03*
Y1165099D03*
X1639638Y1171792D03*
Y1178485D03*
X1634188Y1191870D03*
X1639638Y1185177D03*
X1644038Y1196890D03*
X1634188Y1201910D03*
X1639638Y1208603D03*
Y1215296D03*
Y1221988D03*
X1644038Y1233701D03*
X1634188Y1228681D03*
Y1238721D03*
X1639638Y1245414D03*
Y1252107D03*
X1657747Y756765D03*
Y760265D03*
X1648697Y760177D03*
Y756831D03*
X1657747Y767265D03*
X1653197Y776910D03*
X1657747Y763765D03*
X1648647Y766870D03*
Y763524D03*
X1658647Y790296D03*
X1653197Y783603D03*
Y780256D03*
Y786949D03*
X1657597Y795315D03*
X1658647Y800335D03*
X1653197Y807028D03*
Y803681D03*
Y793642D03*
Y796988D03*
Y813721D03*
Y820414D03*
Y817067D03*
Y810374D03*
X1657597Y832126D03*
X1658647Y827107D03*
Y837146D03*
X1653197Y823760D03*
Y830453D03*
Y833799D03*
Y843839D03*
Y850532D03*
Y840492D03*
Y847185D03*
X1658647Y863918D03*
X1653197Y857225D03*
Y853878D03*
Y860571D03*
X1657597Y868937D03*
X1658647Y873957D03*
X1653197Y880650D03*
Y877303D03*
Y867264D03*
Y870610D03*
Y887343D03*
Y894036D03*
Y883996D03*
Y890689D03*
X1657597Y905749D03*
X1658647Y900729D03*
Y910768D03*
X1653197Y897382D03*
Y904075D03*
Y907422D03*
Y917461D03*
Y924154D03*
Y914114D03*
Y920807D03*
X1658647Y937540D03*
X1653197Y930847D03*
Y927500D03*
Y934193D03*
Y940886D03*
X1657597Y942560D03*
X1658647Y947579D03*
X1653197Y954272D03*
Y950925D03*
Y944233D03*
Y960965D03*
Y967658D03*
Y964311D03*
Y957618D03*
Y971004D03*
Y974351D03*
Y981044D03*
Y977697D03*
Y984390D03*
Y987736D03*
Y994429D03*
Y1001122D03*
Y997776D03*
Y991083D03*
Y1004469D03*
Y1034587D03*
Y1041280D03*
Y1031240D03*
Y1037933D03*
Y1044626D03*
Y1047973D03*
Y1054666D03*
Y1058012D03*
Y1051319D03*
Y1061359D03*
Y1071398D03*
Y1074744D03*
Y1068051D03*
Y1064705D03*
X1657597Y1089804D03*
X1658647Y1084784D03*
X1653197Y1078091D03*
Y1081437D03*
Y1088130D03*
X1658647Y1094823D03*
X1653197Y1101516D03*
Y1098170D03*
Y1104862D03*
Y1091477D03*
Y1108209D03*
Y1114902D03*
Y1111555D03*
Y1118248D03*
X1657597Y1126615D03*
X1658647Y1121595D03*
Y1131634D03*
X1653197Y1134981D03*
Y1124941D03*
Y1128288D03*
Y1138327D03*
Y1145020D03*
Y1148366D03*
Y1141674D03*
X1657597Y1163426D03*
X1658647Y1158406D03*
X1653197Y1151713D03*
Y1155059D03*
Y1161752D03*
Y1165099D03*
X1658647Y1168445D03*
X1653197Y1175138D03*
Y1171792D03*
Y1178485D03*
Y1188524D03*
Y1181831D03*
Y1185177D03*
Y1191870D03*
X1657597Y1200237D03*
X1658647Y1205256D03*
Y1195217D03*
X1653197Y1208603D03*
Y1198563D03*
Y1201910D03*
Y1211949D03*
Y1218642D03*
Y1215296D03*
Y1221988D03*
X1657597Y1237048D03*
X1658647Y1232028D03*
X1653197Y1225335D03*
Y1228681D03*
Y1235374D03*
Y1238721D03*
Y1248760D03*
X1658647Y1242067D03*
X1653197Y1245414D03*
Y1252107D03*
Y1255453D03*
X1664789Y756765D03*
X1673839Y756831D03*
X1664789Y763765D03*
X1669339Y773563D03*
Y776910D03*
X1673839Y763524D03*
X1673889Y770217D03*
X1673739Y791969D03*
X1663889Y786949D03*
X1669339Y780256D03*
Y783603D03*
Y790296D03*
X1663889Y796988D03*
X1669339Y803681D03*
Y800335D03*
Y807028D03*
Y793642D03*
Y810374D03*
Y817067D03*
Y813721D03*
Y820414D03*
X1673739Y828780D03*
X1663889Y823760D03*
Y833799D03*
X1669339Y837146D03*
Y830453D03*
Y827107D03*
Y840492D03*
Y847185D03*
Y843839D03*
Y850532D03*
X1673739Y865591D03*
X1663889Y860571D03*
X1669339Y853878D03*
Y857225D03*
Y863918D03*
X1663889Y870610D03*
X1669339Y877303D03*
Y873957D03*
Y880650D03*
Y867264D03*
Y883996D03*
Y890689D03*
Y887343D03*
Y894036D03*
X1673739Y902402D03*
X1663889Y897382D03*
Y907422D03*
X1669339Y910768D03*
Y904075D03*
Y900729D03*
Y914114D03*
Y920807D03*
Y924154D03*
Y917461D03*
X1673739Y939213D03*
X1663889Y934193D03*
X1669339Y927500D03*
Y930847D03*
Y940886D03*
Y937540D03*
X1663889Y944233D03*
X1669339Y950925D03*
Y947579D03*
Y954272D03*
Y957618D03*
Y964311D03*
Y971004D03*
Y960965D03*
Y967658D03*
Y977697D03*
Y984390D03*
Y974351D03*
Y981044D03*
Y991083D03*
Y997776D03*
Y987736D03*
Y994429D03*
Y1001122D03*
Y1004469D03*
Y1027894D03*
Y1031240D03*
Y1037933D03*
Y1044626D03*
Y1034587D03*
Y1041280D03*
Y1051319D03*
Y1058012D03*
Y1047973D03*
Y1054666D03*
Y1068051D03*
Y1074744D03*
Y1061359D03*
Y1071398D03*
Y1064705D03*
X1673739Y1086457D03*
X1663889Y1081437D03*
X1669339Y1078091D03*
Y1088130D03*
Y1084784D03*
X1663889Y1091477D03*
X1669339Y1098170D03*
Y1104862D03*
Y1094823D03*
Y1101516D03*
X1663889Y1118248D03*
X1669339Y1111555D03*
Y1108209D03*
Y1114902D03*
X1673739Y1123268D03*
X1663889Y1128288D03*
X1669339Y1134981D03*
Y1131634D03*
Y1124941D03*
Y1121595D03*
Y1141674D03*
Y1148366D03*
Y1138327D03*
Y1145020D03*
X1673739Y1160079D03*
X1663889Y1155059D03*
Y1165099D03*
X1669339Y1151713D03*
Y1161752D03*
Y1158406D03*
Y1171792D03*
Y1178485D03*
Y1168445D03*
Y1175138D03*
X1663889Y1191870D03*
X1669339Y1185177D03*
Y1181831D03*
Y1188524D03*
X1673739Y1196890D03*
X1663889Y1201910D03*
X1669339Y1208603D03*
Y1205256D03*
Y1198563D03*
Y1195217D03*
Y1215296D03*
Y1221988D03*
Y1211949D03*
Y1218642D03*
X1673739Y1233701D03*
X1663889Y1228681D03*
Y1238721D03*
X1669339Y1225335D03*
Y1235374D03*
Y1232028D03*
Y1245414D03*
Y1252107D03*
Y1242067D03*
Y1248760D03*
X1687448Y756765D03*
Y760265D03*
X1678398Y760177D03*
Y756831D03*
X1682898Y776910D03*
X1687448Y767265D03*
Y763765D03*
X1678348Y766870D03*
Y763524D03*
X1682898Y783603D03*
X1688348Y790296D03*
X1682898Y780256D03*
Y786949D03*
X1687298Y795315D03*
X1688348Y800335D03*
X1682898Y807028D03*
Y803681D03*
Y793642D03*
Y796988D03*
Y820414D03*
Y813721D03*
Y817067D03*
Y810374D03*
X1688348Y827107D03*
X1687298Y832126D03*
X1688348Y837146D03*
X1682898Y823760D03*
Y830453D03*
Y833799D03*
Y850532D03*
Y843839D03*
Y840492D03*
Y847185D03*
X1688348Y863918D03*
X1682898Y857225D03*
Y853878D03*
Y860571D03*
X1687298Y868937D03*
X1688348Y873957D03*
X1682898Y880650D03*
Y877303D03*
Y867264D03*
Y870610D03*
Y894036D03*
Y887343D03*
Y883996D03*
Y890689D03*
X1687298Y905749D03*
X1688348Y910768D03*
Y900729D03*
X1682898Y897382D03*
Y904075D03*
Y907422D03*
Y917461D03*
Y924154D03*
Y914114D03*
Y920807D03*
Y930847D03*
X1688348Y937540D03*
X1682898Y927500D03*
Y934193D03*
Y940886D03*
X1687298Y942560D03*
X1688348Y947579D03*
X1682898Y954272D03*
Y950925D03*
Y944233D03*
Y967658D03*
Y960965D03*
Y964311D03*
Y957618D03*
Y971004D03*
Y981044D03*
Y974351D03*
Y977697D03*
Y984390D03*
Y994429D03*
Y987736D03*
Y1001122D03*
Y997776D03*
Y991083D03*
Y1004469D03*
Y1041280D03*
Y1034587D03*
Y1031240D03*
Y1037933D03*
Y1044626D03*
Y1054666D03*
Y1047973D03*
Y1058012D03*
Y1051319D03*
Y1061359D03*
Y1071398D03*
Y1074744D03*
Y1068051D03*
Y1064705D03*
Y1078091D03*
X1687298Y1089804D03*
X1688348Y1084784D03*
X1682898Y1081437D03*
Y1088130D03*
X1688348Y1094823D03*
X1682898Y1101516D03*
Y1098170D03*
Y1104862D03*
Y1091477D03*
Y1108209D03*
Y1114902D03*
Y1111555D03*
Y1118248D03*
X1688348Y1131634D03*
Y1121595D03*
X1687298Y1126615D03*
X1682898Y1134981D03*
Y1124941D03*
Y1128288D03*
Y1138327D03*
Y1145020D03*
Y1148366D03*
Y1141674D03*
X1688348Y1158406D03*
X1682898Y1151713D03*
X1687298Y1163426D03*
X1682898Y1155059D03*
Y1161752D03*
Y1165099D03*
X1688348Y1168445D03*
X1682898Y1175138D03*
Y1171792D03*
Y1178485D03*
Y1188524D03*
Y1181831D03*
Y1185177D03*
Y1191870D03*
X1688348Y1205256D03*
X1687298Y1200237D03*
X1688348Y1195217D03*
X1682898Y1208603D03*
Y1198563D03*
Y1201910D03*
Y1211949D03*
Y1218642D03*
Y1215296D03*
Y1221988D03*
Y1225335D03*
X1687298Y1237048D03*
X1688348Y1232028D03*
X1682898Y1228681D03*
Y1235374D03*
Y1238721D03*
Y1248760D03*
X1688348Y1242067D03*
X1682898Y1245414D03*
Y1252107D03*
Y1255453D03*
X1694490Y756765D03*
X1703540Y756831D03*
X1694490Y763765D03*
X1699040Y773563D03*
X1703590Y766870D03*
X1699040Y776910D03*
X1703540Y763524D03*
X1703590Y770217D03*
X1703440Y791969D03*
X1699040Y780256D03*
X1693590Y786949D03*
X1699040Y783603D03*
Y790296D03*
Y803681D03*
X1693590Y796988D03*
X1699040Y800335D03*
Y807028D03*
Y793642D03*
Y817067D03*
Y810374D03*
Y813721D03*
Y820414D03*
X1693590Y823760D03*
X1703440Y828780D03*
X1693590Y833799D03*
X1699040Y837146D03*
Y830453D03*
Y827107D03*
Y847185D03*
Y840492D03*
Y843839D03*
Y850532D03*
Y853878D03*
X1693590Y860571D03*
X1703440Y865591D03*
X1699040Y857225D03*
Y863918D03*
X1693590Y870610D03*
X1699040Y877303D03*
Y873957D03*
Y880650D03*
Y867264D03*
Y883996D03*
Y890689D03*
Y887343D03*
Y894036D03*
X1693590Y907422D03*
X1703440Y902402D03*
X1693590Y897382D03*
X1699040Y910768D03*
Y904075D03*
Y900729D03*
Y914114D03*
Y920807D03*
Y924154D03*
Y917461D03*
X1693590Y934193D03*
X1699040Y927500D03*
X1703440Y939213D03*
X1699040Y930847D03*
Y940886D03*
Y937540D03*
X1693590Y944233D03*
X1699040Y950925D03*
Y947579D03*
Y954272D03*
Y964311D03*
Y971004D03*
Y957618D03*
Y960965D03*
Y967658D03*
Y977697D03*
Y984390D03*
Y974351D03*
Y981044D03*
Y997776D03*
Y991083D03*
Y987736D03*
Y994429D03*
Y1001122D03*
Y1004469D03*
Y1027894D03*
Y1044626D03*
Y1037933D03*
Y1031240D03*
Y1034587D03*
Y1041280D03*
Y1058012D03*
Y1051319D03*
Y1047973D03*
Y1054666D03*
Y1074744D03*
Y1068051D03*
Y1061359D03*
Y1071398D03*
Y1064705D03*
X1703440Y1086457D03*
X1693590Y1081437D03*
X1699040Y1078091D03*
Y1088130D03*
Y1084784D03*
X1693590Y1091477D03*
X1699040Y1104862D03*
Y1098170D03*
Y1094823D03*
Y1101516D03*
Y1111555D03*
X1693590Y1118248D03*
X1699040Y1108209D03*
Y1114902D03*
Y1134981D03*
X1703440Y1123268D03*
X1693590Y1128288D03*
X1699040Y1131634D03*
Y1124941D03*
Y1121595D03*
Y1141674D03*
Y1148366D03*
Y1138327D03*
Y1145020D03*
X1693590Y1155059D03*
Y1165099D03*
X1703440Y1160079D03*
X1699040Y1151713D03*
Y1161752D03*
Y1158406D03*
Y1171792D03*
Y1178485D03*
Y1168445D03*
Y1175138D03*
X1693590Y1191870D03*
X1699040Y1185177D03*
Y1181831D03*
Y1188524D03*
X1693590Y1201910D03*
X1703440Y1196890D03*
X1699040Y1208603D03*
Y1205256D03*
Y1198563D03*
Y1195217D03*
Y1221988D03*
Y1215296D03*
Y1211949D03*
Y1218642D03*
X1693590Y1228681D03*
Y1238721D03*
X1703440Y1233701D03*
X1699040Y1225335D03*
Y1235374D03*
Y1232028D03*
Y1245414D03*
Y1252107D03*
Y1242067D03*
Y1248760D03*
X1717149Y756765D03*
Y760265D03*
X1708099Y760177D03*
Y756831D03*
X1712599Y776910D03*
X1717149Y767265D03*
Y763765D03*
X1708049Y763524D03*
X1718049Y790296D03*
X1712599Y783603D03*
Y780256D03*
Y786949D03*
Y807028D03*
X1716999Y795315D03*
X1718049Y800335D03*
X1712599Y803681D03*
Y793642D03*
Y796988D03*
Y820414D03*
Y813721D03*
Y817067D03*
Y810374D03*
X1718049Y827107D03*
X1716999Y832126D03*
X1718049Y837146D03*
X1712599Y823760D03*
Y830453D03*
Y833799D03*
Y850532D03*
Y843839D03*
Y840492D03*
Y847185D03*
X1718049Y863918D03*
X1712599Y857225D03*
Y853878D03*
Y860571D03*
X1716999Y868937D03*
X1712599Y880650D03*
X1718049Y873957D03*
X1712599Y877303D03*
Y867264D03*
Y870610D03*
Y894036D03*
Y887343D03*
Y883996D03*
Y890689D03*
X1716999Y905749D03*
X1718049Y910768D03*
Y900729D03*
X1712599Y897382D03*
Y904075D03*
Y907422D03*
Y917461D03*
Y924154D03*
Y914114D03*
Y920807D03*
Y930847D03*
X1718049Y937540D03*
X1712599Y927500D03*
Y934193D03*
Y940886D03*
X1716999Y942560D03*
X1718049Y947579D03*
X1712599Y954272D03*
Y950925D03*
Y944233D03*
Y967658D03*
Y960965D03*
Y964311D03*
Y957618D03*
Y971004D03*
Y981044D03*
Y974351D03*
Y977697D03*
Y984390D03*
Y994429D03*
Y987736D03*
Y1001122D03*
Y997776D03*
Y991083D03*
Y1004469D03*
Y1041280D03*
Y1034587D03*
Y1031240D03*
Y1037933D03*
Y1044626D03*
Y1054666D03*
Y1047973D03*
Y1058012D03*
Y1051319D03*
Y1061359D03*
Y1071398D03*
Y1074744D03*
Y1068051D03*
Y1064705D03*
Y1078091D03*
X1716999Y1089804D03*
X1718049Y1084784D03*
X1712599Y1081437D03*
Y1088130D03*
X1718049Y1094823D03*
X1712599Y1101516D03*
Y1098170D03*
Y1104862D03*
Y1091477D03*
Y1108209D03*
Y1114902D03*
Y1111555D03*
Y1118248D03*
X1718049Y1131634D03*
Y1121595D03*
X1716999Y1126615D03*
X1712599Y1134981D03*
Y1124941D03*
Y1128288D03*
Y1138327D03*
Y1145020D03*
Y1148366D03*
Y1141674D03*
X1718049Y1158406D03*
X1712599Y1151713D03*
X1716999Y1163426D03*
X1712599Y1155059D03*
Y1161752D03*
Y1165099D03*
X1718049Y1168445D03*
X1712599Y1175138D03*
Y1171792D03*
Y1178485D03*
Y1188524D03*
Y1181831D03*
Y1185177D03*
Y1191870D03*
X1718049Y1195217D03*
Y1205256D03*
X1716999Y1200237D03*
X1712599Y1208603D03*
Y1198563D03*
Y1201910D03*
Y1218642D03*
Y1211949D03*
Y1215296D03*
Y1221988D03*
Y1225335D03*
X1716999Y1237048D03*
X1718049Y1232028D03*
X1712599Y1228681D03*
Y1235374D03*
Y1238721D03*
Y1248760D03*
X1718049Y1242067D03*
X1712599Y1245414D03*
Y1252107D03*
Y1255453D03*
X1724191Y756765D03*
X1733241Y756831D03*
X1724191Y763765D03*
X1728741Y773563D03*
X1733727Y766870D03*
X1728741Y776910D03*
X1733241Y763524D03*
X1733291Y770217D03*
X1733141Y791969D03*
X1723291Y786949D03*
X1728741Y780256D03*
Y783603D03*
Y790296D03*
Y803681D03*
X1723291Y796988D03*
X1728741Y800335D03*
Y807028D03*
Y793642D03*
Y817067D03*
Y810374D03*
Y813721D03*
Y820414D03*
X1733141Y828780D03*
X1723291Y823760D03*
Y833799D03*
X1728741Y837146D03*
Y830453D03*
Y827107D03*
Y847185D03*
Y840492D03*
Y843839D03*
Y850532D03*
Y853878D03*
X1733141Y865591D03*
X1723291Y860571D03*
X1728741Y857225D03*
Y863918D03*
X1723291Y870610D03*
X1728741Y877303D03*
Y873957D03*
Y880650D03*
Y867264D03*
Y883996D03*
Y890689D03*
Y887343D03*
Y894036D03*
X1723291Y907422D03*
X1733141Y902402D03*
X1723291Y897382D03*
X1728741Y910768D03*
Y904075D03*
Y900729D03*
Y914114D03*
Y920807D03*
Y924154D03*
Y917461D03*
X1723291Y934193D03*
X1728741Y927500D03*
X1733141Y939213D03*
X1728741Y930847D03*
Y940886D03*
Y937540D03*
X1723291Y944233D03*
X1728741Y950925D03*
Y947579D03*
Y954272D03*
Y964311D03*
Y971004D03*
Y957618D03*
Y960965D03*
Y967658D03*
Y977697D03*
Y984390D03*
Y974351D03*
Y981044D03*
Y997776D03*
Y991083D03*
Y987736D03*
Y994429D03*
Y1001122D03*
Y1004469D03*
Y1027894D03*
Y1044626D03*
Y1037933D03*
Y1031240D03*
Y1034587D03*
Y1041280D03*
Y1058012D03*
Y1051319D03*
Y1047973D03*
Y1054666D03*
Y1074744D03*
Y1068051D03*
Y1061359D03*
Y1071398D03*
Y1064705D03*
X1733141Y1086457D03*
X1723291Y1081437D03*
X1728741Y1078091D03*
Y1088130D03*
Y1084784D03*
X1723291Y1091477D03*
X1728741Y1104862D03*
Y1098170D03*
Y1094823D03*
Y1101516D03*
Y1111555D03*
X1723291Y1118248D03*
X1728741Y1108209D03*
Y1114902D03*
Y1134981D03*
X1733141Y1123268D03*
X1723291Y1128288D03*
X1728741Y1131634D03*
Y1124941D03*
Y1121595D03*
Y1141674D03*
Y1148366D03*
Y1138327D03*
Y1145020D03*
X1723291Y1155059D03*
X1733141Y1160079D03*
X1723291Y1165099D03*
X1728741Y1151713D03*
Y1161752D03*
Y1158406D03*
Y1171792D03*
Y1178485D03*
Y1168445D03*
Y1175138D03*
X1723291Y1191870D03*
X1728741Y1185177D03*
Y1181831D03*
Y1188524D03*
X1723291Y1201910D03*
X1733141Y1196890D03*
X1728741Y1208603D03*
Y1205256D03*
Y1198563D03*
Y1195217D03*
Y1221988D03*
Y1215296D03*
Y1211949D03*
Y1218642D03*
X1733141Y1233701D03*
X1723291Y1228681D03*
Y1238721D03*
X1728741Y1225335D03*
Y1235374D03*
Y1232028D03*
Y1245414D03*
Y1252107D03*
Y1242067D03*
Y1248760D03*
X1746850Y756765D03*
Y760265D03*
X1737800Y756831D03*
Y760177D03*
X1742300Y776910D03*
X1746850Y767265D03*
Y763765D03*
X1737750Y763524D03*
X1742300Y783603D03*
X1747750Y790296D03*
X1742300Y780256D03*
Y786949D03*
X1746700Y795315D03*
X1747750Y800335D03*
X1742300Y807028D03*
Y803681D03*
Y793642D03*
Y796988D03*
Y820414D03*
Y813721D03*
Y817067D03*
Y810374D03*
X1747750Y827107D03*
X1746700Y832126D03*
X1747750Y837146D03*
X1742300Y823760D03*
Y830453D03*
Y833799D03*
Y850532D03*
Y843839D03*
Y840492D03*
Y847185D03*
X1747750Y863918D03*
X1742300Y857225D03*
Y853878D03*
Y860571D03*
X1746700Y868937D03*
X1747750Y873957D03*
X1742300Y880650D03*
Y877303D03*
Y867264D03*
Y870610D03*
Y894036D03*
Y887343D03*
Y883996D03*
Y890689D03*
X1746700Y905749D03*
X1747750Y910768D03*
Y900729D03*
X1742300Y897382D03*
Y904075D03*
Y907422D03*
Y917461D03*
Y924154D03*
Y914114D03*
Y920807D03*
Y930847D03*
X1747750Y937540D03*
X1742300Y927500D03*
Y934193D03*
Y940886D03*
X1746700Y942560D03*
X1747750Y947579D03*
X1742300Y954272D03*
Y950925D03*
Y944233D03*
Y960965D03*
Y967658D03*
Y964311D03*
Y957618D03*
Y971004D03*
Y981044D03*
Y974351D03*
Y977697D03*
Y984390D03*
Y994429D03*
Y987736D03*
Y1001122D03*
Y997776D03*
Y991083D03*
Y1004469D03*
Y1041280D03*
Y1034587D03*
Y1031240D03*
Y1037933D03*
Y1044626D03*
Y1054666D03*
Y1047973D03*
Y1058012D03*
Y1051319D03*
Y1061359D03*
Y1071398D03*
Y1074744D03*
Y1068051D03*
Y1064705D03*
Y1078091D03*
X1746700Y1089804D03*
X1747750Y1084784D03*
X1742300Y1081437D03*
Y1088130D03*
X1747750Y1094823D03*
X1742300Y1101516D03*
Y1098170D03*
Y1104862D03*
Y1091477D03*
Y1108209D03*
Y1114902D03*
Y1111555D03*
Y1118248D03*
X1747750Y1131634D03*
Y1121595D03*
X1746700Y1126615D03*
X1742300Y1134981D03*
Y1124941D03*
Y1128288D03*
Y1138327D03*
Y1145020D03*
Y1148366D03*
Y1141674D03*
X1747750Y1158406D03*
X1742300Y1151713D03*
X1746700Y1163426D03*
X1742300Y1155059D03*
Y1161752D03*
Y1165099D03*
X1747750Y1168445D03*
X1742300Y1175138D03*
Y1171792D03*
Y1178485D03*
Y1188524D03*
Y1181831D03*
Y1185177D03*
Y1191870D03*
X1747750Y1205256D03*
X1746700Y1200237D03*
X1747750Y1195217D03*
X1742300Y1208603D03*
Y1198563D03*
Y1201910D03*
Y1218642D03*
Y1211949D03*
Y1215296D03*
Y1221988D03*
Y1225335D03*
X1746700Y1237048D03*
X1747750Y1232028D03*
X1742300Y1228681D03*
Y1235374D03*
Y1238721D03*
Y1248760D03*
X1747750Y1242067D03*
X1742300Y1245414D03*
Y1252107D03*
Y1255453D03*
X1753892Y756765D03*
X1762942Y756831D03*
X1753892Y763765D03*
X1758442Y773563D03*
X1762992Y766870D03*
X1758442Y776910D03*
X1762942Y763524D03*
X1762992Y770217D03*
X1762842Y791969D03*
X1752992Y786949D03*
X1758442Y780256D03*
Y783603D03*
Y790296D03*
Y803681D03*
X1752992Y796988D03*
X1758442Y800335D03*
Y807028D03*
Y793642D03*
Y817067D03*
Y810374D03*
Y813721D03*
Y820414D03*
X1752992Y823760D03*
Y833799D03*
X1762842Y828780D03*
X1758442Y837146D03*
Y830453D03*
Y827107D03*
Y847185D03*
Y840492D03*
Y843839D03*
Y850532D03*
X1752992Y860571D03*
X1758442Y853878D03*
X1762842Y865591D03*
X1758442Y857225D03*
Y863918D03*
X1752992Y870610D03*
X1758442Y877303D03*
Y873957D03*
Y880650D03*
Y867264D03*
Y883996D03*
Y890689D03*
Y887343D03*
Y894036D03*
X1752992Y907422D03*
Y897382D03*
X1762842Y902402D03*
X1758442Y910768D03*
Y904075D03*
Y900729D03*
Y914114D03*
Y920807D03*
Y924154D03*
Y917461D03*
X1752992Y934193D03*
X1758442Y927500D03*
X1762842Y939213D03*
X1758442Y930847D03*
Y940886D03*
Y937540D03*
X1752992Y944233D03*
X1758442Y950925D03*
Y947579D03*
Y954272D03*
Y964311D03*
Y971004D03*
Y957618D03*
Y960965D03*
Y967658D03*
Y977697D03*
Y984390D03*
Y974351D03*
Y981044D03*
Y997776D03*
Y991083D03*
Y987736D03*
Y994429D03*
Y1001122D03*
Y1004469D03*
Y1027894D03*
Y1044626D03*
Y1037933D03*
Y1031240D03*
Y1034587D03*
Y1041280D03*
Y1058012D03*
Y1051319D03*
Y1047973D03*
Y1054666D03*
Y1074744D03*
Y1068051D03*
Y1061359D03*
Y1071398D03*
Y1064705D03*
X1752992Y1081437D03*
X1762842Y1086457D03*
X1758442Y1078091D03*
Y1088130D03*
Y1084784D03*
X1752992Y1091477D03*
X1758442Y1104862D03*
Y1098170D03*
Y1094823D03*
Y1101516D03*
X1752992Y1118248D03*
X1758442Y1111555D03*
Y1108209D03*
Y1114902D03*
Y1134981D03*
X1752992Y1128288D03*
X1762842Y1123268D03*
X1758442Y1131634D03*
Y1124941D03*
Y1121595D03*
Y1141674D03*
Y1148366D03*
Y1138327D03*
Y1145020D03*
X1752992Y1155059D03*
Y1165099D03*
X1762842Y1160079D03*
X1758442Y1151713D03*
Y1161752D03*
Y1158406D03*
Y1171792D03*
Y1178485D03*
Y1168445D03*
Y1175138D03*
X1752992Y1191870D03*
X1758442Y1185177D03*
Y1181831D03*
Y1188524D03*
X1752992Y1201910D03*
X1762842Y1196890D03*
X1758442Y1208603D03*
Y1205256D03*
Y1198563D03*
Y1195217D03*
Y1221988D03*
Y1215296D03*
Y1211949D03*
Y1218642D03*
X1752992Y1228681D03*
Y1238721D03*
X1762842Y1233701D03*
X1758442Y1225335D03*
Y1235374D03*
Y1232028D03*
Y1245414D03*
Y1252107D03*
Y1242067D03*
Y1248760D03*
X1776550Y756765D03*
Y760265D03*
X1767500Y760177D03*
Y756831D03*
X1772000Y776910D03*
X1776550Y767265D03*
X1767450Y763524D03*
X1777450Y790296D03*
X1772000Y783603D03*
Y780256D03*
Y786949D03*
Y807028D03*
X1776400Y795315D03*
X1777450Y800335D03*
X1772000Y803681D03*
Y793642D03*
Y796988D03*
Y813721D03*
Y820414D03*
Y817067D03*
Y810374D03*
X1777450Y827107D03*
X1776400Y832126D03*
X1777450Y837146D03*
X1772000Y823760D03*
Y830453D03*
Y833799D03*
Y850532D03*
Y843839D03*
Y840492D03*
Y847185D03*
Y857225D03*
X1777450Y863918D03*
X1772000Y853878D03*
Y860571D03*
X1776400Y868937D03*
X1772000Y880650D03*
X1777450Y873957D03*
X1772000Y877303D03*
Y867264D03*
Y870610D03*
Y894036D03*
Y887343D03*
Y883996D03*
Y890689D03*
X1776400Y905749D03*
X1777450Y910768D03*
Y900729D03*
X1772000Y897382D03*
Y904075D03*
Y907422D03*
Y917461D03*
Y924154D03*
Y914114D03*
Y920807D03*
Y930847D03*
X1777450Y937540D03*
X1772000Y927500D03*
Y934193D03*
Y940886D03*
X1776400Y942560D03*
X1777450Y947579D03*
X1772000Y954272D03*
Y950925D03*
Y944233D03*
Y967658D03*
Y960965D03*
Y964311D03*
Y957618D03*
Y971004D03*
Y981044D03*
Y974351D03*
Y977697D03*
Y984390D03*
Y994429D03*
Y987736D03*
Y1001122D03*
Y997776D03*
Y991083D03*
Y1004469D03*
Y1041280D03*
Y1034587D03*
Y1031240D03*
Y1037933D03*
Y1044626D03*
Y1047973D03*
Y1054666D03*
Y1058012D03*
Y1051319D03*
Y1061359D03*
Y1071398D03*
Y1074744D03*
Y1068051D03*
Y1064705D03*
Y1078091D03*
X1776400Y1089804D03*
X1777450Y1084784D03*
X1772000Y1081437D03*
Y1088130D03*
X1777450Y1094823D03*
X1772000Y1101516D03*
Y1098170D03*
Y1104862D03*
Y1091477D03*
Y1108209D03*
Y1114902D03*
Y1111555D03*
Y1118248D03*
X1777450Y1131634D03*
Y1121595D03*
X1776400Y1126615D03*
X1772000Y1134981D03*
Y1124941D03*
Y1128288D03*
Y1138327D03*
Y1145020D03*
Y1148366D03*
Y1141674D03*
Y1151713D03*
X1777450Y1158406D03*
X1776400Y1163426D03*
X1772000Y1155059D03*
Y1161752D03*
Y1165099D03*
X1777450Y1168445D03*
X1772000Y1175138D03*
Y1171792D03*
Y1178485D03*
Y1188524D03*
Y1181831D03*
Y1185177D03*
Y1191870D03*
X1777450Y1205256D03*
X1776400Y1200237D03*
X1777450Y1195217D03*
X1772000Y1208603D03*
Y1198563D03*
Y1201910D03*
Y1218642D03*
Y1211949D03*
Y1215296D03*
Y1221988D03*
Y1225335D03*
X1776400Y1237048D03*
X1777450Y1232028D03*
X1772000Y1228681D03*
Y1235374D03*
Y1238721D03*
Y1248760D03*
X1777450Y1242067D03*
X1772000Y1245414D03*
Y1252107D03*
Y1255453D03*
X1783592Y756765D03*
X1792642Y756831D03*
X1783592Y763765D03*
X1788142Y773563D03*
Y776910D03*
X1792642Y763524D03*
X1792692Y770217D03*
X1792542Y791969D03*
X1782692Y786949D03*
X1788142Y780256D03*
Y783603D03*
Y790296D03*
X1782692Y796988D03*
X1788142Y803681D03*
Y800335D03*
Y807028D03*
Y793642D03*
Y817067D03*
Y810374D03*
Y813721D03*
Y820414D03*
X1782692Y823760D03*
Y833799D03*
X1792542Y828780D03*
X1788142Y837146D03*
Y830453D03*
Y827107D03*
Y847185D03*
Y840492D03*
Y843839D03*
Y850532D03*
Y853878D03*
X1792542Y865591D03*
X1782692Y860571D03*
X1788142Y857225D03*
Y863918D03*
X1782692Y870610D03*
X1788142Y877303D03*
Y873957D03*
Y880650D03*
Y867264D03*
Y883996D03*
Y890689D03*
Y887343D03*
Y894036D03*
X1782692Y907422D03*
Y897382D03*
X1792542Y902402D03*
X1788142Y910768D03*
Y904075D03*
Y900729D03*
Y914114D03*
Y920807D03*
Y924154D03*
Y917461D03*
X1782692Y934193D03*
X1788142Y927500D03*
X1792542Y939213D03*
X1788142Y930847D03*
Y940886D03*
Y937540D03*
X1782692Y944233D03*
X1788142Y950925D03*
Y947579D03*
Y954272D03*
Y964311D03*
Y971004D03*
Y957618D03*
Y960965D03*
Y967658D03*
Y977697D03*
Y984390D03*
Y974351D03*
Y981044D03*
Y997776D03*
Y991083D03*
Y987736D03*
Y994429D03*
Y1001122D03*
Y1004469D03*
Y1027894D03*
Y1044626D03*
Y1037933D03*
Y1031240D03*
Y1034587D03*
Y1041280D03*
Y1058012D03*
Y1051319D03*
Y1047973D03*
Y1054666D03*
Y1074744D03*
Y1068051D03*
Y1061359D03*
Y1071398D03*
Y1064705D03*
X1782692Y1081437D03*
X1792542Y1086457D03*
X1788142Y1078091D03*
Y1088130D03*
Y1084784D03*
X1782692Y1091477D03*
X1788142Y1098170D03*
Y1104862D03*
Y1094823D03*
Y1101516D03*
X1782692Y1118248D03*
X1788142Y1111555D03*
Y1108209D03*
Y1114902D03*
Y1134981D03*
X1782692Y1128288D03*
X1792542Y1123268D03*
X1788142Y1131634D03*
Y1124941D03*
Y1121595D03*
Y1141674D03*
Y1148366D03*
Y1138327D03*
Y1145020D03*
X1782692Y1155059D03*
Y1165099D03*
X1792542Y1160079D03*
X1788142Y1151713D03*
Y1161752D03*
Y1158406D03*
Y1171792D03*
Y1178485D03*
Y1168445D03*
Y1175138D03*
X1782692Y1191870D03*
X1788142Y1185177D03*
Y1181831D03*
Y1188524D03*
X1782692Y1201910D03*
X1792542Y1196890D03*
X1788142Y1208603D03*
Y1205256D03*
Y1198563D03*
Y1195217D03*
Y1221988D03*
Y1215296D03*
Y1211949D03*
Y1218642D03*
X1782692Y1228681D03*
Y1238721D03*
X1792542Y1233701D03*
X1788142Y1225335D03*
Y1235374D03*
Y1232028D03*
Y1245414D03*
Y1252107D03*
Y1242067D03*
Y1248760D03*
G54D57*
G01X14092Y290137D02*
X17292D01*
G01X39173Y197224D02*
X45323D01*
X45340Y197241D01*
X45406D01*
X45423Y197224D01*
G01X39173Y202224D02*
X45323D01*
X45340Y202241D01*
X45406D01*
X45423Y202224D01*
G01X39173Y207224D02*
X45323D01*
X45340Y207241D01*
X45406D01*
X45423Y207224D01*
G01X39173Y212224D02*
X45323D01*
X45340Y212241D01*
X45406D01*
X45423Y212224D01*
G01X44692Y290137D02*
X47892D01*
G01X50631Y1533246D02*
X49234D01*
X48383Y1532395D01*
G01X50133Y1595321D02*
Y1592481D01*
G01X45633Y1595321D02*
Y1592481D01*
G01X51133Y1636471D02*
Y1640796D01*
X51333Y1640996D01*
G01X46133Y1636471D02*
X51133D01*
G01X41427Y1668587D02*
X44352D01*
G01Y1663587D02*
Y1668587D01*
G01X64442Y507540D02*
Y510667D01*
G01X69323Y756832D02*
X64823D01*
G01X69323Y760178D02*
X64823D01*
G01X74179Y161191D02*
X71782D01*
X71779Y161194D01*
G01X74179Y157191D02*
X71782D01*
X71779Y157194D01*
G01X74179Y165191D02*
X71782D01*
X71779Y165194D01*
G01X85465Y786950D02*
X80015D01*
G01X69323Y790297D02*
X74773D01*
G01X85465Y796989D02*
X80015D01*
G01X69323Y800336D02*
X74773D01*
G01X85465Y823761D02*
X80015D01*
G01X85465Y833800D02*
X80015D01*
G01X69323Y827108D02*
X74773D01*
G01X69323Y837147D02*
X74773D01*
G01X85465Y860572D02*
X80015D01*
G01X69323Y863919D02*
X74773D01*
G01X85465Y870611D02*
X80015D01*
G01X69323Y873958D02*
X74773D01*
G01X85465Y897383D02*
X80015D01*
G01X69323Y900730D02*
X74773D01*
G01X85465Y907423D02*
X80015D01*
G01X69323Y910769D02*
X74773D01*
G01X85465Y934194D02*
X80015D01*
G01X69323Y937541D02*
X74773D01*
G01X85465Y944234D02*
X80015D01*
G01X69323Y947580D02*
X74773D01*
G01X85465Y1081438D02*
X80015D01*
G01X69323Y1084785D02*
X74773D01*
G01X85465Y1091478D02*
X80015D01*
G01X69323Y1094824D02*
X74773D01*
G01X85465Y1118249D02*
X80015D01*
G01X85465Y1128289D02*
X80015D01*
G01X69323Y1121596D02*
X74773D01*
G01X69323Y1131635D02*
X74773D01*
G01X85465Y1155060D02*
X80015D01*
G01X69323Y1158407D02*
X74773D01*
G01X85465Y1165100D02*
X80015D01*
G01X69323Y1168446D02*
X74773D01*
G01X85465Y1191871D02*
X80015D01*
G01X69323Y1195218D02*
X74773D01*
G01X69323Y1205257D02*
X74773D01*
G01X85465Y1201911D02*
X80015D01*
G01X85465Y1238722D02*
X80015D01*
G01X85465Y1228682D02*
X80015D01*
G01X69323Y1232029D02*
X74773D01*
G01X69323Y1242068D02*
X74773D01*
G01X99024Y760178D02*
X94524D01*
G01X99024Y756832D02*
X94524D01*
G01X85465D02*
X89965D01*
G01X85465Y763525D02*
X89965D01*
G01X339532Y1218605D02*
X328512Y1229625D01*
X288715D01*
X247925Y1270415D01*
X215388D01*
X213049Y1272754D01*
X101050D01*
X95790Y1278014D01*
G01X87058Y1663138D02*
X89466D01*
G01X87017Y1667127D02*
X89466D01*
G01X104829Y158191D02*
X107355D01*
X107931Y158767D01*
G01X99024Y790297D02*
X104474D01*
G01X115166Y786950D02*
X109716D01*
G01X99024Y800336D02*
X104474D01*
G01X115166Y796989D02*
X109716D01*
G01X99024Y827108D02*
X104474D01*
G01X115166Y823761D02*
X109716D01*
G01X115166Y833800D02*
X109716D01*
G01X99024Y837147D02*
X104474D01*
G01X99024Y863919D02*
X104474D01*
G01X115166Y860572D02*
X109716D01*
G01X99024Y873958D02*
X104474D01*
G01X115166Y870611D02*
X109716D01*
G01X99024Y900730D02*
X104474D01*
G01X115166Y897383D02*
X109716D01*
G01X99024Y910769D02*
X104474D01*
G01X115166Y907423D02*
X109716D01*
G01X99024Y937541D02*
X104474D01*
G01X115166Y934194D02*
X109716D01*
G01X99024Y947580D02*
X104474D01*
G01X115166Y944234D02*
X109716D01*
G01X99024Y1084785D02*
X104474D01*
G01X115166Y1081438D02*
X109716D01*
G01X99024Y1094824D02*
X104474D01*
G01X115166Y1091478D02*
X109716D01*
G01X115166Y1118249D02*
X109716D01*
G01X99024Y1121596D02*
X104474D01*
G01X115166Y1128289D02*
X109716D01*
G01X99024Y1131635D02*
X104474D01*
G01X99024Y1158407D02*
X104474D01*
G01X115166Y1155060D02*
X109716D01*
G01X99024Y1168446D02*
X104474D01*
G01X115166Y1165100D02*
X109716D01*
G01X115166Y1191871D02*
X109716D01*
G01X99024Y1195218D02*
X104474D01*
G01X99024Y1205257D02*
X104474D01*
G01X115166Y1201911D02*
X109716D01*
G01X99024Y1232029D02*
X104474D01*
G01X115166Y1228682D02*
X109716D01*
G01X115166Y1238722D02*
X109716D01*
G01X99024Y1242068D02*
X104474D01*
G01X98101Y1371559D02*
Y1373962D01*
G01X98586Y1552796D02*
X101369D01*
X101396Y1552769D01*
G01X104546Y1554069D02*
X104269D01*
X102896Y1555442D01*
X102096D01*
G01X103911Y1667361D02*
X100439D01*
G01X103911D02*
Y1671361D01*
G01Y1679564D02*
X100915D01*
G01X103911Y1675564D02*
Y1679564D01*
G01X122117Y202241D02*
X128367D01*
G01X122117Y207241D02*
X128367D01*
G01X122117Y197241D02*
X128367D01*
G01X122117Y212241D02*
X128367D01*
G01X120016Y297772D02*
Y300654D01*
G01Y318206D02*
Y320631D01*
G01X128724Y760178D02*
X124224D01*
G01X128724Y756832D02*
X124224D01*
G01X115166D02*
X119666D01*
G01X115166Y763525D02*
X119666D01*
G01X127272Y1680276D02*
X126760Y1680788D01*
Y1682383D01*
G01X128724Y790297D02*
X134174D01*
G01X144866Y786950D02*
X139416D01*
G01X128724Y800336D02*
X134174D01*
G01X144866Y796989D02*
X139416D01*
G01X144866Y823761D02*
X139416D01*
G01X144866Y833800D02*
X139416D01*
G01X128724Y827108D02*
X134174D01*
G01X128724Y837147D02*
X134174D01*
G01X128724Y863919D02*
X134174D01*
G01X144866Y860572D02*
X139416D01*
G01X128724Y873958D02*
X134174D01*
G01X144866Y870611D02*
X139416D01*
G01X128724Y900730D02*
X134174D01*
G01X144866Y897383D02*
X139416D01*
G01X128724Y910769D02*
X134174D01*
G01X144866Y907423D02*
X139416D01*
G01X128724Y937541D02*
X134174D01*
G01X144866Y934194D02*
X139416D01*
G01X128724Y947580D02*
X134174D01*
G01X144866Y944234D02*
X139416D01*
G01X144866Y1081438D02*
X139416D01*
G01X128724Y1084785D02*
X134174D01*
G01X144866Y1091478D02*
X139416D01*
G01X128724Y1094824D02*
X134174D01*
G01X144866Y1118249D02*
X139416D01*
G01X144866Y1128289D02*
X139416D01*
G01X128724Y1121596D02*
X134174D01*
G01X128724Y1131635D02*
X134174D01*
G01X128724Y1158407D02*
X134174D01*
G01X144866Y1155060D02*
X139416D01*
G01X128724Y1168446D02*
X134174D01*
G01X144866Y1165100D02*
X139416D01*
G01X144866Y1191871D02*
X139416D01*
G01X128724Y1195218D02*
X134174D01*
G01X128724Y1205257D02*
X134174D01*
G01X144866Y1201911D02*
X139416D01*
G01X144866Y1228682D02*
X139416D01*
G01X144866Y1238722D02*
X139416D01*
G01X128724Y1232029D02*
X134174D01*
G01X128724Y1242068D02*
X134174D01*
G01X130701Y1366612D02*
Y1369018D01*
G01Y1371559D02*
Y1373962D01*
G01X158425Y760178D02*
X153925D01*
G01X158425Y756832D02*
X153925D01*
G01X144866D02*
X149366D01*
G01X144866Y763525D02*
X149366D01*
G01X158425Y790297D02*
X163875D01*
G01X174567Y786950D02*
X169117D01*
G01X158425Y800336D02*
X163875D01*
G01X174567Y796989D02*
X169117D01*
G01X158425Y827108D02*
X163875D01*
G01X174567Y823761D02*
X169117D01*
G01X174567Y833800D02*
X169117D01*
G01X158425Y837147D02*
X163875D01*
G01X158425Y863919D02*
X163875D01*
G01X174567Y860572D02*
X169117D01*
G01X158425Y873958D02*
X163875D01*
G01X174567Y870611D02*
X169117D01*
G01X158425Y900730D02*
X163875D01*
G01X174567Y897383D02*
X169117D01*
G01X158425Y910769D02*
X163875D01*
G01X174567Y907423D02*
X169117D01*
G01X158425Y937541D02*
X163875D01*
G01X174567Y934194D02*
X169117D01*
G01X158425Y947580D02*
X163875D01*
G01X174567Y944234D02*
X169117D01*
G01X158425Y1084785D02*
X163875D01*
G01X174567Y1081438D02*
X169117D01*
G01X158425Y1094824D02*
X163875D01*
G01X174567Y1091478D02*
X169117D01*
G01X174567Y1118249D02*
X169117D01*
G01X158425Y1121596D02*
X163875D01*
G01X174567Y1128289D02*
X169117D01*
G01X158425Y1131635D02*
X163875D01*
G01X158425Y1158407D02*
X163875D01*
G01X174567Y1155060D02*
X169117D01*
G01X158425Y1168446D02*
X163875D01*
G01X174567Y1165100D02*
X169117D01*
G01X174567Y1191871D02*
X169117D01*
G01X158425Y1195218D02*
X163875D01*
G01X158425Y1205257D02*
X163875D01*
G01X174567Y1201911D02*
X169117D01*
G01X158425Y1232029D02*
X163875D01*
G01X174567Y1238722D02*
X169117D01*
G01X174567Y1228682D02*
X169117D01*
G01X158425Y1242068D02*
X163875D01*
G01X163401Y1369018D02*
Y1366612D01*
G01Y1373962D02*
Y1371559D01*
G01X188126Y760178D02*
X183626D01*
G01X188126Y756832D02*
X183626D01*
G01X174567D02*
X179067D01*
G01X174567Y763525D02*
X179067D01*
G01X195979Y113022D02*
Y109462D01*
G01X190861Y128652D02*
X188272D01*
X187250Y129674D01*
G01X205489Y142790D02*
X203317Y144962D01*
X195995D01*
G01X204268Y786950D02*
X198818D01*
G01X188126Y790297D02*
X193576D01*
G01X204268Y796989D02*
X198818D01*
G01X188126Y800336D02*
X193576D01*
G01X204268Y823761D02*
X198818D01*
G01X204268Y833800D02*
X198818D01*
G01X188126Y827108D02*
X193576D01*
G01X188126Y837147D02*
X193576D01*
G01X204268Y860572D02*
X198818D01*
G01X188126Y863919D02*
X193576D01*
G01X204268Y870611D02*
X198818D01*
G01X188126Y873958D02*
X193576D01*
G01X204268Y897383D02*
X198818D01*
G01X188126Y900730D02*
X193576D01*
G01X204268Y907423D02*
X198818D01*
G01X188126Y910769D02*
X193576D01*
G01X204268Y934194D02*
X198818D01*
G01X188126Y937541D02*
X193576D01*
G01X204268Y944234D02*
X198818D01*
G01X188126Y947580D02*
X193576D01*
G01X188126Y1084785D02*
X193576D01*
G01X204268Y1081438D02*
X198818D01*
G01X204268Y1091478D02*
X198818D01*
G01X188126Y1094824D02*
X193576D01*
G01X204268Y1118249D02*
X198818D01*
G01X188126Y1121596D02*
X193576D01*
G01X204268Y1128289D02*
X198818D01*
G01X188126Y1131635D02*
X193576D01*
G01X204268Y1155060D02*
X198818D01*
G01X188126Y1158407D02*
X193576D01*
G01X204268Y1165100D02*
X198818D01*
G01X188126Y1168446D02*
X193576D01*
G01X204268Y1191871D02*
X198818D01*
G01X204268Y1201911D02*
X198818D01*
G01X188126Y1205257D02*
X193576D01*
G01X188126Y1195218D02*
X193576D01*
G01X204268Y1228682D02*
X198818D01*
G01X188126Y1232029D02*
X193576D01*
G01X204268Y1238722D02*
X198818D01*
G01X188126Y1242068D02*
X193576D01*
G01X196301Y1369018D02*
Y1366612D01*
G01Y1373962D02*
Y1371559D01*
G01X208179Y113022D02*
X214107D01*
G01X203061Y128652D02*
Y131158D01*
G01X217827Y760178D02*
X213327D01*
G01X217827Y756832D02*
X213327D01*
G01X204268D02*
X208768D01*
G01X204268Y763525D02*
X208768D01*
G01X224055Y124662D02*
Y127146D01*
G01X233653Y162074D02*
X233609Y162030D01*
X231514D01*
X230445Y160961D01*
Y159071D01*
G01X233969Y786950D02*
X228519D01*
G01X217827Y790297D02*
X223277D01*
G01X233969Y796989D02*
X228519D01*
G01X217827Y800336D02*
X223277D01*
G01X233969Y823761D02*
X228519D01*
G01X233969Y833800D02*
X228519D01*
G01X217827Y827108D02*
X223277D01*
G01X217827Y837147D02*
X223277D01*
G01X233969Y860572D02*
X228519D01*
G01X217827Y863919D02*
X223277D01*
G01X233969Y870611D02*
X228519D01*
G01X217827Y873958D02*
X223277D01*
G01X233969Y897383D02*
X228519D01*
G01X217827Y900730D02*
X223277D01*
G01X233969Y907423D02*
X228519D01*
G01X217827Y910769D02*
X223277D01*
G01X233969Y934194D02*
X228519D01*
G01X217827Y937541D02*
X223277D01*
G01X233969Y944234D02*
X228519D01*
G01X217827Y947580D02*
X223277D01*
G01X217827Y1084785D02*
X223277D01*
G01X233969Y1081438D02*
X228519D01*
G01X233969Y1091478D02*
X228519D01*
G01X217827Y1094824D02*
X223277D01*
G01X233969Y1118249D02*
X228519D01*
G01X217827Y1121596D02*
X223277D01*
G01X233969Y1128289D02*
X228519D01*
G01X217827Y1131635D02*
X223277D01*
G01X233969Y1155060D02*
X228519D01*
G01X217827Y1158407D02*
X223277D01*
G01X233969Y1165100D02*
X228519D01*
G01X217827Y1168446D02*
X223277D01*
G01X233969Y1191871D02*
X228519D01*
G01X233969Y1201911D02*
X228519D01*
G01X217827Y1205257D02*
X223277D01*
G01X217827Y1195218D02*
X223277D01*
G01X233969Y1228682D02*
X228519D01*
G01X217827Y1232029D02*
X223277D01*
G01X233969Y1238722D02*
X228519D01*
G01X217827Y1242068D02*
X223277D01*
G01X229101Y1369018D02*
Y1366612D01*
G01Y1373962D02*
Y1371559D01*
G01X261054Y84185D02*
X244184D01*
X241100Y87269D01*
Y102298D01*
X243487Y104685D01*
G01X242255Y160162D02*
Y162511D01*
X242251Y162515D01*
G01X233969Y756832D02*
X238469D01*
G01X233969Y763525D02*
X238469D01*
G01X262886Y144882D02*
Y147391D01*
G01X266978Y159203D02*
X264577D01*
X264574Y159206D01*
G01X266978Y155203D02*
X264577D01*
X264574Y155206D01*
G01X262701Y1322872D02*
Y1320466D01*
G01Y1327816D02*
Y1325413D01*
G01X285432Y674150D02*
X287832D01*
G01X284392Y1342705D02*
X281992D01*
G01X298091Y67128D02*
Y67309D01*
X296272Y69128D01*
G01X298091Y71128D02*
X296419Y72800D01*
X295755D01*
G01X299628Y156203D02*
Y158702D01*
X299624Y158706D01*
G01X295597Y1320438D02*
Y1322844D01*
G01Y1325385D02*
Y1327788D01*
G01X320174Y95852D02*
Y99833D01*
X320178Y99837D01*
G01X317218Y694525D02*
X317767D01*
X319657Y696415D01*
G01X325617Y76938D02*
X323116D01*
X323113Y76941D01*
G01X328966Y545521D02*
Y543012D01*
G01Y545521D02*
Y548030D01*
G01X331804Y566086D02*
X334744D01*
G01X328654D02*
X324647D01*
G01X328375Y560271D02*
Y565807D01*
X328654Y566086D01*
G01X328501Y1320381D02*
Y1322787D01*
G01Y1327731D02*
Y1325328D01*
G01X349848Y286865D02*
X352628D01*
G01X349695Y286712D02*
X349848Y286865D01*
G01X345500Y574415D02*
X348157D01*
G01X362833Y294030D02*
X360433D01*
G01X355828Y294965D02*
Y297851D01*
X355832Y297855D01*
G01X356032Y550415D02*
Y548711D01*
X356850Y547893D01*
G01X365593Y621622D02*
X367707Y619508D01*
Y617438D01*
G01X361301Y1320581D02*
Y1322987D01*
G01Y1327931D02*
Y1325528D01*
G01X377130Y243615D02*
X380012D01*
G01X384163Y294370D02*
Y295858D01*
X381249Y298772D01*
X379200D01*
G01X375943Y534121D02*
Y524903D01*
G01X384163Y280370D02*
X386563D01*
G01X387184Y491057D02*
Y494382D01*
G01X387440Y532398D02*
Y525154D01*
G01X380771Y534063D02*
Y524903D01*
G01X393883Y1339912D02*
Y1342318D01*
G01Y1347262D02*
Y1344859D01*
G01X399299Y217646D02*
X397938D01*
X396977Y216685D01*
G01X406184Y504676D02*
Y507900D01*
G01X402946Y555915D02*
X406615D01*
X408550Y557850D01*
G01X403381Y573516D02*
X402693D01*
X402281Y573928D01*
X400673D01*
G01X422575Y54762D02*
X424975D01*
G01X411299Y206545D02*
Y189281D01*
X412370Y188210D01*
G01X411299Y217646D02*
Y219699D01*
X411800Y220200D01*
G01X427299Y217646D02*
X424815D01*
G01X417515Y226323D02*
X420115D01*
G01X414365Y235442D02*
X411940D01*
G01X419984Y504599D02*
Y508000D01*
G01X435262Y55016D02*
X431896D01*
X430564Y56348D01*
G01X429997Y163700D02*
Y166400D01*
G01X437997Y163700D02*
Y166400D01*
G01X433997Y163700D02*
Y166400D01*
G01X431299Y206545D02*
Y204145D01*
G01X428899Y222253D02*
X433124D01*
G01X439299Y217646D02*
Y220046D01*
G01X435299Y217646D02*
X431299D01*
G01D02*
X427299D01*
G01X426011Y532701D02*
Y524888D01*
G01X427251Y1289269D02*
Y1291747D01*
G01X441997Y163700D02*
Y166400D01*
G01X449997Y163700D02*
Y166400D01*
G01X453997Y163700D02*
Y166400D01*
G01X445997Y163700D02*
Y166400D01*
G01X451299Y217646D02*
X453783D01*
G01X443299D02*
Y220046D01*
G01X447299Y217646D02*
Y220046D01*
G01X466600Y142800D02*
X468280D01*
X470010Y141070D01*
G01X465997Y163700D02*
Y166400D01*
G01X457997Y163700D02*
Y166400D01*
G01X461997Y163700D02*
Y166400D01*
G01X468574Y210620D02*
Y213104D01*
G01Y206620D02*
Y210620D01*
G01X457931Y215103D02*
Y212703D01*
G01X461931Y215103D02*
Y212703D01*
G01X468971Y231764D02*
X471371D01*
G01X468971Y235764D02*
X471371D01*
G01X458115Y244103D02*
X460624D01*
G01X465821Y243764D02*
X464399Y242342D01*
X462703D01*
G01X465821Y247764D02*
X465040D01*
X463240Y245964D01*
Y244980D01*
G01X458115Y240953D02*
X460624D01*
G01X475428Y60029D02*
X478949D01*
G01X475358Y55135D02*
X478949D01*
G01X475428Y64975D02*
X478949D01*
G01X476700Y90574D02*
X479400D01*
G01X476700Y95574D02*
X477700Y94574D01*
X479400D01*
G01X476700Y100574D02*
X477600D01*
X479400Y98774D01*
Y97574D01*
G01X476700Y110574D02*
X479044D01*
X479400Y110930D01*
G01X476765Y119644D02*
X479465D01*
G01X476765Y115644D02*
X479465D01*
G01X476765Y123644D02*
X479465D01*
G01X483178Y206827D02*
X482073D01*
X480700Y208200D01*
G01X484754Y226527D02*
X487541D01*
G01X486109Y233000D02*
X483227D01*
G01X489118Y55095D02*
X491849D01*
G01X488958Y60105D02*
X491849D01*
G01X488848Y64965D02*
X491849D01*
G01X486949Y109959D02*
Y106610D01*
X487590Y105969D01*
G01X493051Y117243D02*
Y120638D01*
X492300Y121389D01*
G01X497657Y189516D02*
X495232D01*
G01X497657Y193516D02*
X495232D01*
G01X489107D02*
X486682D01*
G01X489107Y197516D02*
X486682D01*
G01X501201Y209285D02*
X498776D01*
G01X489107Y201516D02*
X487316D01*
X486600Y200800D01*
G01X497657Y197516D02*
X495232D01*
G01X501201Y213285D02*
X498776D01*
G01X494459Y238119D02*
X491578D01*
X491577Y238120D01*
G01X506945Y224930D02*
X511170D01*
G01X528304Y210922D02*
X531280D01*
G01X532075Y53543D02*
Y49198D01*
X532070Y49193D01*
G01X539161Y53543D02*
Y49198D01*
X539156Y49193D01*
G01X543413Y222441D02*
X541013D01*
G01X543413Y218441D02*
X541195D01*
X540695Y217941D01*
Y217874D01*
G01X536177Y246780D02*
X533097D01*
G01X539217Y245270D02*
X537577Y243630D01*
X536177D01*
G01X542071Y593089D02*
X543371Y594389D01*
Y595353D01*
G01X540106Y659725D02*
X543126D01*
X543362Y659489D01*
X544162D01*
G01X544771Y195256D02*
X547196D01*
G01X544771Y190256D02*
X547196D01*
G01X550196Y187831D02*
Y190256D01*
G01X554196Y187831D02*
Y190256D01*
G01X556003Y193541D02*
X553578D01*
G01X544771Y199256D02*
X547196D01*
G01X554513Y239566D02*
Y238024D01*
X555567Y236970D01*
G01X546563Y235560D02*
X547971Y234152D01*
X549248D01*
G01X572297Y149226D02*
X568472D01*
G01X573911Y214621D02*
Y212196D01*
G01X571161Y235821D02*
X568736D01*
G01X565908Y426508D02*
X563230D01*
G01X573388Y421390D02*
X575917D01*
G01X582193Y93248D02*
Y94344D01*
X580098Y96439D01*
G01X588194Y178125D02*
X585685D01*
G01X590954Y221277D02*
X588554D01*
G01X577859Y214621D02*
Y212196D01*
G01X590954Y217277D02*
X588554D01*
G01X590954Y225277D02*
X588554D01*
G01X590954Y229277D02*
X588554D01*
G01X588099Y253691D02*
Y256671D01*
X587140Y257630D01*
G01X577949Y261171D02*
X575524D01*
G01X590428Y474353D02*
X587812D01*
G01X703781Y641805D02*
X703431D01*
X682341Y662895D01*
X667733Y668946D01*
X666040Y670639D01*
Y678040D01*
X658390Y685690D01*
X657517D01*
X627521Y715686D01*
Y758898D01*
X624027Y767334D01*
Y770412D01*
X621743Y772696D01*
Y776570D01*
X624737Y779564D01*
Y789888D01*
X598206Y816419D01*
X584762D01*
X581421Y813078D01*
G01X826728Y1246315D02*
X822085D01*
X818684Y1249716D01*
Y1262426D01*
X817938Y1263172D01*
X649716D01*
X641281Y1271607D01*
Y1275602D01*
X635555Y1281328D01*
X631560D01*
X619115Y1293773D01*
X588280D01*
X582881Y1288374D01*
Y1275612D01*
X590746Y1267747D01*
G01X590512Y106645D02*
Y108292D01*
X591385Y109165D01*
G01X602328Y106645D02*
Y109062D01*
G01X596923Y464349D02*
X595179D01*
X594430Y463600D01*
G01X618256Y106645D02*
X615772D01*
G01X616357Y179720D02*
Y182229D01*
G01X615741Y221924D02*
X620307D01*
X620454Y221777D01*
G01X615385Y398578D02*
X617985D01*
G01X617204Y465088D02*
X621916D01*
G01X616219Y483346D02*
X621309D01*
G01X619284Y1367166D02*
X616037D01*
G01X619202Y1390732D02*
X616527D01*
G01X635060Y146218D02*
X631349D01*
X627390Y150177D01*
X625574D01*
G01X635060Y143068D02*
X629654D01*
X625740Y146982D01*
X625532D01*
G01X623604Y221777D02*
Y219278D01*
X623605Y219277D01*
G01X620454Y221777D02*
Y219278D01*
X620455Y219277D01*
G01X623604Y226277D02*
Y228776D01*
X623605Y228777D01*
G01X620454Y226277D02*
Y228776D01*
X620455Y228777D01*
G01X636305Y302289D02*
X633805D01*
G01X626705Y302880D02*
Y305106D01*
X626473Y305338D01*
G01X632996Y474020D02*
Y478309D01*
G01X642394Y128047D02*
Y131172D01*
G01X634914Y137495D02*
Y142922D01*
X635060Y143068D01*
G01X642301Y153126D02*
Y157110D01*
X641111Y158300D01*
G01X643785Y297171D02*
X646285D01*
G01X651735Y307089D02*
Y309480D01*
X649935Y311280D01*
X642171D01*
G01X642449Y405449D02*
Y401636D01*
X642505Y401580D01*
G01X642449Y405449D02*
X637160D01*
G01X642925Y433862D02*
X639211D01*
G01X642925Y442362D02*
X639500D01*
G01X642936Y457746D02*
X641078D01*
X637684Y454352D01*
X637504D01*
G01X643049Y461853D02*
Y457859D01*
X642936Y457746D01*
G01X679047Y678733D02*
X678482Y679298D01*
Y684943D01*
X657852Y705573D01*
Y710532D01*
X644636Y723748D01*
Y737801D01*
X646309Y739474D01*
X672156D01*
X674123Y737507D01*
Y736083D01*
G01X647354Y760178D02*
X642854D01*
G01X647354Y756832D02*
X642854D01*
G01X647354Y790297D02*
X652804D01*
G01X647354Y800336D02*
X652804D01*
G01X647354Y827108D02*
X652804D01*
G01X647354Y837147D02*
X652804D01*
G01X647354Y863919D02*
X652804D01*
G01X647354Y873958D02*
X652804D01*
G01X647354Y900730D02*
X652804D01*
G01X647354Y910769D02*
X652804D01*
G01X647354Y937541D02*
X652804D01*
G01X647354Y947580D02*
X652804D01*
G01X647354Y1084785D02*
X652804D01*
G01X647354Y1094824D02*
X652804D01*
G01X647354Y1121596D02*
X652804D01*
G01X647354Y1131635D02*
X652804D01*
G01X647354Y1158407D02*
X652804D01*
G01X647354Y1168446D02*
X652804D01*
G01X647354Y1205257D02*
X652804D01*
G01X647354Y1195218D02*
X652804D01*
G01X647354Y1232029D02*
X652804D01*
G01X647354Y1242068D02*
X652804D01*
G01X638436Y1353362D02*
Y1350877D01*
G01X646236Y1353362D02*
Y1350877D01*
G01X642436Y1353362D02*
Y1350877D01*
G01X653821Y87337D02*
Y90326D01*
G01X649441Y174201D02*
Y177003D01*
G01X666885Y408330D02*
Y410788D01*
X665085Y412588D01*
X660885D01*
G01X656425Y453862D02*
Y452058D01*
X654441Y450074D01*
Y449618D01*
G01X656365Y461458D02*
X655667D01*
X653449Y459240D01*
Y458542D01*
G01X656365Y461818D02*
Y461458D01*
G01D02*
Y457772D01*
X656348Y457755D01*
G01X656425Y473862D02*
Y469862D01*
G01Y473862D02*
X654014D01*
G01X661242Y495126D02*
Y487079D01*
X661380Y486941D01*
G01D02*
Y486095D01*
X663180Y484295D01*
X663374D01*
G01X663496Y756832D02*
X667996D01*
G01X663496Y763525D02*
X667996D01*
G01X663496Y786950D02*
X658046D01*
G01X663496Y796989D02*
X658046D01*
G01X663496Y833800D02*
X658046D01*
G01X663496Y823761D02*
X658046D01*
G01X663496Y860572D02*
X658046D01*
G01X663496Y870611D02*
X658046D01*
G01X663496Y897383D02*
X658046D01*
G01X663496Y907423D02*
X658046D01*
G01X663496Y934194D02*
X658046D01*
G01X663496Y944234D02*
X658046D01*
G01X663496Y1081438D02*
X658046D01*
G01X663496Y1091478D02*
X658046D01*
G01X663496Y1118249D02*
X658046D01*
G01X663496Y1128289D02*
X658046D01*
G01X663496Y1155060D02*
X658046D01*
G01X663496Y1165100D02*
X658046D01*
G01X663496Y1191871D02*
X658046D01*
G01X663496Y1201911D02*
X658046D01*
G01X663496Y1238722D02*
X658046D01*
G01X663496Y1228682D02*
X658046D01*
G01X650036Y1353362D02*
Y1350877D01*
G01X653836Y1353362D02*
Y1350877D01*
G01X657836Y1353362D02*
Y1350877D01*
G01X683405Y88732D02*
X675843Y96294D01*
Y104110D01*
G01X666948Y398112D02*
X667349Y397711D01*
X671528D01*
X671753Y397936D01*
G01X675620Y409320D02*
X679862D01*
G01X672714Y495084D02*
Y487199D01*
X672457Y486942D01*
G01X672714Y495084D02*
X670339D01*
X669955Y495468D01*
G01X677055Y756832D02*
X672555D01*
G01X677055Y760178D02*
X672555D01*
G01X677055Y790297D02*
X682505D01*
G01X677055Y800336D02*
X682505D01*
G01X677055Y827108D02*
X682505D01*
G01X677055Y837147D02*
X682505D01*
G01X677055Y863919D02*
X682505D01*
G01X677055Y873958D02*
X682505D01*
G01X677055Y900730D02*
X682505D01*
G01X677055Y910769D02*
X682505D01*
G01X677055Y937541D02*
X682505D01*
G01X677055Y947580D02*
X682505D01*
G01X677055Y1084785D02*
X682505D01*
G01X677055Y1094824D02*
X682505D01*
G01X677055Y1121596D02*
X682505D01*
G01X677055Y1131635D02*
X682505D01*
G01X677055Y1158407D02*
X682505D01*
G01X677055Y1168446D02*
X682505D01*
G01X677055Y1205257D02*
X682505D01*
G01X677055Y1195218D02*
X682505D01*
G01X677055Y1232029D02*
X682505D01*
G01X677055Y1242068D02*
X682505D01*
G01X688249Y405628D02*
X687320Y404699D01*
Y396617D01*
X687500Y396437D01*
G01X693197Y756832D02*
X697697D01*
G01X693197Y763525D02*
X697697D01*
G01X693197Y786950D02*
X687747D01*
G01X693197Y796989D02*
X687747D01*
G01X693197Y833800D02*
X687747D01*
G01X693197Y823761D02*
X687747D01*
G01X693197Y860572D02*
X687747D01*
G01X693197Y870611D02*
X687747D01*
G01X693197Y897383D02*
X687747D01*
G01X693197Y907423D02*
X687747D01*
G01X693197Y934194D02*
X687747D01*
G01X693197Y944234D02*
X687747D01*
G01X693197Y1081438D02*
X687747D01*
G01X693197Y1091478D02*
X687747D01*
G01X693197Y1118249D02*
X687747D01*
G01X693197Y1128289D02*
X687747D01*
G01X693197Y1155060D02*
X687747D01*
G01X693197Y1165100D02*
X687747D01*
G01X693197Y1191871D02*
X687747D01*
G01X693197Y1201911D02*
X687747D01*
G01X693197Y1238722D02*
X687747D01*
G01X693197Y1228682D02*
X687747D01*
G01X707545Y363246D02*
Y361041D01*
X707943Y360643D01*
G01X696500Y527437D02*
Y529862D01*
G01X700500Y543437D02*
Y545862D01*
G01X704500Y553437D02*
Y555862D01*
G01X698996Y577506D02*
Y575081D01*
G01X704056Y577506D02*
Y575081D01*
G01X697392Y606060D02*
Y601686D01*
G01X706756Y756832D02*
X702256D01*
G01X706756Y760178D02*
X702256D01*
G01X706756Y790297D02*
X712206D01*
G01X706756Y800336D02*
X712206D01*
G01X706756Y827108D02*
X712206D01*
G01X706756Y837147D02*
X712206D01*
G01X706756Y863919D02*
X712206D01*
G01X706756Y873958D02*
X712206D01*
G01X706756Y900730D02*
X712206D01*
G01X706756Y910769D02*
X712206D01*
G01X706756Y937541D02*
X712206D01*
G01X706756Y947580D02*
X712206D01*
G01X706756Y1084785D02*
X712206D01*
G01X706756Y1094824D02*
X712206D01*
G01X706756Y1121596D02*
X712206D01*
G01X706756Y1131635D02*
X712206D01*
G01X706756Y1158407D02*
X712206D01*
G01X706756Y1168446D02*
X712206D01*
G01X706756Y1195218D02*
X712206D01*
G01X706756Y1205257D02*
X712206D01*
G01X706756Y1232029D02*
X712206D01*
G01X706756Y1242068D02*
X712206D01*
G01X705657Y1391971D02*
Y1389568D01*
G01X709998Y103308D02*
X712172D01*
X713420Y102060D01*
G01X713275Y157762D02*
X714275Y158762D01*
Y165835D01*
X710284Y169826D01*
G01X711458Y363285D02*
Y360904D01*
X711500Y360862D01*
G01X719334Y363287D02*
Y361028D01*
X719500Y360862D01*
G01X715395Y363277D02*
Y360967D01*
X715500Y360862D01*
G01X711845Y587642D02*
X714583D01*
G01X711907Y603278D02*
X715037D01*
G01X711702Y652331D02*
Y654337D01*
X712319Y654954D01*
G01X722898Y756832D02*
X727398D01*
G01X722898Y763525D02*
X727398D01*
G01X722898Y786950D02*
X717448D01*
G01X722898Y796989D02*
X717448D01*
G01X722898Y823761D02*
X717448D01*
G01X722898Y833800D02*
X717448D01*
G01X722898Y860572D02*
X717448D01*
G01X722898Y870611D02*
X717448D01*
G01X722898Y897383D02*
X717448D01*
G01X722898Y907423D02*
X717448D01*
G01X722898Y934194D02*
X717448D01*
G01X722898Y944234D02*
X717448D01*
G01X722898Y1081438D02*
X717448D01*
G01X722898Y1091478D02*
X717448D01*
G01X722898Y1118249D02*
X717448D01*
G01X722898Y1128289D02*
X717448D01*
G01X722898Y1155060D02*
X717448D01*
G01X722898Y1165100D02*
X717448D01*
G01X722898Y1191871D02*
X717448D01*
G01X722898Y1201911D02*
X717448D01*
G01X722898Y1228682D02*
X717448D01*
G01X722898Y1238722D02*
X717448D01*
G01X717798Y1607335D02*
Y1606751D01*
X717110Y1606063D01*
Y1602598D01*
G01X729918Y86998D02*
X727944Y88972D01*
G01X723933Y138563D02*
Y141087D01*
X724134Y141288D01*
G01X735449Y375103D02*
X734553D01*
X733781Y374331D01*
X731406D01*
G01Y376756D02*
Y374331D01*
G01X736457Y756832D02*
X731957D01*
G01X736457Y760178D02*
X731957D01*
G01X736457Y790297D02*
X741907D01*
G01X736457Y800336D02*
X741907D01*
G01X736457Y827108D02*
X741907D01*
G01X736457Y837147D02*
X741907D01*
G01X736457Y863919D02*
X741907D01*
G01X736457Y873958D02*
X741907D01*
G01X736457Y900730D02*
X741907D01*
G01X736457Y910769D02*
X741907D01*
G01X736457Y937541D02*
X741907D01*
G01X736457Y947580D02*
X741907D01*
G01X736457Y1084785D02*
X741907D01*
G01X736457Y1094824D02*
X741907D01*
G01X736457Y1121596D02*
X741907D01*
G01X736457Y1131635D02*
X741907D01*
G01X736457Y1158407D02*
X741907D01*
G01X736457Y1168446D02*
X741907D01*
G01X736457Y1195218D02*
X741907D01*
G01X736457Y1205257D02*
X741907D01*
G01X736457Y1232029D02*
X741907D01*
G01X736457Y1242068D02*
X741907D01*
G01X754710Y119172D02*
X757125D01*
G01X743500Y376787D02*
Y374362D01*
G01X752599Y756832D02*
X757099D01*
G01X752599Y763525D02*
X757099D01*
G01X752599Y786950D02*
X747149D01*
G01X752599Y796989D02*
X747149D01*
G01X752599Y823761D02*
X747149D01*
G01X752599Y833800D02*
X747149D01*
G01X752599Y860572D02*
X747149D01*
G01X752599Y870611D02*
X747149D01*
G01X752599Y897383D02*
X747149D01*
G01X752599Y907423D02*
X747149D01*
G01X752599Y934194D02*
X747149D01*
G01X752599Y944234D02*
X747149D01*
G01X752599Y1081438D02*
X747149D01*
G01X752599Y1091478D02*
X747149D01*
G01X752599Y1118249D02*
X747149D01*
G01X752599Y1128289D02*
X747149D01*
G01X752599Y1155060D02*
X747149D01*
G01X752599Y1165100D02*
X747149D01*
G01X752599Y1191871D02*
X747149D01*
G01X752599Y1201911D02*
X747149D01*
G01X752599Y1228682D02*
X747149D01*
G01X752599Y1238722D02*
X747149D01*
G01X738439Y1387127D02*
Y1384721D01*
G01Y1392071D02*
Y1389668D01*
G01X760193Y96423D02*
X758508Y98108D01*
X757694D01*
G01X760193Y100653D02*
X757694D01*
G01X754710Y119172D02*
Y115290D01*
X754708Y115288D01*
G01X766769Y143438D02*
X770073D01*
G01X759500Y376787D02*
X759652Y376635D01*
Y374362D01*
G01X766158Y756832D02*
X761658D01*
G01X766158Y760178D02*
X761658D01*
G01X766158Y790297D02*
X771608D01*
G01X766158Y800336D02*
X771608D01*
G01X766158Y827108D02*
X771608D01*
G01X766158Y837147D02*
X771608D01*
G01X766158Y863919D02*
X771608D01*
G01X766158Y873958D02*
X771608D01*
G01X766158Y900730D02*
X771608D01*
G01X766158Y910769D02*
X771608D01*
G01X766158Y937541D02*
X771608D01*
G01X766158Y947580D02*
X771608D01*
G01X766158Y1084785D02*
X771608D01*
G01X766158Y1094824D02*
X771608D01*
G01X766158Y1121596D02*
X771608D01*
G01X766158Y1131635D02*
X771608D01*
G01X766158Y1158407D02*
X771608D01*
G01X766158Y1168446D02*
X771608D01*
G01X766158Y1195218D02*
X771608D01*
G01X766158Y1205257D02*
X771608D01*
G01X766158Y1232029D02*
X771608D01*
G01X766158Y1242068D02*
X771608D01*
G01X758179Y1482049D02*
X771220D01*
G01X762913Y1490789D02*
X758163D01*
G01X762913Y1526223D02*
X758163D01*
G01X758179Y1534963D02*
X771220D01*
G01X768725Y167518D02*
X771356D01*
G01X773456Y253292D02*
Y249793D01*
X773457Y249792D01*
G01X778244Y419464D02*
X778645Y419865D01*
X780808D01*
G01X786800Y756832D02*
X782300D01*
G01X786800Y763525D02*
X782300D01*
G01Y786950D02*
X776850D01*
G01X782300Y796989D02*
X776850D01*
G01X782300Y823761D02*
X776850D01*
G01X782300Y833800D02*
X776850D01*
G01X782300Y860572D02*
X776850D01*
G01X782300Y870611D02*
X776850D01*
G01X782300Y897383D02*
X776850D01*
G01X782300Y907423D02*
X776850D01*
G01X782300Y934194D02*
X776850D01*
G01X782300Y944234D02*
X776850D01*
G01X782300Y1081438D02*
X776850D01*
G01X782300Y1091478D02*
X776850D01*
G01X782300Y1118249D02*
X776850D01*
G01X782300Y1128289D02*
X776850D01*
G01X782300Y1155060D02*
X776850D01*
G01X782300Y1165100D02*
X776850D01*
G01X782300Y1191871D02*
X776850D01*
G01X782300Y1201911D02*
X776850D01*
G01X782300Y1228682D02*
X776850D01*
G01X782300Y1238722D02*
X776850D01*
G01X784261Y1482049D02*
X771220D01*
G01X779527Y1488821D02*
X788710D01*
G01X779527Y1528191D02*
X784277D01*
G01X784261Y1534963D02*
X771220D01*
G01X789277Y1524254D02*
X779527D01*
G01X791341Y267822D02*
Y264848D01*
G01X792727Y471344D02*
X797252D01*
G01X795858Y760178D02*
X791358D01*
G01X795858Y756832D02*
X791358D01*
G01X795858Y790297D02*
X801308D01*
G01X795858Y800336D02*
X801308D01*
G01X795858Y827108D02*
X801308D01*
G01X795858Y837147D02*
X801308D01*
G01X795858Y863919D02*
X801308D01*
G01X795858Y873958D02*
X801308D01*
G01X795858Y900730D02*
X801308D01*
G01X795858Y910769D02*
X801308D01*
G01X795858Y937541D02*
X801308D01*
G01X795858Y947580D02*
X801308D01*
G01X795858Y1084785D02*
X801308D01*
G01X795858Y1094824D02*
X801308D01*
G01X795858Y1121596D02*
X801308D01*
G01X795858Y1131635D02*
X801308D01*
G01X795858Y1158407D02*
X801308D01*
G01X795858Y1168446D02*
X801308D01*
G01X795858Y1195218D02*
X801308D01*
G01X795858Y1205257D02*
X801308D01*
G01X795858Y1232029D02*
X801308D01*
G01X795858Y1242068D02*
X801308D01*
G01X791823Y1527404D02*
X789277D01*
G01X791867Y1524254D02*
X789277D01*
G01X809650Y422687D02*
X813175D01*
G01X809694Y495344D02*
X813114D01*
G01X812000Y756832D02*
X816500D01*
G01X812000Y763525D02*
X816500D01*
G01X812000Y786950D02*
X806550D01*
G01X812000Y796989D02*
X806550D01*
G01X812000Y833800D02*
X806550D01*
G01X812000Y823761D02*
X806550D01*
G01X812000Y860572D02*
X806550D01*
G01X812000Y870611D02*
X806550D01*
G01X812000Y897383D02*
X806550D01*
G01X812000Y907423D02*
X806550D01*
G01X812000Y934194D02*
X806550D01*
G01X812000Y944234D02*
X806550D01*
G01X812000Y1081438D02*
X806550D01*
G01X812000Y1091478D02*
X806550D01*
G01X812000Y1118249D02*
X806550D01*
G01X812000Y1128289D02*
X806550D01*
G01X812000Y1155060D02*
X806550D01*
G01X812000Y1165100D02*
X806550D01*
G01X812000Y1191871D02*
X806550D01*
G01X812000Y1201911D02*
X806550D01*
G01X812000Y1228682D02*
X806550D01*
G01X812000Y1238722D02*
X806550D01*
G01X807439Y1340762D02*
Y1342562D01*
X804823Y1345178D01*
X804455D01*
G01X807439Y1340762D02*
Y1336334D01*
G01X804099Y1333835D02*
X804152Y1333888D01*
X806701D01*
X807439Y1334626D01*
Y1336334D01*
G01X801171Y1343278D02*
X802362Y1344118D01*
X803395D01*
X804455Y1345178D01*
G01X807846Y1351988D02*
X810246D01*
G01X810986Y1364193D02*
Y1361684D01*
G01X819114Y117623D02*
Y115224D01*
X819115Y115223D01*
G01X826614Y150273D02*
X829115D01*
G01X826615Y147123D02*
X829115D01*
G01X826614D02*
X826615D01*
G01X828145Y166862D02*
X825332D01*
G01X829867Y543612D02*
X826552D01*
G01X821347Y557607D02*
X823777Y560037D01*
Y560988D01*
G01X831114Y117623D02*
Y115224D01*
X831115Y115223D01*
G01X842562Y168064D02*
X843443D01*
X848745Y162762D01*
G01X830743Y497912D02*
Y500740D01*
G01X850088Y99651D02*
X854578D01*
G01X851895Y162762D02*
Y160141D01*
G01X848745Y162762D02*
Y160137D01*
G01X856228Y265057D02*
X853800D01*
G01X856228Y269057D02*
X853621D01*
G01X868271Y165350D02*
X864663D01*
X861949Y168064D01*
X859688D01*
G01X871500Y316425D02*
Y313500D01*
X874000Y311000D01*
X880972D01*
X881000Y310972D01*
G01X886503Y278712D02*
X884004D01*
G01X886503Y274482D02*
X884004D01*
G01X881018Y293347D02*
Y297342D01*
X881041Y297365D01*
G01D02*
X881075Y297399D01*
Y301500D01*
G01D02*
X881000Y301575D01*
Y310972D01*
G01X884740Y320028D02*
Y316000D01*
G01X877425Y326000D02*
X876500D01*
X874500Y328000D01*
G01X894455Y1153497D02*
Y1149069D01*
G01D02*
Y1147269D01*
X897071Y1144653D01*
X897439D01*
G01D02*
X898499Y1145713D01*
X899532D01*
X900723Y1146553D01*
G01X894048Y1137843D02*
X891648D01*
G01X894455Y1153497D02*
Y1155205D01*
X895369Y1156119D01*
X897754D01*
G01X916268Y275434D02*
Y277859D01*
G01X919968Y554548D02*
X919384D01*
X914575Y559357D01*
Y560027D01*
G01X931496Y195925D02*
X935497D01*
G01X931496Y203012D02*
X935497D01*
G01X945263Y277731D02*
X942779D01*
G01X945006Y590417D02*
Y593609D01*
G01X941480Y1153497D02*
Y1149069D01*
G01D02*
Y1147269D01*
X944096Y1144653D01*
X944464D01*
G01X947748Y1146553D02*
X946557Y1145713D01*
X945524D01*
X944464Y1144653D01*
G01X941480Y1153497D02*
Y1155205D01*
X942394Y1156119D01*
X944820D01*
G01X988835Y191878D02*
Y189589D01*
X988593Y189347D01*
G01X984699D02*
X988593D01*
G01X981445Y182658D02*
Y185389D01*
G01X985445Y182658D02*
Y185389D01*
G01X984880Y264781D02*
X982455D01*
G01X984880Y275443D02*
X982455D01*
G01X1005307Y155043D02*
X1006482Y153868D01*
X1009735D01*
G01X1001575Y152299D02*
Y153265D01*
X999945Y154895D01*
X999580D01*
G01X994575Y152299D02*
Y154577D01*
X994257Y154895D01*
G01X997689Y263340D02*
X995189D01*
G01X1005169Y268884D02*
X1007669D01*
G01X1005169Y258222D02*
X1007669D01*
G01X997689Y274002D02*
X995189D01*
G01X1004460Y363461D02*
X1007083D01*
G01X992678Y420886D02*
X994432D01*
X996232Y422686D01*
Y424440D01*
G01X1000759Y446175D02*
Y451675D01*
G01X1009735Y153868D02*
Y157868D01*
G01X1014828Y261690D02*
Y258970D01*
G01Y270852D02*
Y268427D01*
G01X1015334Y294386D02*
X1017870D01*
G01X1009618Y398990D02*
Y396125D01*
G01X1010277Y433426D02*
X1013365D01*
G01X1023220Y189174D02*
Y191573D01*
X1023221Y191574D01*
G01X1024534Y397726D02*
X1027724D01*
G01X1045465Y756831D02*
X1040965D01*
G01X1045465Y760177D02*
X1040965D01*
G01X1045465Y790296D02*
X1050915D01*
G01X1045465Y800335D02*
X1050915D01*
G01X1045465Y827107D02*
X1050915D01*
G01X1045465Y837146D02*
X1050915D01*
G01X1045465Y863918D02*
X1050915D01*
G01X1045465Y873957D02*
X1050915D01*
G01X1045465Y910768D02*
X1050915D01*
G01X1045465Y900729D02*
X1050915D01*
G01X1045465Y937540D02*
X1050915D01*
G01X1045465Y947579D02*
X1050915D01*
G01X1045465Y1084784D02*
X1050915D01*
G01X1045465Y1094823D02*
X1050915D01*
G01X1045465Y1131634D02*
X1050915D01*
G01X1045465Y1121595D02*
X1050915D01*
G01X1045465Y1158406D02*
X1050915D01*
G01X1045465Y1168445D02*
X1050915D01*
G01X1045465Y1205256D02*
X1050915D01*
G01X1045465Y1195217D02*
X1050915D01*
G01X1045465Y1232028D02*
X1050915D01*
G01X1045465Y1242067D02*
X1050915D01*
G01X1069322Y404123D02*
X1063893D01*
X1061456Y406560D01*
G01X1058092D02*
X1061456D01*
G01X1061607Y756831D02*
X1066107D01*
G01X1061607Y763524D02*
X1066107D01*
G01X1061607Y786949D02*
X1056157D01*
G01X1061607Y796988D02*
X1056157D01*
G01X1061607Y823760D02*
X1056157D01*
G01X1061607Y833799D02*
X1056157D01*
G01X1061607Y860571D02*
X1056157D01*
G01X1061607Y870610D02*
X1056157D01*
G01X1061607Y907422D02*
X1056157D01*
G01X1061607Y897382D02*
X1056157D01*
G01X1061607Y934193D02*
X1056157D01*
G01X1061607Y944233D02*
X1056157D01*
G01X1061607Y1081437D02*
X1056157D01*
G01X1061607Y1091477D02*
X1056157D01*
G01X1061607Y1118248D02*
X1056157D01*
G01X1061607Y1128288D02*
X1056157D01*
G01X1061607Y1155059D02*
X1056157D01*
G01X1061607Y1165099D02*
X1056157D01*
G01X1061607Y1191870D02*
X1056157D01*
G01X1061607Y1201910D02*
X1056157D01*
G01X1061607Y1238721D02*
X1056157D01*
G01X1061607Y1228681D02*
X1056157D01*
G01X1060721Y1313954D02*
Y1311203D01*
G01D02*
X1064775D01*
X1064915Y1311063D01*
G01X1075166Y756831D02*
X1070666D01*
G01X1075166Y760177D02*
X1070666D01*
G01X1075166Y790296D02*
X1080616D01*
G01X1075166Y800335D02*
X1080616D01*
G01X1075166Y827107D02*
X1080616D01*
G01X1075166Y837146D02*
X1080616D01*
G01X1075166Y863918D02*
X1080616D01*
G01X1075166Y873957D02*
X1080616D01*
G01X1075166Y910768D02*
X1080616D01*
G01X1075166Y900729D02*
X1080616D01*
G01X1075166Y937540D02*
X1080616D01*
G01X1075166Y947579D02*
X1080616D01*
G01X1075166Y1084784D02*
X1080616D01*
G01X1075166Y1094823D02*
X1080616D01*
G01X1075166Y1131634D02*
X1080616D01*
G01X1075166Y1121595D02*
X1080616D01*
G01X1075166Y1158406D02*
X1080616D01*
G01X1075166Y1168445D02*
X1080616D01*
G01X1075166Y1205256D02*
X1080616D01*
G01X1075166Y1195217D02*
X1080616D01*
G01X1075166Y1232028D02*
X1080616D01*
G01X1075166Y1242067D02*
X1080616D01*
G01X1069839Y1373943D02*
Y1371540D01*
G01X1091270Y668286D02*
X1108984Y686000D01*
X1139038D01*
X1201860Y748822D01*
Y762406D01*
X1200501Y763765D01*
X1198519D01*
G01X1091308Y756831D02*
X1095808D01*
G01X1091308Y763524D02*
X1095808D01*
G01X1091308Y786949D02*
X1085858D01*
G01X1091308Y796988D02*
X1085858D01*
G01X1091308Y823760D02*
X1085858D01*
G01X1091308Y833799D02*
X1085858D01*
G01X1091308Y860571D02*
X1085858D01*
G01X1091308Y870610D02*
X1085858D01*
G01X1091308Y907422D02*
X1085858D01*
G01X1091308Y897382D02*
X1085858D01*
G01X1091308Y934193D02*
X1085858D01*
G01X1091308Y944233D02*
X1085858D01*
G01X1091308Y1081437D02*
X1085858D01*
G01X1091308Y1091477D02*
X1085858D01*
G01X1091308Y1118248D02*
X1085858D01*
G01X1091308Y1128288D02*
X1085858D01*
G01X1091308Y1155059D02*
X1085858D01*
G01X1091308Y1165099D02*
X1085858D01*
G01X1091308Y1191870D02*
X1085858D01*
G01X1091308Y1201910D02*
X1085858D01*
G01X1091308Y1238721D02*
X1085858D01*
G01X1091308Y1228681D02*
X1085858D01*
G01X1104866Y756831D02*
X1100366D01*
G01X1104866Y760177D02*
X1100366D01*
G01X1104866Y790296D02*
X1110316D01*
G01X1104866Y800335D02*
X1110316D01*
G01X1104866Y827107D02*
X1110316D01*
G01X1104866Y837146D02*
X1110316D01*
G01X1104866Y863918D02*
X1110316D01*
G01X1104866Y873957D02*
X1110316D01*
G01X1104866Y910768D02*
X1110316D01*
G01X1104866Y900729D02*
X1110316D01*
G01X1104866Y937540D02*
X1110316D01*
G01X1104866Y947579D02*
X1110316D01*
G01X1104866Y1084784D02*
X1110316D01*
G01X1104866Y1094823D02*
X1110316D01*
G01X1104866Y1131634D02*
X1110316D01*
G01X1104866Y1121595D02*
X1110316D01*
G01X1104866Y1158406D02*
X1110316D01*
G01X1104866Y1168445D02*
X1110316D01*
G01X1104866Y1205256D02*
X1110316D01*
G01X1104866Y1195217D02*
X1110316D01*
G01X1104866Y1232028D02*
X1110316D01*
G01X1104866Y1242067D02*
X1110316D01*
G01X1102439Y1368999D02*
Y1366593D01*
G01Y1373943D02*
Y1371540D01*
G01X1126658Y52651D02*
X1121157D01*
X1119676Y54132D01*
G01X1121008Y756831D02*
X1125508D01*
G01X1121008Y763524D02*
X1125508D01*
G01X1121008Y786949D02*
X1115558D01*
G01X1121008Y796988D02*
X1115558D01*
G01X1121008Y823760D02*
X1115558D01*
G01X1121008Y833799D02*
X1115558D01*
G01X1121008Y860571D02*
X1115558D01*
G01X1121008Y870610D02*
X1115558D01*
G01X1121008Y907422D02*
X1115558D01*
G01X1121008Y897382D02*
X1115558D01*
G01X1121008Y934193D02*
X1115558D01*
G01X1121008Y944233D02*
X1115558D01*
G01X1121008Y1081437D02*
X1115558D01*
G01X1121008Y1091477D02*
X1115558D01*
G01X1121008Y1118248D02*
X1115558D01*
G01X1121008Y1128288D02*
X1115558D01*
G01X1121008Y1155059D02*
X1115558D01*
G01X1121008Y1165099D02*
X1115558D01*
G01X1121008Y1191870D02*
X1115558D01*
G01X1121008Y1201910D02*
X1115558D01*
G01X1121008Y1238721D02*
X1115558D01*
G01X1121008Y1228681D02*
X1115558D01*
G01X1136480Y380533D02*
X1139200D01*
G01X1136480Y385698D02*
X1139200D01*
G01X1127484Y398020D02*
Y402058D01*
X1127471Y402071D01*
Y404788D01*
G01X1134567Y756831D02*
X1130067D01*
G01X1134567Y760177D02*
X1130067D01*
G01X1134567Y790296D02*
X1140017D01*
G01X1134567Y800335D02*
X1140017D01*
G01X1134567Y827107D02*
X1140017D01*
G01X1134567Y837146D02*
X1140017D01*
G01X1134567Y863918D02*
X1140017D01*
G01X1134567Y873957D02*
X1140017D01*
G01X1134567Y910768D02*
X1140017D01*
G01X1134567Y900729D02*
X1140017D01*
G01X1134567Y937540D02*
X1140017D01*
G01X1134567Y947579D02*
X1140017D01*
G01X1134567Y1084784D02*
X1140017D01*
G01X1134567Y1094823D02*
X1140017D01*
G01X1134567Y1131634D02*
X1140017D01*
G01X1134567Y1121595D02*
X1140017D01*
G01X1134567Y1158406D02*
X1140017D01*
G01X1134567Y1168445D02*
X1140017D01*
G01X1134567Y1205256D02*
X1140017D01*
G01X1134567Y1195217D02*
X1140017D01*
G01X1134567Y1232028D02*
X1140017D01*
G01X1134567Y1242067D02*
X1140017D01*
G01X1135139Y1366593D02*
Y1368999D01*
G01Y1373943D02*
Y1371540D01*
G01X1133846Y1456373D02*
X1137846D01*
G01D02*
Y1453487D01*
G01X1131256Y1572102D02*
X1133765D01*
G01X1131256Y1568952D02*
X1133765D01*
G01X1144663Y489819D02*
Y492319D01*
G01X1150709Y756831D02*
X1155209D01*
G01X1150709Y763524D02*
X1155209D01*
G01X1150709Y786949D02*
X1145259D01*
G01X1150709Y796988D02*
X1145259D01*
G01X1150709Y823760D02*
X1145259D01*
G01X1150709Y833799D02*
X1145259D01*
G01X1150709Y860571D02*
X1145259D01*
G01X1150709Y870610D02*
X1145259D01*
G01X1150709Y907422D02*
X1145259D01*
G01X1150709Y897382D02*
X1145259D01*
G01X1150709Y934193D02*
X1145259D01*
G01X1150709Y944233D02*
X1145259D01*
G01X1150709Y1081437D02*
X1145259D01*
G01X1150709Y1091477D02*
X1145259D01*
G01X1150709Y1118248D02*
X1145259D01*
G01X1150709Y1128288D02*
X1145259D01*
G01X1150709Y1155059D02*
X1145259D01*
G01X1150709Y1165099D02*
X1145259D01*
G01X1150709Y1191870D02*
X1145259D01*
G01X1150709Y1201910D02*
X1145259D01*
G01X1150709Y1238721D02*
X1145259D01*
G01X1150709Y1228681D02*
X1145259D01*
G01X1164268Y760177D02*
X1159768D01*
G01X1164268Y756831D02*
X1159768D01*
G01X1164268Y790296D02*
X1169718D01*
G01X1164268Y800335D02*
X1169718D01*
G01X1164268Y827107D02*
X1169718D01*
G01X1164268Y837146D02*
X1169718D01*
G01X1164268Y863918D02*
X1169718D01*
G01X1164268Y873957D02*
X1169718D01*
G01X1164268Y900729D02*
X1169718D01*
G01X1164268Y910768D02*
X1169718D01*
G01X1164268Y937540D02*
X1169718D01*
G01X1164268Y947579D02*
X1169718D01*
G01X1164268Y1084784D02*
X1169718D01*
G01X1164268Y1094823D02*
X1169718D01*
G01X1164268Y1121595D02*
X1169718D01*
G01X1164268Y1131634D02*
X1169718D01*
G01X1164268Y1158406D02*
X1169718D01*
G01X1164268Y1168445D02*
X1169718D01*
G01X1164268Y1205256D02*
X1169718D01*
G01X1164268Y1195217D02*
X1169718D01*
G01X1164268Y1232028D02*
X1169718D01*
G01X1164268Y1242067D02*
X1169718D01*
G01X1168039Y1366593D02*
Y1368999D01*
G01Y1373943D02*
Y1371540D01*
G01X1172781Y453341D02*
X1175181D01*
G01X1172781Y481691D02*
X1175181D01*
G01X1185117Y574322D02*
Y571807D01*
G01X1180410Y756831D02*
X1184910D01*
G01X1180410Y763524D02*
X1184910D01*
G01X1180410Y786949D02*
X1174960D01*
G01X1180410Y796988D02*
X1174960D01*
G01X1180410Y833799D02*
X1174960D01*
G01X1180410Y823760D02*
X1174960D01*
G01X1180410Y860571D02*
X1174960D01*
G01X1180410Y870610D02*
X1174960D01*
G01X1180410Y897382D02*
X1174960D01*
G01X1180410Y907422D02*
X1174960D01*
G01X1180410Y934193D02*
X1174960D01*
G01X1180410Y944233D02*
X1174960D01*
G01X1180410Y1081437D02*
X1174960D01*
G01X1180410Y1091477D02*
X1174960D01*
G01X1180410Y1118248D02*
X1174960D01*
G01X1180410Y1128288D02*
X1174960D01*
G01X1180410Y1155059D02*
X1174960D01*
G01X1180410Y1165099D02*
X1174960D01*
G01X1180410Y1191870D02*
X1174960D01*
G01X1180410Y1201910D02*
X1174960D01*
G01X1180410Y1238721D02*
X1174960D01*
G01X1180410Y1228681D02*
X1174960D01*
G01X1193969Y760177D02*
X1189469D01*
G01X1193969Y756831D02*
X1189469D01*
G01X1193969Y790296D02*
X1199419D01*
G01X1193969Y800335D02*
X1199419D01*
G01X1193969Y827107D02*
X1199419D01*
G01X1193969Y837146D02*
X1199419D01*
G01X1193969Y863918D02*
X1199419D01*
G01X1193969Y873957D02*
X1199419D01*
G01X1193969Y900729D02*
X1199419D01*
G01X1193969Y910768D02*
X1199419D01*
G01X1193969Y937540D02*
X1199419D01*
G01X1193969Y947579D02*
X1199419D01*
G01X1193969Y1084784D02*
X1199419D01*
G01X1193969Y1094823D02*
X1199419D01*
G01X1193969Y1121595D02*
X1199419D01*
G01X1193969Y1131634D02*
X1199419D01*
G01X1193969Y1158406D02*
X1199419D01*
G01X1193969Y1168445D02*
X1199419D01*
G01X1193969Y1195217D02*
X1199419D01*
G01X1193969Y1205256D02*
X1199419D01*
G01X1193969Y1232028D02*
X1199419D01*
G01X1193969Y1242067D02*
X1199419D01*
G01X1214600Y759562D02*
Y758632D01*
X1212799Y756831D01*
X1210111D01*
G01Y763524D02*
X1214611D01*
G01X1210111Y786949D02*
X1204661D01*
G01X1210111Y796988D02*
X1204661D01*
G01X1210111Y833799D02*
X1204661D01*
G01X1210111Y823760D02*
X1204661D01*
G01X1210111Y860571D02*
X1204661D01*
G01X1210111Y870610D02*
X1204661D01*
G01X1210111Y897382D02*
X1204661D01*
G01X1210111Y907422D02*
X1204661D01*
G01X1210111Y934193D02*
X1204661D01*
G01X1210111Y944233D02*
X1204661D01*
G01X1210111Y1081437D02*
X1204661D01*
G01X1210111Y1091477D02*
X1204661D01*
G01X1210111Y1118248D02*
X1204661D01*
G01X1210111Y1128288D02*
X1204661D01*
G01X1210111Y1155059D02*
X1204661D01*
G01X1210111Y1165099D02*
X1204661D01*
G01X1210111Y1191870D02*
X1204661D01*
G01X1210111Y1201910D02*
X1204661D01*
G01X1210111Y1228681D02*
X1204661D01*
G01X1210111Y1238721D02*
X1204661D01*
G01X1200839Y1366593D02*
Y1368999D01*
G01Y1371540D02*
Y1373943D01*
G01X1215581Y88921D02*
Y91346D01*
G01X1223455Y88921D02*
Y91346D01*
G01X1217831Y131307D02*
X1220931D01*
G01X1230312Y91060D02*
Y88635D01*
G01X1236909Y90470D02*
X1234647D01*
X1232812Y88635D01*
G01X1238830Y1322853D02*
Y1320447D01*
G01Y1325394D02*
Y1327797D01*
G01X1253152Y87320D02*
Y84895D01*
G01X1259472Y90439D02*
Y92864D01*
G01X1253152Y101100D02*
X1256064D01*
G01X1253152Y97950D02*
Y95525D01*
G01X1260227Y407128D02*
X1260230Y407125D01*
X1262627D01*
G01X1260227Y411128D02*
X1260230Y411125D01*
X1262627D01*
G01X1260227Y415128D02*
X1260230Y415125D01*
X1262627D01*
G01X1260521Y1342686D02*
X1258121D01*
G01X1263472Y90439D02*
Y92864D01*
G01X1271457Y236594D02*
X1277732D01*
G01X1271457Y246594D02*
X1277732D01*
G01X1271457Y241594D02*
X1277732D01*
G01X1271457Y251594D02*
X1277732D01*
G01X1271726Y1320419D02*
Y1322825D01*
G01Y1325366D02*
Y1327769D01*
G01X1296200Y64486D02*
Y66911D01*
G01X1296228Y408125D02*
X1293277D01*
G01X1299076Y527418D02*
Y530023D01*
G01X1304630Y1320362D02*
Y1322768D01*
G01Y1327712D02*
Y1325309D01*
G01X1308110Y64486D02*
Y66911D01*
G01X1319667Y83687D02*
Y87587D01*
G01Y101327D02*
Y105227D01*
G01X1318363Y1408282D02*
Y1411404D01*
G01X1320020Y64554D02*
Y66979D01*
G01X1331930Y64520D02*
Y66945D01*
G01X1339840Y75369D02*
Y72860D01*
G01X1343840Y64486D02*
Y66911D01*
G01X1344958Y82849D02*
Y85358D01*
G01X1341535Y236594D02*
X1335260D01*
G01X1341535Y246594D02*
X1335260D01*
G01X1341535Y241594D02*
X1335260D01*
G01X1341535Y251594D02*
X1335260D01*
G01X1337430Y1320562D02*
Y1322968D01*
G01Y1327912D02*
Y1325509D01*
G01X1351750Y75335D02*
Y72826D01*
G01X1361550Y64564D02*
Y67264D01*
G01X1355750Y64486D02*
Y66886D01*
G01X1356868Y82815D02*
Y85324D01*
G01X1360629Y116205D02*
Y120380D01*
G01X1367950Y64486D02*
Y66886D01*
G01X1369808Y83687D02*
Y87587D01*
G01X1371259Y100509D02*
Y98000D01*
G01X1368109Y100509D02*
Y98000D01*
G01X1370012Y1339893D02*
Y1342299D01*
G01Y1347243D02*
Y1344840D01*
G01X1408817Y109037D02*
X1404917D01*
G01X1407615Y1285765D02*
Y1283613D01*
X1406608Y1282606D01*
G01X1403690Y1286190D02*
X1407190D01*
X1407615Y1285765D01*
G01X1434262Y55317D02*
Y52892D01*
G01X1438262Y55317D02*
Y52892D01*
G01X1434513Y109825D02*
Y106950D01*
G01X1429169Y109738D02*
Y107313D01*
G01X1445372Y52933D02*
X1441907D01*
X1441141Y53699D01*
G01X1446869Y108286D02*
Y105129D01*
G01X1439049Y109868D02*
Y107443D01*
G01X1443049Y109868D02*
Y107443D01*
G01X1448549Y117068D02*
Y114643D01*
G01X1444769Y171792D02*
Y174217D01*
G01X1439769Y179792D02*
Y182217D01*
G01X1449769Y179792D02*
Y182217D01*
G01X1454769Y171792D02*
Y173619D01*
X1453974Y174414D01*
G01X1459896Y61563D02*
X1462405D01*
G01X1464830D02*
Y59054D01*
G01X1454549Y109868D02*
Y107443D01*
G01X1458817Y128242D02*
X1461242D01*
G01X1465832Y537827D02*
Y535330D01*
G01X1458682Y564977D02*
Y566577D01*
X1456282Y568977D01*
G01X1483820Y125683D02*
Y122713D01*
G01X1502443Y134562D02*
X1498864D01*
X1495539Y131237D01*
G01X1492797Y127082D02*
X1488135D01*
X1486384Y128833D01*
X1483820D01*
G01D02*
Y132405D01*
G01X1491560Y594462D02*
X1494371D01*
G01X1513644Y222100D02*
Y220662D01*
X1514576Y219730D01*
G01X1513348Y256463D02*
Y253954D01*
G01X1513644Y249500D02*
Y250583D01*
X1514900Y251839D01*
G01X1526894Y201250D02*
X1529379D01*
X1529384Y201245D01*
G01X1518944Y249250D02*
X1516926D01*
X1516452Y249724D01*
G01X1608652Y1303338D02*
X1613197Y1298793D01*
Y1271327D01*
X1595030Y1253160D01*
Y1241819D01*
X1577129Y1223918D01*
X1547000D01*
X1543663Y1220581D01*
X1521680D01*
X1518777Y1217678D01*
Y1192528D01*
X1521217Y1190088D01*
G01X1536542Y304819D02*
X1536545Y304816D01*
X1538942D01*
G01X1536542Y300819D02*
X1536545Y300816D01*
X1538942D01*
G01X1536542Y308819D02*
X1536545Y308816D01*
X1538942D01*
G01X1539693Y538038D02*
Y535212D01*
G01X1542697Y565162D02*
X1545960D01*
G01X1542697Y562012D02*
X1545987D01*
G01X1564202Y224250D02*
X1556405D01*
X1552981Y220826D01*
G01X1564202Y219250D02*
X1556405D01*
X1555481Y218326D01*
G01X1612144Y418552D02*
X1606709D01*
X1550542Y474719D01*
Y491686D01*
X1554438Y495582D01*
Y533999D01*
X1555585Y535146D01*
Y575855D01*
X1557503Y577773D01*
X1561345D01*
G01X1564202Y249250D02*
X1572502D01*
X1574546Y251294D01*
G01X1572283Y301816D02*
X1569592D01*
G01X1588800Y306746D02*
X1586291D01*
G01X1582927Y536344D02*
X1579748D01*
G01X1594537Y295328D02*
X1599837D01*
G01X1590407Y531226D02*
X1593214D01*
G01X1617400Y303596D02*
X1619909D01*
G01X1632822Y221842D02*
X1629597D01*
G01X1625484Y298742D02*
X1627909D01*
G01X1625484Y294742D02*
X1627909D01*
G01X1635425Y381500D02*
X1632500D01*
G01X1629000Y385925D02*
X1632500D01*
X1633547Y386972D01*
X1638500D01*
G01X1629000Y396075D02*
X1630927Y398002D01*
G01X1623496Y760177D02*
X1618996D01*
G01X1623496Y756831D02*
X1618996D01*
G01X1623496Y790296D02*
X1628946D01*
G01X1623496Y800335D02*
X1628946D01*
G01X1623496Y827107D02*
X1628946D01*
G01X1623496Y837146D02*
X1628946D01*
G01X1623496Y863918D02*
X1628946D01*
G01X1623496Y873957D02*
X1628946D01*
G01X1623496Y900729D02*
X1628946D01*
G01X1623496Y910768D02*
X1628946D01*
G01X1623496Y937540D02*
X1628946D01*
G01X1623496Y947579D02*
X1628946D01*
G01X1623496Y1084784D02*
X1628946D01*
G01X1623496Y1094823D02*
X1628946D01*
G01X1623496Y1121595D02*
X1628946D01*
G01X1623496Y1131634D02*
X1628946D01*
G01X1623496Y1158406D02*
X1628946D01*
G01X1623496Y1168445D02*
X1628946D01*
G01X1623496Y1195217D02*
X1628946D01*
G01X1623496Y1205256D02*
X1628946D01*
G01X1623496Y1232028D02*
X1628946D01*
G01X1623496Y1242067D02*
X1628946D01*
G01X1638575Y381500D02*
X1638500Y381575D01*
Y386972D01*
G01X1668000Y378000D02*
X1642075D01*
X1638575Y381500D01*
G01X1649979Y618971D02*
X1647158D01*
G01X1639638Y756831D02*
X1644138D01*
G01X1639638Y763524D02*
X1644138D01*
G01X1639638Y786949D02*
X1634188D01*
G01X1639638Y796988D02*
X1634188D01*
G01X1639638Y823760D02*
X1634188D01*
G01X1639638Y833799D02*
X1634188D01*
G01X1639638Y860571D02*
X1634188D01*
G01X1639638Y870610D02*
X1634188D01*
G01X1639638Y897382D02*
X1634188D01*
G01X1639638Y907422D02*
X1634188D01*
G01X1639638Y934193D02*
X1634188D01*
G01X1639638Y944233D02*
X1634188D01*
G01X1639638Y1081437D02*
X1634188D01*
G01X1639638Y1091477D02*
X1634188D01*
G01X1639638Y1118248D02*
X1634188D01*
G01X1639638Y1128288D02*
X1634188D01*
G01X1639638Y1155059D02*
X1634188D01*
G01X1639638Y1165099D02*
X1634188D01*
G01X1639638Y1191870D02*
X1634188D01*
G01X1639638Y1201910D02*
X1634188D01*
G01X1639638Y1228681D02*
X1634188D01*
G01X1639638Y1238721D02*
X1634188D01*
G01X1654950Y141762D02*
X1652525D01*
G01X1654950Y146762D02*
X1652525D01*
G01X1654950Y151762D02*
X1652525D01*
G01X1654950Y161762D02*
X1652525D01*
G01X1651910Y233062D02*
X1654419D01*
G01X1661928Y227747D02*
Y230172D01*
G01X1653197Y760177D02*
X1648697D01*
G01X1653197Y756831D02*
X1648697D01*
G01X1653197Y790296D02*
X1658647D01*
G01X1653197Y800335D02*
X1658647D01*
G01X1653197Y827107D02*
X1658647D01*
G01X1653197Y837146D02*
X1658647D01*
G01X1653197Y863918D02*
X1658647D01*
G01X1653197Y873957D02*
X1658647D01*
G01X1653197Y900729D02*
X1658647D01*
G01X1653197Y910768D02*
X1658647D01*
G01X1653197Y937540D02*
X1658647D01*
G01X1653197Y947579D02*
X1658647D01*
G01X1653197Y1084784D02*
X1658647D01*
G01X1653197Y1094823D02*
X1658647D01*
G01X1653197Y1121595D02*
X1658647D01*
G01X1653197Y1131634D02*
X1658647D01*
G01X1653197Y1158406D02*
X1658647D01*
G01X1653197Y1168445D02*
X1658647D01*
G01X1653197Y1205256D02*
X1658647D01*
G01X1653197Y1195217D02*
X1658647D01*
G01X1653197Y1232028D02*
X1658647D01*
G01X1653197Y1242067D02*
X1658647D01*
G01X1669100Y126762D02*
X1673100D01*
G01X1669100Y156762D02*
X1665100D01*
G01X1669100Y166762D02*
X1665100D01*
G01X1675509Y206451D02*
X1678809D01*
G01X1668612Y220857D02*
X1673223D01*
G01X1669339Y756831D02*
X1673839D01*
G01X1669339Y763524D02*
X1673839D01*
G01X1669339Y786949D02*
X1663889D01*
G01X1669339Y796988D02*
X1663889D01*
G01X1669339Y823760D02*
X1663889D01*
G01X1669339Y833799D02*
X1663889D01*
G01X1669339Y860571D02*
X1663889D01*
G01X1669339Y870610D02*
X1663889D01*
G01X1669339Y897382D02*
X1663889D01*
G01X1669339Y907422D02*
X1663889D01*
G01X1669339Y934193D02*
X1663889D01*
G01X1669339Y944233D02*
X1663889D01*
G01X1669339Y1081437D02*
X1663889D01*
G01X1669339Y1091477D02*
X1663889D01*
G01X1669339Y1118248D02*
X1663889D01*
G01X1669339Y1128288D02*
X1663889D01*
G01X1669339Y1155059D02*
X1663889D01*
G01X1669339Y1165099D02*
X1663889D01*
G01X1669339Y1191870D02*
X1663889D01*
G01X1669339Y1201910D02*
X1663889D01*
G01X1669339Y1228681D02*
X1663889D01*
G01X1669339Y1238721D02*
X1663889D01*
G01X1684942Y231487D02*
Y234000D01*
G01X1689000Y231575D02*
Y234000D01*
G01X1686154Y431760D02*
Y434160D01*
G01X1690140D02*
X1690154Y434146D01*
Y431760D01*
G01X1682898Y760177D02*
X1678398D01*
G01X1682898Y756831D02*
X1678398D01*
G01X1682898Y790296D02*
X1688348D01*
G01X1682898Y800335D02*
X1688348D01*
G01X1682898Y827107D02*
X1688348D01*
G01X1682898Y837146D02*
X1688348D01*
G01X1682898Y863918D02*
X1688348D01*
G01X1682898Y873957D02*
X1688348D01*
G01X1682898Y910768D02*
X1688348D01*
G01X1682898Y900729D02*
X1688348D01*
G01X1682898Y937540D02*
X1688348D01*
G01X1682898Y947579D02*
X1688348D01*
G01X1682898Y1084784D02*
X1688348D01*
G01X1682898Y1094823D02*
X1688348D01*
G01X1682898Y1131634D02*
X1688348D01*
G01X1682898Y1121595D02*
X1688348D01*
G01X1682898Y1158406D02*
X1688348D01*
G01X1682898Y1168445D02*
X1688348D01*
G01X1682898Y1205256D02*
X1688348D01*
G01X1682898Y1195217D02*
X1688348D01*
G01X1682898Y1232028D02*
X1688348D01*
G01X1682898Y1242067D02*
X1688348D01*
G01X1687883Y1699152D02*
Y1700794D01*
X1689184Y1702095D01*
G01X1693000Y231575D02*
Y234000D01*
G01X1699809Y401485D02*
Y403985D01*
G01X1695579Y401485D02*
Y403985D01*
G01X1699040Y756831D02*
X1703540D01*
G01X1699040Y763524D02*
X1703540D01*
G01X1699040Y786949D02*
X1693590D01*
G01X1699040Y796988D02*
X1693590D01*
G01X1699040Y823760D02*
X1693590D01*
G01X1699040Y833799D02*
X1693590D01*
G01X1699040Y860571D02*
X1693590D01*
G01X1699040Y870610D02*
X1693590D01*
G01X1699040Y907422D02*
X1693590D01*
G01X1699040Y897382D02*
X1693590D01*
G01X1699040Y934193D02*
X1693590D01*
G01X1699040Y944233D02*
X1693590D01*
G01X1699040Y1081437D02*
X1693590D01*
G01X1699040Y1091477D02*
X1693590D01*
G01X1699040Y1118248D02*
X1693590D01*
G01X1699040Y1128288D02*
X1693590D01*
G01X1699040Y1155059D02*
X1693590D01*
G01X1699040Y1165099D02*
X1693590D01*
G01X1699040Y1191870D02*
X1693590D01*
G01X1699040Y1201910D02*
X1693590D01*
G01X1699040Y1228681D02*
X1693590D01*
G01X1699040Y1238721D02*
X1693590D01*
G01X1736193Y89087D02*
X1733778Y86672D01*
X1723646D01*
X1718608Y91710D01*
Y101009D01*
G01X1712599Y760177D02*
X1708099D01*
G01X1712599Y756831D02*
X1708099D01*
G01X1712599Y790296D02*
X1718049D01*
G01X1712599Y800335D02*
X1718049D01*
G01X1712599Y827107D02*
X1718049D01*
G01X1712599Y837146D02*
X1718049D01*
G01X1712599Y863918D02*
X1718049D01*
G01X1712599Y873957D02*
X1718049D01*
G01X1712599Y910768D02*
X1718049D01*
G01X1712599Y900729D02*
X1718049D01*
G01X1712599Y937540D02*
X1718049D01*
G01X1712599Y947579D02*
X1718049D01*
G01X1712599Y1084784D02*
X1718049D01*
G01X1712599Y1094823D02*
X1718049D01*
G01X1712599Y1131634D02*
X1718049D01*
G01X1712599Y1121595D02*
X1718049D01*
G01X1712599Y1158406D02*
X1718049D01*
G01X1712599Y1168445D02*
X1718049D01*
G01X1712599Y1205256D02*
X1718049D01*
G01X1712599Y1195217D02*
X1718049D01*
G01X1712599Y1232028D02*
X1718049D01*
G01X1712599Y1242067D02*
X1718049D01*
G01X1736193Y89827D02*
Y89087D01*
G01X1730364Y174526D02*
Y177588D01*
G01X1728741Y756831D02*
X1733241D01*
G01X1728741Y763524D02*
X1733241D01*
G01X1728741Y786949D02*
X1723291D01*
G01X1728741Y796988D02*
X1723291D01*
G01X1728741Y823760D02*
X1723291D01*
G01X1728741Y833799D02*
X1723291D01*
G01X1728741Y860571D02*
X1723291D01*
G01X1728741Y870610D02*
X1723291D01*
G01X1728741Y907422D02*
X1723291D01*
G01X1728741Y897382D02*
X1723291D01*
G01X1728741Y934193D02*
X1723291D01*
G01X1728741Y944233D02*
X1723291D01*
G01X1728741Y1081437D02*
X1723291D01*
G01X1728741Y1091477D02*
X1723291D01*
G01X1728741Y1118248D02*
X1723291D01*
G01X1728741Y1128288D02*
X1723291D01*
G01X1728741Y1155059D02*
X1723291D01*
G01X1728741Y1165099D02*
X1723291D01*
G01X1728741Y1191870D02*
X1723291D01*
G01X1728741Y1201910D02*
X1723291D01*
G01X1728741Y1228681D02*
X1723291D01*
G01X1728741Y1238721D02*
X1723291D01*
G01X1735379Y1566282D02*
X1737914D01*
G01X1730202Y1579277D02*
Y1570265D01*
X1734171Y1566296D01*
X1735365D01*
X1735379Y1566282D01*
G01X1730202Y1596018D02*
Y1579277D01*
G01X1726202Y1596018D02*
X1730202D01*
G01Y1599168D02*
Y1602093D01*
G01X1726888Y1681465D02*
X1724263D01*
G01X1742300Y760177D02*
X1737800D01*
G01X1742300Y756831D02*
X1737800D01*
G01X1742300Y790296D02*
X1747750D01*
G01X1742300Y800335D02*
X1747750D01*
G01X1742300Y827107D02*
X1747750D01*
G01X1742300Y837146D02*
X1747750D01*
G01X1742300Y863918D02*
X1747750D01*
G01X1742300Y873957D02*
X1747750D01*
G01X1742300Y910768D02*
X1747750D01*
G01X1742300Y900729D02*
X1747750D01*
G01X1742300Y937540D02*
X1747750D01*
G01X1742300Y947579D02*
X1747750D01*
G01X1742300Y1084784D02*
X1747750D01*
G01X1742300Y1094823D02*
X1747750D01*
G01X1742300Y1131634D02*
X1747750D01*
G01X1742300Y1121595D02*
X1747750D01*
G01X1742300Y1158406D02*
X1747750D01*
G01X1742300Y1168445D02*
X1747750D01*
G01X1742300Y1205256D02*
X1747750D01*
G01X1742300Y1195217D02*
X1747750D01*
G01X1742300Y1232028D02*
X1747750D01*
G01X1742300Y1242067D02*
X1747750D01*
G01X1760463Y68637D02*
X1758047D01*
G01X1760463Y72637D02*
X1757923D01*
G01X1758442Y756831D02*
X1762942D01*
G01X1758442Y763524D02*
X1762942D01*
G01X1758442Y786949D02*
X1752992D01*
G01X1758442Y796988D02*
X1752992D01*
G01X1758442Y823760D02*
X1752992D01*
G01X1758442Y833799D02*
X1752992D01*
G01X1758442Y860571D02*
X1752992D01*
G01X1758442Y870610D02*
X1752992D01*
G01X1758442Y907422D02*
X1752992D01*
G01X1758442Y897382D02*
X1752992D01*
G01X1758442Y934193D02*
X1752992D01*
G01X1758442Y944233D02*
X1752992D01*
G01X1758442Y1081437D02*
X1752992D01*
G01X1758442Y1091477D02*
X1752992D01*
G01X1758442Y1118248D02*
X1752992D01*
G01X1758442Y1128288D02*
X1752992D01*
G01X1758442Y1155059D02*
X1752992D01*
G01X1758442Y1165099D02*
X1752992D01*
G01X1758442Y1191870D02*
X1752992D01*
G01X1758442Y1201910D02*
X1752992D01*
G01X1758442Y1228681D02*
X1752992D01*
G01X1758442Y1238721D02*
X1752992D01*
G01X1762963Y1647890D02*
X1757963D01*
G01D02*
Y1643565D01*
X1757763Y1643365D01*
G01X1763463Y1689040D02*
Y1691465D01*
G01X1758963Y1689040D02*
Y1691565D01*
G01X1772000Y760177D02*
X1767500D01*
G01X1772000Y756831D02*
X1767500D01*
G01X1772000Y790296D02*
X1777450D01*
G01X1772000Y800335D02*
X1777450D01*
G01X1772000Y827107D02*
X1777450D01*
G01X1772000Y837146D02*
X1777450D01*
G01X1772000Y863918D02*
X1777450D01*
G01X1772000Y873957D02*
X1777450D01*
G01X1772000Y910768D02*
X1777450D01*
G01X1772000Y900729D02*
X1777450D01*
G01X1772000Y937540D02*
X1777450D01*
G01X1772000Y947579D02*
X1777450D01*
G01X1772000Y1084784D02*
X1777450D01*
G01X1772000Y1094823D02*
X1777450D01*
G01X1772000Y1131634D02*
X1777450D01*
G01X1772000Y1121595D02*
X1777450D01*
G01X1772000Y1158406D02*
X1777450D01*
G01X1772000Y1168445D02*
X1777450D01*
G01X1772000Y1205256D02*
X1777450D01*
G01X1772000Y1195217D02*
X1777450D01*
G01X1772000Y1232028D02*
X1777450D01*
G01X1772000Y1242067D02*
X1777450D01*
G01X1790738Y78062D02*
X1788250D01*
X1788204Y78108D01*
G01X1785253Y96927D02*
X1785211Y96969D01*
Y100939D01*
G01X1789815Y151834D02*
Y146834D01*
G01Y161834D02*
X1787390D01*
G01X1789815Y151834D02*
X1787390D01*
G01X1788142Y756831D02*
X1792642D01*
G01X1788142Y763524D02*
X1792642D01*
G01X1788142Y786949D02*
X1782692D01*
G01X1788142Y796988D02*
X1782692D01*
G01X1788142Y823760D02*
X1782692D01*
G01X1788142Y833799D02*
X1782692D01*
G01X1788142Y860571D02*
X1782692D01*
G01X1788142Y870610D02*
X1782692D01*
G01X1788142Y907422D02*
X1782692D01*
G01X1788142Y897382D02*
X1782692D01*
G01X1788142Y934193D02*
X1782692D01*
G01X1788142Y944233D02*
X1782692D01*
G01X1788142Y1081437D02*
X1782692D01*
G01X1788142Y1091477D02*
X1782692D01*
G01X1788142Y1118248D02*
X1782692D01*
G01X1788142Y1128288D02*
X1782692D01*
G01X1788142Y1155059D02*
X1782692D01*
G01X1788142Y1165099D02*
X1782692D01*
G01X1788142Y1191870D02*
X1782692D01*
G01X1788142Y1201910D02*
X1782692D01*
G01X1788142Y1228681D02*
X1782692D01*
G01X1788142Y1238721D02*
X1782692D01*
G01X1785869Y1585832D02*
X1788652D01*
X1788679Y1585805D01*
G01X1791829Y1587105D02*
X1791552D01*
X1790179Y1588478D01*
X1789379D01*
G01X1802800Y146716D02*
X1805525D01*
G01X1802565Y164393D02*
X1800040D01*
G01X1810045Y159275D02*
X1812570D01*
G01X1810280Y151834D02*
X1815005D01*
G01X1818155D02*
Y149325D01*
G01X1827636Y164393D02*
X1825111D01*
G01X1825155Y151834D02*
X1827580D01*
G01X1823081Y388051D02*
X1820656D01*
G01X1835116Y159275D02*
X1837641D01*
G01X1827307Y367359D02*
X1829732D01*
G01X1847866Y161834D02*
Y159124D01*
X67725Y1538946D03*
X74912D03*
X72585D03*
X70155D03*
X103468D03*
X105898D03*
X108328D03*
X110655D03*
X140775Y1638035D03*
X152449Y1623572D03*
Y1628528D03*
X161239Y1636147D03*
Y1631191D03*
X197703Y1550897D03*
X192978Y1550797D03*
X188254D03*
Y1544997D03*
X192978D03*
X197703D03*
X188254Y1548397D03*
X192978D03*
X197703D03*
X187388Y1594876D03*
X192344D03*
X199448D03*
X187388Y1589884D03*
X199448D03*
X192344D03*
X188166Y1592380D03*
X200226D03*
X191566D03*
X193418Y1604876D03*
Y1599884D03*
X198374D03*
Y1604876D03*
Y1611796D03*
X193418D03*
X198374Y1616788D03*
X193418D03*
X192344Y1626788D03*
X199448D03*
X192344Y1621796D03*
X199448D03*
X187388D03*
Y1626788D03*
X188166Y1624292D03*
X200226D03*
X191566D03*
X216601Y1550697D03*
X202427D03*
X211876Y1550897D03*
X207152D03*
X202427Y1544997D03*
X207152D03*
X211876D03*
X216601D03*
X202427Y1548397D03*
X207152D03*
X211876D03*
X216601D03*
X211508Y1594876D03*
X204404D03*
X216464D03*
X211508Y1589884D03*
X204404D03*
X216464D03*
X212286Y1592380D03*
X203626D03*
X215686D03*
X210434Y1604876D03*
X205478D03*
X210434Y1599884D03*
X205478D03*
Y1611796D03*
X210434D03*
Y1616788D03*
X205478D03*
X211508Y1626788D03*
X216464D03*
X211508Y1621796D03*
X216464D03*
X204404Y1626788D03*
Y1621796D03*
X212286Y1624292D03*
X203626D03*
X215686D03*
X226050Y1550897D03*
X221325Y1550797D03*
X230774Y1550897D03*
X221325Y1544997D03*
X226050D03*
X230774D03*
X221325Y1548397D03*
X226050D03*
X230774D03*
X228524Y1594876D03*
X223568D03*
Y1589884D03*
X228524D03*
X224346Y1592380D03*
X227746D03*
X222494Y1604876D03*
X217538D03*
X222494Y1599884D03*
X217538D03*
X229598Y1604876D03*
Y1599884D03*
Y1611796D03*
X217538D03*
X222494D03*
X229598Y1616788D03*
X217538D03*
X222494D03*
X223568Y1626788D03*
X228524D03*
X223568Y1621796D03*
X228524D03*
X224346Y1624292D03*
X227746D03*
X235499Y1550897D03*
X240223D03*
X244947Y1550697D03*
X235499Y1544997D03*
X240223D03*
X244947D03*
X235499Y1548397D03*
X240223D03*
X244947D03*
X240584Y1594876D03*
X235628D03*
Y1589884D03*
X240584D03*
X236406Y1592380D03*
X239806D03*
X246614Y1604876D03*
Y1599884D03*
X234554Y1604876D03*
Y1599884D03*
X241658Y1604876D03*
Y1599884D03*
X246614Y1611796D03*
X241658D03*
X234554D03*
X246614Y1616788D03*
X241658D03*
X234554D03*
X235628Y1626788D03*
X240584D03*
X235628Y1621796D03*
X240584D03*
X236406Y1624292D03*
X239806D03*
X241141Y1679320D03*
Y1683857D03*
X233267Y1675383D03*
Y1679920D03*
Y1684454D03*
X241141Y1688391D03*
Y1693493D03*
Y1698030D03*
X233267Y1689556D03*
Y1694093D03*
Y1698627D03*
X241141Y1702564D03*
Y1707666D03*
Y1712203D03*
Y1716737D03*
X233267Y1703729D03*
Y1708266D03*
Y1712800D03*
X241141Y1721840D03*
Y1726377D03*
Y1730911D03*
X233267Y1717903D03*
Y1722440D03*
Y1726974D03*
X259120Y1550797D03*
X254396Y1550897D03*
X249671D03*
Y1544997D03*
X254396D03*
X259120D03*
X249671Y1548397D03*
X254396D03*
X259120D03*
X259748Y1594876D03*
X247688D03*
X252644D03*
X247688Y1589884D03*
X259748D03*
X252644D03*
X248466Y1592380D03*
X260526D03*
X251866D03*
X253718Y1604876D03*
X258674D03*
X253718Y1599884D03*
X258674D03*
Y1611796D03*
X253718D03*
X258674Y1616788D03*
X253718D03*
X252644Y1626788D03*
X259748D03*
X252644Y1621796D03*
X259748D03*
X247688Y1626788D03*
Y1621796D03*
X248466Y1624292D03*
X260526D03*
X251866D03*
X256889Y1679320D03*
Y1683857D03*
X249015Y1684454D03*
Y1679920D03*
Y1675383D03*
X256889Y1688391D03*
Y1693493D03*
Y1698030D03*
X249015Y1698627D03*
Y1694093D03*
Y1689556D03*
X256889Y1702564D03*
Y1707666D03*
Y1712203D03*
Y1716737D03*
X249015Y1712800D03*
Y1708266D03*
Y1703729D03*
X256889Y1721840D03*
Y1726377D03*
Y1730911D03*
X249015Y1726974D03*
Y1722440D03*
Y1717903D03*
X272525Y108556D03*
X268981D03*
Y111056D03*
X265438Y108556D03*
X261895D03*
Y111056D03*
X265438D03*
X272525D03*
X271808Y1594876D03*
X264704D03*
X271808Y1589884D03*
X264704D03*
X272586Y1592380D03*
X263926D03*
X275986D03*
X265778Y1604876D03*
X270734D03*
X265778Y1599790D03*
X270734D03*
Y1611796D03*
X265778D03*
X270734Y1616788D03*
X265778D03*
X271808Y1626788D03*
Y1621796D03*
X264704Y1626788D03*
Y1621796D03*
X272586Y1624292D03*
X263926D03*
X275986D03*
X272637Y1679320D03*
Y1683857D03*
X264763Y1684454D03*
Y1679920D03*
Y1675383D03*
X272637Y1688391D03*
Y1693493D03*
Y1698030D03*
X264763Y1698627D03*
Y1694093D03*
Y1689556D03*
X272637Y1702564D03*
Y1707666D03*
Y1712203D03*
Y1716737D03*
X264763Y1712800D03*
Y1708266D03*
Y1703729D03*
X272637Y1721840D03*
Y1726377D03*
Y1730911D03*
X264763Y1726974D03*
Y1722440D03*
Y1717903D03*
X288824Y1594876D03*
X276764D03*
X283868D03*
Y1589884D03*
X276764D03*
X288824D03*
X284646Y1592380D03*
X288046D03*
X277838Y1604876D03*
X282794D03*
X277838Y1599884D03*
X282794D03*
X289898Y1604876D03*
Y1599884D03*
Y1611796D03*
X282794D03*
X277838D03*
X289898Y1616788D03*
X282794D03*
X277838D03*
X283868Y1626788D03*
X288824D03*
X283868Y1621796D03*
X288824D03*
X276764Y1626788D03*
Y1621796D03*
X284646Y1624292D03*
X288046D03*
X288385Y1683857D03*
Y1679320D03*
X280511Y1684454D03*
Y1679920D03*
Y1675383D03*
X288385Y1688391D03*
Y1693494D03*
Y1698031D03*
X280511Y1698627D03*
Y1694093D03*
Y1689556D03*
X288385Y1712204D03*
Y1716738D03*
Y1702565D03*
Y1707667D03*
X280511Y1712800D03*
Y1708266D03*
Y1703729D03*
X288385Y1721840D03*
Y1726377D03*
Y1730911D03*
X280511Y1726974D03*
Y1722440D03*
Y1717903D03*
X300884Y1594876D03*
X295928D03*
Y1589884D03*
X300884D03*
X296706Y1592380D03*
X300106D03*
X294854Y1604876D03*
Y1599884D03*
X301958Y1604876D03*
Y1599884D03*
Y1611796D03*
X294854D03*
X301958Y1616788D03*
X294854D03*
X295928Y1626788D03*
X300884D03*
X295928Y1621796D03*
X300884D03*
X296706Y1624292D03*
X300106D03*
X300196Y1675383D03*
Y1679920D03*
Y1684454D03*
Y1689556D03*
Y1694093D03*
Y1698627D03*
Y1703729D03*
Y1708266D03*
Y1712800D03*
Y1717903D03*
Y1722440D03*
Y1726974D03*
X321040Y1550797D03*
X316316D03*
Y1544997D03*
X321040D03*
X316316Y1548397D03*
X321040D03*
X320048Y1594876D03*
X307988D03*
X312944D03*
X307988Y1589884D03*
X320048D03*
X312944D03*
X308766Y1592380D03*
X320826D03*
X312166D03*
X306914Y1604876D03*
Y1599884D03*
X314018Y1604876D03*
X318974D03*
X314018Y1599884D03*
X318974D03*
Y1611796D03*
X314018D03*
X306914D03*
X318974Y1616788D03*
X314018D03*
X306914D03*
X320048Y1626788D03*
X312944D03*
X320048Y1621796D03*
X312944D03*
X307988Y1626788D03*
Y1621796D03*
X308766Y1624292D03*
X320826D03*
X312166D03*
X315944Y1675383D03*
Y1679920D03*
Y1684454D03*
X308070Y1683857D03*
Y1679320D03*
X315944Y1689556D03*
Y1694093D03*
Y1698627D03*
X308070Y1698030D03*
Y1693493D03*
Y1688391D03*
X315944Y1703729D03*
Y1708266D03*
Y1712800D03*
X308070Y1716737D03*
Y1712203D03*
Y1707666D03*
Y1702564D03*
X315944Y1722440D03*
Y1726974D03*
X308070Y1730911D03*
Y1726377D03*
Y1721840D03*
X315944Y1717903D03*
X325765Y1550897D03*
X330489Y1550697D03*
X335214Y1550897D03*
X325765Y1544997D03*
X330489D03*
X335214D03*
X325765Y1548397D03*
X330489D03*
X335214D03*
X332108Y1594876D03*
X325004D03*
X332108Y1589884D03*
X325004D03*
X332886Y1592380D03*
X324226D03*
X326078Y1604876D03*
X331034D03*
X326078Y1599884D03*
X331034D03*
Y1611796D03*
X326078D03*
X331034Y1616788D03*
X326078D03*
X332108Y1626788D03*
X325004D03*
X332108Y1621796D03*
X325004D03*
X332886Y1624292D03*
X324226D03*
X331692Y1675383D03*
Y1679920D03*
Y1684454D03*
X323818Y1683857D03*
Y1679320D03*
X331692Y1689556D03*
Y1694093D03*
Y1698627D03*
X323818Y1698030D03*
Y1693493D03*
Y1688391D03*
X331692Y1703729D03*
Y1708266D03*
Y1712800D03*
X323818Y1716737D03*
Y1712203D03*
Y1707666D03*
Y1702564D03*
Y1721840D03*
X331692Y1717903D03*
Y1722440D03*
Y1726974D03*
X323818Y1730911D03*
Y1726377D03*
X339938Y1550897D03*
X349387Y1550797D03*
X344663Y1550697D03*
X339938Y1544997D03*
X344663D03*
X349387D03*
X339938Y1548397D03*
X344663D03*
X349387D03*
X349124Y1594876D03*
X337064D03*
X344168D03*
Y1589884D03*
X337064D03*
X349124D03*
X344946Y1592380D03*
X336286D03*
X348346D03*
X338138Y1604876D03*
X343094D03*
X338138Y1599884D03*
X343094D03*
X350198Y1604876D03*
Y1599884D03*
Y1611796D03*
X343094D03*
X338138D03*
X350198Y1616788D03*
X343094D03*
X338138D03*
X344168Y1626788D03*
X349124D03*
X344168Y1621796D03*
X349124D03*
X337064Y1626788D03*
Y1621796D03*
X344946Y1624292D03*
X336286D03*
X348346D03*
X347440Y1675383D03*
Y1679920D03*
Y1684454D03*
X339566Y1683857D03*
Y1679320D03*
X347440Y1694093D03*
Y1698627D03*
X339566Y1698030D03*
Y1693493D03*
Y1688391D03*
X347440Y1689556D03*
Y1703729D03*
Y1708266D03*
Y1712800D03*
X339566Y1716737D03*
Y1712203D03*
Y1707666D03*
Y1702564D03*
X347440Y1717903D03*
Y1722440D03*
Y1726974D03*
X339566Y1730911D03*
Y1726377D03*
Y1721840D03*
X354112Y1550897D03*
X358836D03*
X363561D03*
Y1544997D03*
X354112D03*
X358836D03*
X363561Y1548397D03*
X354112D03*
X358836D03*
X361184Y1594876D03*
X356228D03*
Y1589884D03*
X361184D03*
X357006Y1592380D03*
X360406D03*
X355154Y1604876D03*
Y1599884D03*
X362258Y1604876D03*
Y1599790D03*
Y1611796D03*
X355154D03*
X362258Y1616788D03*
X355154D03*
X356228Y1626788D03*
X361184D03*
X356228Y1621796D03*
X361184D03*
X357006Y1624292D03*
X360406D03*
X355314Y1683857D03*
Y1679320D03*
Y1688391D03*
Y1698030D03*
Y1693493D03*
Y1716737D03*
Y1712203D03*
Y1707666D03*
Y1702564D03*
Y1730911D03*
Y1726377D03*
Y1721840D03*
X368285Y1550897D03*
X373009Y1550697D03*
X377733Y1550897D03*
X368285Y1544997D03*
X373009D03*
X377733D03*
X368285Y1548397D03*
X373009D03*
X377733D03*
X368288Y1594876D03*
X373244D03*
X368288Y1589884D03*
X373244D03*
X369066Y1592380D03*
X372466D03*
X367214Y1604876D03*
Y1599790D03*
X374318Y1604876D03*
X379274D03*
X374318Y1599884D03*
X379274D03*
Y1611796D03*
X374318D03*
X367214D03*
X379274Y1616788D03*
X374318D03*
X367214D03*
X373244Y1626788D03*
Y1621796D03*
X368288Y1626788D03*
Y1621796D03*
X369066Y1624292D03*
X372466D03*
X382458Y1550897D03*
X387182Y1550797D03*
X382458Y1544997D03*
X387182D03*
X382458Y1548397D03*
X387182D03*
X452427Y1550797D03*
Y1544997D03*
Y1548397D03*
X451561Y1589884D03*
Y1594876D03*
X452339Y1592380D03*
X451561Y1621796D03*
Y1626788D03*
X452339Y1624292D03*
X461876Y1550897D03*
X457151Y1550797D03*
X466600Y1550697D03*
X457151Y1544997D03*
X461876D03*
X466600D03*
X457151Y1548397D03*
X461876D03*
X466600D03*
X468577Y1589884D03*
Y1594876D03*
X456517Y1589884D03*
X463621D03*
Y1594876D03*
X456517D03*
X464399Y1592380D03*
X455739D03*
X467799D03*
X457591Y1599884D03*
X462547D03*
Y1604876D03*
X457591D03*
X462547Y1611796D03*
X457591D03*
X469651D03*
Y1599884D03*
Y1604876D03*
X462547Y1616788D03*
X457591D03*
X469651D03*
X468577Y1621796D03*
Y1626788D03*
X463621Y1621796D03*
Y1626788D03*
X456517Y1621796D03*
Y1626788D03*
X464399Y1624292D03*
X455739D03*
X467799D03*
X480774Y1550697D03*
X476049Y1550897D03*
X471325D03*
Y1544997D03*
X476049D03*
X480774D03*
X471325Y1548397D03*
X476049D03*
X480774D03*
X480637Y1589884D03*
Y1594876D03*
X475681D03*
Y1589884D03*
X476459Y1592380D03*
X479859D03*
X481711Y1611796D03*
Y1599884D03*
Y1604876D03*
X474607Y1611796D03*
Y1599884D03*
Y1604876D03*
X481711Y1616788D03*
X474607D03*
X475681Y1621796D03*
X480637D03*
X475681Y1626788D03*
X480637D03*
X476459Y1624292D03*
X479859D03*
X485498Y1550797D03*
X490223Y1550897D03*
X494947D03*
X499672D03*
Y1544997D03*
X485498D03*
X490223D03*
X494947D03*
X499672Y1548397D03*
X485498D03*
X490223D03*
X494947D03*
X499801Y1594876D03*
X492697Y1589884D03*
X487741Y1594876D03*
X492697D03*
X499801Y1589884D03*
X487741D03*
X488519Y1592380D03*
X491919D03*
X498727Y1611796D03*
Y1599884D03*
Y1604876D03*
X486667Y1611796D03*
X493771D03*
Y1599884D03*
Y1604876D03*
X486667Y1599884D03*
Y1604876D03*
X498727Y1616788D03*
X499801Y1621796D03*
Y1626788D03*
X486667Y1616788D03*
X493771D03*
X492697Y1621796D03*
X487741D03*
X492697Y1626788D03*
X487741D03*
X488519Y1624292D03*
X491919D03*
X497440Y1684454D03*
Y1679920D03*
Y1675383D03*
Y1698627D03*
Y1694093D03*
Y1689556D03*
Y1712800D03*
Y1708266D03*
Y1703729D03*
Y1726974D03*
Y1722440D03*
Y1717903D03*
X513844Y1550897D03*
X509120Y1550697D03*
X504396Y1550897D03*
Y1544997D03*
X509120D03*
X513844D03*
X504396Y1548397D03*
X509120D03*
X513844D03*
X511861Y1594876D03*
X504757Y1589884D03*
Y1594876D03*
X511861Y1589884D03*
X500579Y1592380D03*
X512639D03*
X503979D03*
X505831Y1611796D03*
X510787D03*
X505831Y1599884D03*
Y1604876D03*
X510787Y1599884D03*
Y1604876D03*
X511861Y1621796D03*
Y1626788D03*
X505831Y1616788D03*
X510787D03*
X504757Y1621796D03*
Y1626788D03*
X500579Y1624292D03*
X512639D03*
X503979D03*
X505314Y1679320D03*
Y1683857D03*
X513188Y1684454D03*
Y1679920D03*
Y1675383D03*
X505314Y1688391D03*
Y1693493D03*
Y1698030D03*
X513188Y1698627D03*
Y1694093D03*
Y1689556D03*
X505314Y1707666D03*
Y1712203D03*
X513188Y1712800D03*
Y1708266D03*
Y1703729D03*
X505314Y1716737D03*
Y1702564D03*
Y1721840D03*
Y1726377D03*
Y1730911D03*
X513188Y1726974D03*
Y1722440D03*
Y1717903D03*
X523293Y1550797D03*
X518569Y1550897D03*
Y1544997D03*
X523293D03*
X518569Y1548397D03*
X523293D03*
X528877Y1589884D03*
Y1594876D03*
X516817Y1589884D03*
Y1594876D03*
X523921D03*
Y1589884D03*
X524699Y1592380D03*
X516039D03*
X528099D03*
X529951Y1611796D03*
Y1599790D03*
Y1604876D03*
X517891Y1611796D03*
X522847D03*
Y1599884D03*
X517891D03*
X522847Y1604876D03*
X517891D03*
X529951Y1616788D03*
X528877Y1621796D03*
Y1626788D03*
X517891Y1616788D03*
X522847D03*
X523921Y1621796D03*
X516817D03*
X523921Y1626788D03*
X516817D03*
X524699Y1624292D03*
X516039D03*
X528099D03*
X521062Y1679320D03*
Y1683857D03*
X528936Y1684454D03*
Y1679920D03*
Y1675383D03*
X521062Y1688391D03*
Y1693493D03*
Y1698030D03*
X528936Y1698627D03*
Y1694093D03*
Y1689556D03*
X521062Y1716737D03*
Y1702564D03*
Y1707666D03*
Y1712203D03*
X528936Y1712800D03*
Y1708266D03*
Y1703729D03*
X521062Y1721840D03*
Y1726377D03*
Y1730911D03*
X528936Y1726974D03*
Y1722440D03*
Y1717903D03*
X540937Y1589884D03*
Y1594876D03*
X535981D03*
Y1589884D03*
X536759Y1592380D03*
X540159D03*
X542011Y1611796D03*
Y1599884D03*
Y1604876D03*
X534907Y1611796D03*
Y1599790D03*
Y1604876D03*
X542011Y1616788D03*
X540937Y1621796D03*
Y1626788D03*
X534907Y1616788D03*
X535981Y1621796D03*
Y1626788D03*
X536759Y1624292D03*
X540159D03*
X536810Y1679320D03*
Y1683857D03*
X544684Y1684454D03*
Y1679920D03*
Y1675383D03*
X536810Y1688391D03*
Y1693493D03*
Y1698030D03*
X544684Y1698627D03*
Y1694093D03*
Y1689556D03*
X536810Y1716737D03*
Y1702564D03*
Y1707666D03*
Y1712203D03*
X544684Y1712800D03*
Y1708266D03*
Y1703729D03*
X536810Y1721840D03*
Y1726377D03*
Y1730911D03*
X544684Y1726974D03*
Y1722440D03*
Y1717903D03*
X552997Y1589884D03*
X548041Y1594876D03*
X552997D03*
X548041Y1589884D03*
X548819Y1592380D03*
X552219D03*
X559027Y1611796D03*
Y1599884D03*
Y1604876D03*
X546967Y1611796D03*
X554071D03*
Y1599884D03*
Y1604876D03*
X546967Y1599884D03*
Y1604876D03*
X559027Y1616788D03*
X546967D03*
X554071D03*
X552997Y1621796D03*
Y1626788D03*
X548041D03*
Y1621796D03*
X548819Y1624292D03*
X552219D03*
X552558Y1679320D03*
Y1683857D03*
Y1688391D03*
Y1693493D03*
Y1698030D03*
Y1716737D03*
Y1702564D03*
Y1707666D03*
Y1712203D03*
Y1721840D03*
Y1726377D03*
Y1730911D03*
X572161Y1594876D03*
X565057Y1589884D03*
X560101Y1594876D03*
X565057D03*
X572161Y1589884D03*
X560101D03*
X572939Y1592380D03*
X560879D03*
X564279D03*
X571087Y1611796D03*
Y1599884D03*
Y1604876D03*
X566131Y1611796D03*
Y1599884D03*
Y1604876D03*
X571087Y1616788D03*
X572161Y1621796D03*
Y1626788D03*
X566131Y1616788D03*
X565057Y1621796D03*
X560101D03*
X565057Y1626788D03*
X560101D03*
X572939Y1624292D03*
X560879D03*
X564279D03*
X572243Y1683857D03*
X564369Y1684454D03*
Y1679920D03*
Y1675383D03*
X572243Y1679320D03*
X564369Y1694093D03*
Y1689556D03*
X572243Y1688391D03*
Y1693493D03*
Y1698030D03*
X564369Y1698627D03*
X572243Y1702564D03*
Y1707666D03*
Y1712203D03*
X564369Y1712800D03*
Y1708266D03*
Y1703729D03*
X572243Y1716737D03*
Y1726377D03*
Y1730911D03*
X564369Y1726974D03*
Y1722440D03*
Y1717903D03*
X572243Y1721840D03*
X585213Y1550797D03*
X580489D03*
Y1544997D03*
X585213D03*
X580489Y1548397D03*
X585213D03*
X589177Y1589884D03*
Y1594876D03*
X577117Y1589884D03*
Y1594876D03*
X584221D03*
Y1589884D03*
X584999Y1592380D03*
X576339D03*
X588399D03*
X578191Y1611796D03*
X583147D03*
Y1599884D03*
X578191D03*
X583147Y1604876D03*
X578191D03*
X589177Y1621796D03*
Y1626788D03*
X578191Y1616788D03*
X583147D03*
X584221Y1621796D03*
X577117D03*
X584221Y1626788D03*
X577117D03*
X584999Y1624292D03*
X576339D03*
X588399D03*
X587991Y1679320D03*
Y1683857D03*
X580117Y1684454D03*
Y1679920D03*
Y1675383D03*
X587991Y1688391D03*
Y1693493D03*
Y1698030D03*
X580117Y1698627D03*
Y1694093D03*
Y1689556D03*
X587991Y1716737D03*
Y1702564D03*
Y1707666D03*
Y1712203D03*
X580117Y1712800D03*
Y1708266D03*
Y1703729D03*
X587991Y1721840D03*
Y1726377D03*
Y1730911D03*
X580117Y1726974D03*
Y1722440D03*
Y1717903D03*
X599387Y1550897D03*
X604111D03*
X589938D03*
X594662Y1550697D03*
X589938Y1544997D03*
X594662D03*
X599387D03*
X604111D03*
X589938Y1548397D03*
X594662D03*
X599387D03*
X604111D03*
X601237Y1589884D03*
Y1594876D03*
X596281D03*
Y1589884D03*
X597059Y1592380D03*
X600459D03*
X602311Y1611796D03*
Y1599884D03*
Y1604876D03*
X590251Y1611796D03*
X595207D03*
Y1599884D03*
X590251D03*
X595207Y1604876D03*
X590251D03*
X602311Y1616788D03*
X601237Y1621796D03*
Y1626788D03*
X590251Y1616788D03*
X595207D03*
X596281Y1621796D03*
Y1626788D03*
X597059Y1624292D03*
X600459D03*
X603739Y1679320D03*
Y1683857D03*
X595865Y1684454D03*
Y1679920D03*
Y1675383D03*
X603739Y1688391D03*
Y1693493D03*
Y1698030D03*
X595865Y1698627D03*
Y1694093D03*
Y1689556D03*
X603739Y1716737D03*
Y1702564D03*
Y1707666D03*
Y1712203D03*
X595865Y1712800D03*
Y1708266D03*
Y1703729D03*
X603739Y1721840D03*
Y1726377D03*
Y1730911D03*
X595865Y1726974D03*
Y1722440D03*
Y1717903D03*
X613560Y1550797D03*
X618285Y1550897D03*
X608836Y1550697D03*
Y1544997D03*
X613560D03*
X618285D03*
X608836Y1548397D03*
X613560D03*
X618285D03*
X613297Y1589884D03*
X608341Y1594876D03*
X613297D03*
X608341Y1589884D03*
X609119Y1592380D03*
X612519D03*
X619327Y1611796D03*
Y1599884D03*
Y1604876D03*
X607267Y1611796D03*
X614371D03*
Y1599884D03*
Y1604876D03*
X607267Y1599884D03*
Y1604876D03*
X619327Y1616788D03*
X607267D03*
X614371D03*
X613297Y1621796D03*
X608341D03*
X613297Y1626788D03*
X608341D03*
X609119Y1624292D03*
X612519D03*
X611613Y1684454D03*
Y1679920D03*
Y1675383D03*
Y1698627D03*
Y1694093D03*
Y1689556D03*
Y1712800D03*
Y1708266D03*
Y1703729D03*
Y1726974D03*
Y1722440D03*
Y1717903D03*
X632458Y1550897D03*
X623009D03*
X627734D03*
Y1544997D03*
X632458D03*
X623009D03*
X627734Y1548397D03*
X632458D03*
X623009D03*
X632461Y1594876D03*
X625357Y1589884D03*
X620401Y1594876D03*
X625357D03*
X632461Y1589884D03*
X620401D03*
X621179Y1592380D03*
X633239D03*
X624579D03*
X631387Y1611796D03*
Y1599790D03*
Y1604876D03*
X626431Y1611796D03*
Y1599790D03*
Y1604876D03*
X631387Y1616788D03*
X632461Y1626788D03*
Y1621796D03*
X626431Y1616788D03*
X620401Y1621796D03*
X625357D03*
X620401Y1626788D03*
X625357D03*
X621179Y1624292D03*
X633239D03*
X624579D03*
X619487Y1679320D03*
Y1683857D03*
Y1688391D03*
Y1693493D03*
Y1698030D03*
Y1716737D03*
Y1702564D03*
Y1707666D03*
Y1712203D03*
Y1721840D03*
Y1726377D03*
Y1730911D03*
X646631Y1550897D03*
X637182Y1550697D03*
X641906Y1550897D03*
X637182Y1544997D03*
X641906D03*
X646631D03*
X637182Y1548397D03*
X641906D03*
X646631D03*
X637417Y1589884D03*
Y1594876D03*
X636639Y1592380D03*
X643447Y1599884D03*
X638491D03*
X643447Y1604876D03*
X638491D03*
X643447Y1611796D03*
X638491D03*
X643447Y1616788D03*
X637417Y1626788D03*
X638491Y1616788D03*
X637417Y1621796D03*
X636639Y1624292D03*
X651355Y1550797D03*
Y1544997D03*
Y1548397D03*
X664634Y449952D03*
X695796Y430957D03*
Y437256D03*
Y468672D03*
X698599Y115178D03*
X705686D03*
X702142D03*
X698599Y112678D03*
X705686D03*
X702142D03*
X695056D03*
Y115178D03*
X695796Y418358D03*
X708395Y427807D03*
Y424657D03*
X705245D03*
Y427807D03*
X702095D03*
X708395Y434106D03*
X705245Y430957D03*
X708395D03*
X702095Y421508D03*
Y434106D03*
X698946Y427807D03*
X705245Y437256D03*
X698946Y430957D03*
X705245Y434106D03*
X702095Y430957D03*
X698946Y437256D03*
X705245Y446705D03*
X708395Y440405D03*
Y443555D03*
X702095Y446705D03*
X705245Y443555D03*
X702095Y437256D03*
Y440405D03*
Y443555D03*
X705245Y440405D03*
X708395Y437256D03*
X698946Y446705D03*
X708395D03*
X698946Y449854D03*
X708395Y462373D03*
Y449854D03*
X702095D03*
X705245Y459223D03*
X702095Y456074D03*
Y459223D03*
X708395Y456074D03*
X705245Y462373D03*
X702095D03*
X705245Y456074D03*
X695796Y449854D03*
X708395Y459223D03*
Y465523D03*
Y474971D03*
X698946Y468672D03*
X705245D03*
X702095D03*
X698946Y471822D03*
X702095Y465523D03*
X695796Y471822D03*
X708395Y478121D03*
X705245Y471822D03*
X695796Y465523D03*
X702095Y478121D03*
X705245Y474971D03*
X708395Y471822D03*
Y468672D03*
X705245Y465523D03*
X702095Y471822D03*
X698946Y465523D03*
X705245Y478121D03*
X702095Y474971D03*
X698946Y487570D03*
Y481271D03*
X695796Y487570D03*
X698946Y484420D03*
X705245Y481271D03*
X702095D03*
X695796Y484420D03*
X708395D03*
Y481271D03*
X720993Y418358D03*
X717843D03*
Y421508D03*
X720993Y430957D03*
X711544D03*
X714694D03*
X717843Y434106D03*
X720993D03*
X717843Y430957D03*
X720993Y421508D03*
X711544Y434106D03*
X714694D03*
X720993Y424657D03*
X717843D03*
Y427807D03*
X714694Y424657D03*
Y427807D03*
X711544Y421508D03*
Y424657D03*
Y427807D03*
X720993D03*
X717843Y437256D03*
X720993D03*
X714694D03*
X711544D03*
X720993Y443555D03*
Y446705D03*
X717843D03*
Y440405D03*
X711544Y443555D03*
X717843D03*
X714694Y446705D03*
Y440405D03*
X720993D03*
X711544D03*
X714694Y443555D03*
X711544Y446705D03*
Y459223D03*
X720993Y449854D03*
Y462373D03*
Y459223D03*
Y456074D03*
X717843Y459223D03*
X714694D03*
X717843Y462373D03*
Y456074D03*
Y449854D03*
X714694Y462373D03*
X711544D03*
X714694Y449854D03*
X711544D03*
X714694Y456074D03*
X711544D03*
X720993Y471822D03*
Y468672D03*
X711544Y478121D03*
X717843Y474971D03*
X724143Y471822D03*
X720993Y478121D03*
X717843D03*
X720993Y474971D03*
X714694Y465523D03*
X717843D03*
Y471822D03*
Y468672D03*
X714694Y471822D03*
X711544D03*
X714694Y468672D03*
X711544D03*
X720993Y465523D03*
X711544Y474971D03*
X714694Y478121D03*
Y474971D03*
X724143Y481271D03*
X711544Y465523D03*
X717843Y481271D03*
X714694D03*
X720993D03*
X711544Y484420D03*
Y481271D03*
X720993Y484420D03*
X731208Y398737D03*
X733512Y418358D03*
X727292D03*
X724143D03*
X736661Y424657D03*
Y430957D03*
Y434106D03*
X733512D03*
Y421508D03*
Y427807D03*
X727292Y421508D03*
X733512Y424657D03*
Y430957D03*
X727292D03*
Y434106D03*
X724143Y430957D03*
X727292Y427807D03*
X736661D03*
X727292Y424657D03*
X724143Y434106D03*
Y421508D03*
X739811Y430957D03*
X724143Y427807D03*
Y424657D03*
X733512Y437256D03*
X736661Y443555D03*
X733512Y446705D03*
Y443555D03*
X727292Y446705D03*
Y443555D03*
X724143D03*
X727292Y440405D03*
X724143Y446705D03*
X736661D03*
X733512Y440405D03*
X736661D03*
X727292Y437256D03*
X724143Y440405D03*
Y437256D03*
X736661D03*
X724143Y462373D03*
X727292D03*
X733512Y459223D03*
X727292D03*
X733512Y462373D03*
X736661D03*
Y459223D03*
Y456074D03*
X733512D03*
Y449854D03*
X736661D03*
X727292Y456074D03*
X724143Y459223D03*
Y456074D03*
X727292Y449854D03*
X724143D03*
X727292Y471822D03*
X724143Y468672D03*
X727292D03*
X736661D03*
X724143Y474971D03*
X727292D03*
X733512Y478121D03*
X724143Y465523D03*
X727292D03*
X733512D03*
X736661D03*
X733512Y474971D03*
Y468672D03*
X736661Y478121D03*
Y471822D03*
X724143Y478121D03*
X727292D03*
X733512Y471822D03*
X736661Y474971D03*
Y487570D03*
Y484420D03*
X724143D03*
X736661Y481271D03*
X733512D03*
X727292D03*
X724143Y487570D03*
X727292Y484420D03*
Y487570D03*
X755559Y421508D03*
X739811Y424657D03*
Y427807D03*
X742961Y424657D03*
Y427807D03*
X746110Y424657D03*
Y427807D03*
X752409Y430957D03*
Y434106D03*
X749260D03*
X752409Y421508D03*
Y424657D03*
X749260D03*
X746110Y430957D03*
X749260D03*
X742961D03*
X752409Y427807D03*
X749260D03*
X739811Y434106D03*
X742961D03*
X746110D03*
X752409Y443555D03*
X739811Y437256D03*
X746110D03*
X742961D03*
X746110Y440405D03*
X749260Y437256D03*
X739811Y443555D03*
Y446705D03*
X742961Y440405D03*
X739811D03*
X742961Y443555D03*
Y446705D03*
X752409Y440405D03*
X749260D03*
Y446705D03*
X752409Y437256D03*
Y446705D03*
X746110D03*
Y443555D03*
X749260D03*
X739811Y449854D03*
Y456074D03*
Y459223D03*
Y462373D03*
X742961Y459223D03*
Y462373D03*
Y456074D03*
Y449854D03*
X752409Y456074D03*
X749260Y449854D03*
X746110Y459223D03*
X752409Y462373D03*
Y459223D03*
X749260D03*
X746110Y456074D03*
Y449854D03*
Y462373D03*
X749260D03*
X752409Y449854D03*
X749260Y456074D03*
X742961Y474971D03*
Y468672D03*
X739811Y478121D03*
Y474971D03*
Y471822D03*
X749260D03*
X739811Y468672D03*
X749260D03*
Y474971D03*
X742961Y471822D03*
X749260Y478121D03*
X742961Y465523D03*
X746110Y474971D03*
X752409Y468672D03*
X742961Y478121D03*
X746110Y468672D03*
X739811Y465523D03*
X752409Y478121D03*
Y471822D03*
Y465523D03*
X746110D03*
X749260D03*
X752409Y474971D03*
X746110Y478121D03*
Y471822D03*
X749260Y481271D03*
X742961Y484420D03*
X739811Y481271D03*
X746110Y484420D03*
X749260D03*
X752409Y487570D03*
X742961D03*
X752409Y484420D03*
X742961Y490070D03*
X746110Y481271D03*
X752409D03*
X742961D03*
X765008Y418358D03*
X755559D03*
X758709D03*
X761858D03*
X755559Y427807D03*
Y430957D03*
X758709Y427807D03*
Y430957D03*
X765008Y424657D03*
X755559D03*
X758709D03*
Y421508D03*
X761858Y424657D03*
X765008Y430957D03*
X755559Y434106D03*
X761858Y430957D03*
Y427807D03*
X758709Y434106D03*
X765008Y427807D03*
Y446705D03*
X758709D03*
X755559Y443555D03*
Y446705D03*
X758709Y437256D03*
X755559D03*
X758709Y440405D03*
X755559D03*
X758709Y443555D03*
X761858Y446705D03*
X755559Y456074D03*
Y449854D03*
Y459223D03*
X765008Y456074D03*
X758709Y465523D03*
X755559Y462373D03*
X758709Y459223D03*
Y462373D03*
Y456074D03*
Y449854D03*
X755559Y478121D03*
X758709Y468672D03*
X755559D03*
Y471822D03*
X758709D03*
X761858Y478121D03*
Y474971D03*
Y471822D03*
X758709Y474971D03*
X765008Y471822D03*
Y474971D03*
Y465523D03*
X758709Y478121D03*
X761858Y468672D03*
Y465523D03*
X765008Y468672D03*
X755559Y465523D03*
Y474971D03*
Y481271D03*
Y484420D03*
X765008Y487570D03*
Y481271D03*
X761858D03*
X758709D03*
X998206Y196191D03*
X1000706D03*
X998206Y199735D03*
X1000706D03*
X998206Y206821D03*
X1000706D03*
X998206Y203278D03*
X1000706D03*
X1117946Y1467955D03*
X1117828Y1473091D03*
X1120376Y1641684D03*
X1125487Y1641754D03*
X1125771Y1652189D03*
X1120595Y1652037D03*
X1120200Y1646597D03*
X1130772Y1641753D03*
X1130684Y1646949D03*
X1130245Y1652189D03*
X1196127Y1577997D03*
Y1581397D03*
Y1583797D03*
X1195261Y1622884D03*
X1200217D03*
X1196039Y1625380D03*
X1199439D03*
X1195261Y1627876D03*
X1200217D03*
Y1654796D03*
X1195261D03*
X1200217Y1659788D03*
X1195261D03*
X1196039Y1657292D03*
X1199439D03*
X1200851Y1577997D03*
X1205576D03*
X1210300D03*
X1215025D03*
X1200851Y1581397D03*
X1205576D03*
X1210300D03*
X1215025D03*
X1200851Y1583797D03*
X1205576Y1583897D03*
X1210300Y1583697D03*
X1215025Y1583897D03*
X1207321Y1622884D03*
X1212277D03*
X1208099Y1625380D03*
X1211499D03*
X1201291Y1637876D03*
Y1632884D03*
X1206247D03*
Y1637876D03*
X1213351D03*
Y1632884D03*
X1207321Y1627876D03*
X1212277D03*
X1207321Y1654796D03*
X1206247Y1649788D03*
X1201291D03*
X1212277Y1654796D03*
X1213351Y1649788D03*
X1206247Y1644796D03*
X1201291D03*
X1213351D03*
X1207321Y1659788D03*
X1212277D03*
X1208099Y1657292D03*
X1211499D03*
X1219749Y1577997D03*
X1224474D03*
X1229198D03*
X1219749Y1581397D03*
X1224474D03*
X1229198D03*
X1219749Y1583897D03*
X1224474Y1583697D03*
X1229198Y1583797D03*
X1219381Y1622884D03*
X1224337D03*
X1220159Y1625380D03*
X1223559D03*
X1218307Y1637876D03*
Y1632884D03*
X1230367Y1637876D03*
X1225411D03*
X1230367Y1632884D03*
X1225411D03*
X1219381Y1627876D03*
X1224337D03*
Y1654796D03*
X1219381D03*
X1218307Y1649788D03*
X1225411D03*
X1230367D03*
X1218307Y1644796D03*
X1225411D03*
X1230367D03*
X1224337Y1659788D03*
X1219381D03*
X1220159Y1657292D03*
X1223559D03*
X1243372Y1577997D03*
X1233923D03*
X1238647D03*
X1243372Y1581397D03*
X1233923D03*
X1238647D03*
X1233923Y1583897D03*
X1238647D03*
X1243372D03*
X1231441Y1622884D03*
X1236397D03*
X1243501D03*
X1232219Y1625380D03*
X1244279D03*
X1235619D03*
X1237471Y1637876D03*
Y1632884D03*
X1242427Y1637876D03*
Y1632884D03*
X1236397Y1627876D03*
X1231441D03*
X1243501D03*
X1231441Y1654796D03*
X1236397D03*
X1237471Y1649788D03*
X1243501Y1654796D03*
X1242427Y1649788D03*
X1237471Y1644796D03*
X1242427D03*
X1231441Y1659788D03*
X1236397D03*
X1243501D03*
X1232219Y1657292D03*
X1244279D03*
X1235619D03*
X1241140Y1684454D03*
Y1679920D03*
Y1675383D03*
Y1698627D03*
Y1694093D03*
Y1689556D03*
Y1712800D03*
Y1708266D03*
Y1703729D03*
Y1726974D03*
Y1722440D03*
Y1717903D03*
X1248096Y1577997D03*
X1252820D03*
X1257544D03*
X1248096Y1581397D03*
X1252820D03*
X1257544D03*
X1248096Y1583897D03*
X1252820Y1583697D03*
X1257544Y1583897D03*
X1248457Y1622884D03*
X1255561D03*
X1256339Y1625380D03*
X1247679D03*
X1259739D03*
X1254487Y1637876D03*
Y1632884D03*
X1249531Y1637876D03*
Y1632884D03*
X1248457Y1627876D03*
X1255561D03*
X1248457Y1654796D03*
X1254487Y1649788D03*
X1249531D03*
X1255561Y1654796D03*
X1254487Y1644796D03*
X1249531D03*
X1248657Y1659588D03*
X1255561Y1659788D03*
X1256339Y1657292D03*
X1247679D03*
X1259739D03*
X1249014Y1679320D03*
Y1683857D03*
X1256888Y1684454D03*
Y1679920D03*
Y1675383D03*
X1249014Y1688391D03*
Y1693493D03*
Y1698030D03*
X1256888Y1698627D03*
Y1694093D03*
Y1689556D03*
Y1703729D03*
X1249014Y1716737D03*
Y1702564D03*
Y1707666D03*
Y1712203D03*
X1256888Y1712800D03*
Y1708266D03*
X1249014Y1721840D03*
Y1726377D03*
Y1730911D03*
X1256888Y1726974D03*
Y1722440D03*
Y1717903D03*
X1262269Y1577997D03*
X1266993D03*
X1262269Y1581397D03*
X1266993D03*
X1262269Y1583897D03*
X1266993Y1583797D03*
X1267621Y1622884D03*
X1260517D03*
X1272577D03*
X1268399Y1625380D03*
X1271799D03*
X1261591Y1637876D03*
X1266547D03*
X1261591Y1632884D03*
X1266547D03*
X1273651Y1637876D03*
Y1632790D03*
X1267621Y1627876D03*
X1260517D03*
X1272577D03*
X1260517Y1654796D03*
X1267621D03*
X1266547Y1649788D03*
X1261591D03*
X1272577Y1654796D03*
X1273651Y1649788D03*
X1266547Y1644796D03*
X1261591D03*
X1273651D03*
X1260517Y1659788D03*
X1267621D03*
X1272577D03*
X1268399Y1657292D03*
X1271799D03*
X1264762Y1679320D03*
Y1683857D03*
X1272636Y1684454D03*
Y1679920D03*
Y1675383D03*
X1264762Y1688391D03*
Y1693493D03*
Y1698030D03*
X1272636Y1698627D03*
Y1694093D03*
Y1689556D03*
X1264762Y1716737D03*
Y1702564D03*
Y1707666D03*
Y1712203D03*
X1272636Y1712800D03*
Y1708266D03*
Y1703729D03*
X1264762Y1721840D03*
Y1726377D03*
Y1730911D03*
X1272636Y1726974D03*
Y1722440D03*
Y1717903D03*
X1279681Y1622884D03*
X1284637D03*
X1280459Y1625380D03*
X1283859D03*
X1278607Y1637876D03*
Y1632790D03*
X1285711Y1637876D03*
Y1632884D03*
X1279681Y1627876D03*
X1284637D03*
X1279681Y1654796D03*
X1278607Y1649788D03*
X1284637Y1654796D03*
X1285711Y1649788D03*
X1278607Y1644796D03*
X1285711D03*
X1279681Y1659788D03*
X1284637D03*
X1280459Y1657292D03*
X1283859D03*
X1280510Y1679320D03*
Y1683857D03*
X1288384Y1684454D03*
Y1679920D03*
Y1675383D03*
X1280510Y1688391D03*
Y1693493D03*
Y1698030D03*
X1288384Y1698627D03*
Y1694093D03*
Y1689556D03*
X1280510Y1716737D03*
Y1702564D03*
Y1707666D03*
Y1712203D03*
X1288384Y1712800D03*
Y1708266D03*
Y1703729D03*
X1280510Y1721840D03*
Y1726377D03*
Y1730911D03*
X1288384Y1726974D03*
Y1722440D03*
Y1717903D03*
X1291741Y1622884D03*
X1296697D03*
X1303801D03*
X1292519Y1625380D03*
X1304579D03*
X1295919D03*
X1290667Y1637876D03*
Y1632884D03*
X1297771Y1637876D03*
Y1632884D03*
X1302727Y1637876D03*
Y1632884D03*
X1296697Y1627876D03*
X1291741D03*
X1303801D03*
X1291741Y1654796D03*
X1296697D03*
X1297771Y1649788D03*
X1290667D03*
X1303801Y1654796D03*
X1302727Y1649788D03*
X1297771Y1644796D03*
X1290667D03*
X1302727D03*
X1291741Y1659788D03*
X1296697D03*
X1303801D03*
X1292519Y1657292D03*
X1304579D03*
X1295919D03*
X1296258Y1679320D03*
Y1683857D03*
Y1688391D03*
Y1693493D03*
Y1698030D03*
Y1716737D03*
Y1702564D03*
Y1707666D03*
Y1712203D03*
Y1721840D03*
Y1726377D03*
Y1730911D03*
X1308757Y1622884D03*
X1315861D03*
X1316639Y1625380D03*
X1320039D03*
X1307979D03*
X1309831Y1637876D03*
Y1632884D03*
X1314787Y1637876D03*
Y1632884D03*
X1308757Y1627876D03*
X1315861D03*
X1308757Y1654796D03*
X1309831Y1649788D03*
X1315861Y1654796D03*
X1314787Y1649788D03*
X1309831Y1644796D03*
X1314787D03*
X1308757Y1659788D03*
X1315861D03*
X1316639Y1657292D03*
X1320039D03*
X1307979D03*
X1315943Y1679320D03*
Y1683857D03*
X1308069Y1684454D03*
Y1679920D03*
Y1675383D03*
X1315943Y1688391D03*
Y1693493D03*
Y1698030D03*
X1308069Y1698627D03*
Y1694093D03*
Y1689556D03*
X1315943Y1716737D03*
Y1702564D03*
Y1707666D03*
Y1712203D03*
X1308069Y1712800D03*
Y1708266D03*
Y1703729D03*
X1315943Y1721840D03*
Y1726377D03*
Y1730911D03*
X1308069Y1726974D03*
Y1722440D03*
Y1717903D03*
X1324189Y1577997D03*
X1328913D03*
X1333638D03*
X1324189Y1581397D03*
X1328913D03*
X1333638D03*
X1328913Y1583797D03*
X1333638Y1583897D03*
X1324189Y1583797D03*
X1327921Y1622884D03*
X1320817D03*
X1332877D03*
X1328699Y1625380D03*
X1332099D03*
X1321891Y1637876D03*
X1326847D03*
X1321891Y1632884D03*
X1326847D03*
X1333951Y1637876D03*
Y1632884D03*
X1327921Y1627876D03*
X1320817D03*
X1332877D03*
X1320817Y1654796D03*
X1327921D03*
X1326847Y1649788D03*
X1321891D03*
X1332877Y1654796D03*
X1333951Y1649788D03*
X1326847Y1644796D03*
X1321891D03*
X1333951D03*
X1320817Y1659788D03*
X1327921D03*
X1332877D03*
X1328699Y1657292D03*
X1332099D03*
X1331691Y1679320D03*
Y1683857D03*
X1323817Y1684454D03*
Y1679920D03*
Y1675383D03*
X1331691Y1688391D03*
Y1693493D03*
Y1698030D03*
X1323817Y1698627D03*
Y1694093D03*
Y1689556D03*
X1331691Y1716737D03*
Y1702564D03*
Y1707666D03*
Y1712203D03*
X1323817Y1712800D03*
Y1708266D03*
Y1703729D03*
X1331691Y1721840D03*
Y1726377D03*
Y1730911D03*
X1323817Y1726974D03*
Y1722440D03*
Y1717903D03*
X1338362Y1577997D03*
X1343087D03*
X1347811D03*
X1338362Y1581397D03*
X1343087D03*
X1347811D03*
X1343087Y1583897D03*
X1347811D03*
X1338362Y1583697D03*
X1339981Y1622884D03*
X1344937D03*
X1340759Y1625380D03*
X1344159D03*
X1338907Y1637876D03*
Y1632884D03*
X1346011Y1637876D03*
Y1632884D03*
X1339981Y1627876D03*
X1344937D03*
X1339981Y1654796D03*
X1338907Y1649788D03*
X1344937Y1654796D03*
X1346011Y1649788D03*
X1338907Y1644796D03*
X1346011D03*
X1339981Y1659788D03*
X1344937D03*
X1340759Y1657292D03*
X1344159D03*
X1347439Y1679320D03*
Y1683857D03*
X1339565Y1684454D03*
Y1679920D03*
Y1675383D03*
X1347439Y1688391D03*
Y1693493D03*
Y1698030D03*
X1339565Y1698627D03*
Y1694093D03*
Y1689556D03*
X1347439Y1716737D03*
Y1702564D03*
Y1707666D03*
Y1712203D03*
X1339565Y1712800D03*
Y1708266D03*
Y1703729D03*
X1347439Y1721840D03*
Y1726377D03*
Y1730911D03*
X1339565Y1726974D03*
Y1722440D03*
Y1717903D03*
X1352536Y1577997D03*
X1357260D03*
X1361985D03*
X1352536Y1581397D03*
X1357260D03*
X1361985D03*
X1357260Y1583797D03*
X1361985Y1583897D03*
X1352536Y1583697D03*
X1352041Y1622884D03*
X1356997D03*
X1364101D03*
X1352819Y1625380D03*
X1356219D03*
X1350967Y1637876D03*
Y1632884D03*
X1358071Y1637876D03*
Y1632884D03*
X1363027Y1637876D03*
Y1632884D03*
X1356997Y1627876D03*
X1352041D03*
X1364101D03*
X1352041Y1654796D03*
X1356997D03*
X1358071Y1649788D03*
X1350967D03*
X1364101Y1654796D03*
X1363027Y1649788D03*
X1358071Y1644796D03*
X1350967D03*
X1363027D03*
X1352041Y1659788D03*
X1356997D03*
X1364101D03*
X1352819Y1657292D03*
X1356219D03*
X1363187Y1679320D03*
Y1683857D03*
X1355313Y1684454D03*
Y1679920D03*
Y1675383D03*
Y1694093D03*
Y1689556D03*
X1363187Y1688391D03*
Y1693493D03*
Y1698030D03*
X1355313Y1698627D03*
X1363187Y1716737D03*
Y1702564D03*
Y1707666D03*
Y1712203D03*
X1355313Y1712800D03*
Y1708266D03*
Y1703729D03*
X1363187Y1726377D03*
Y1730911D03*
X1355313Y1726974D03*
Y1722440D03*
Y1717903D03*
X1363187Y1721840D03*
X1371434Y1577997D03*
X1376158D03*
X1366709D03*
X1371434Y1581397D03*
X1376158D03*
X1366709D03*
X1376158Y1583897D03*
X1366709D03*
X1371434D03*
X1369057Y1622884D03*
X1376161D03*
X1364879Y1625380D03*
X1376939D03*
X1368279D03*
X1370131Y1637876D03*
Y1632790D03*
X1375087Y1637876D03*
Y1632790D03*
X1369057Y1627876D03*
X1376161D03*
X1369057Y1654796D03*
X1370131Y1649788D03*
X1376161Y1654796D03*
X1375087Y1649788D03*
X1370131Y1644796D03*
X1375087D03*
X1369057Y1659788D03*
X1376161D03*
X1364879Y1657292D03*
X1376939D03*
X1368279D03*
X1380882Y1577997D03*
X1385606D03*
X1390331D03*
X1380882Y1581397D03*
X1385606D03*
X1390331D03*
Y1583897D03*
X1380882Y1583697D03*
X1385606Y1583897D03*
X1381117Y1622884D03*
X1380339Y1625380D03*
X1382191Y1637876D03*
X1387147D03*
X1382191Y1632884D03*
X1387147D03*
X1381117Y1627876D03*
Y1654796D03*
X1382191Y1649788D03*
X1387147D03*
X1382191Y1644796D03*
X1387147D03*
X1381117Y1659788D03*
X1380339Y1657292D03*
X1395055Y1577997D03*
Y1581397D03*
Y1583797D03*
X1445500Y1611500D03*
X1448500Y1601000D03*
X1460301Y1577997D03*
X1465025D03*
X1460301Y1581397D03*
X1465025D03*
Y1583797D03*
X1460301D03*
X1464391Y1622884D03*
X1459435D03*
X1460213Y1625380D03*
X1463613D03*
X1465465Y1637876D03*
Y1632884D03*
X1459435Y1627876D03*
X1464391D03*
Y1654796D03*
X1465465Y1649788D03*
Y1644796D03*
X1459435Y1654796D03*
X1464391Y1659788D03*
X1459435D03*
X1460213Y1657292D03*
X1463613D03*
X1469750Y1577997D03*
X1474474D03*
X1479199D03*
X1483923D03*
X1469750Y1581397D03*
X1474474D03*
X1479199D03*
X1483923D03*
X1479199Y1583897D03*
X1483923D03*
X1469750D03*
X1474474Y1583697D03*
X1476451Y1622884D03*
X1471495D03*
X1483555D03*
X1472273Y1625380D03*
X1475673D03*
X1470421Y1632884D03*
Y1637876D03*
X1482481D03*
X1477525D03*
X1482481Y1632884D03*
X1477525D03*
X1471495Y1627876D03*
X1483555D03*
X1476451D03*
X1471495Y1654796D03*
X1470421Y1649788D03*
X1476451Y1654796D03*
X1483555D03*
X1482481Y1649788D03*
X1477525D03*
X1470421Y1644796D03*
X1477525D03*
X1482481D03*
X1471495Y1659788D03*
X1476451D03*
X1483555D03*
X1472273Y1657292D03*
X1475673D03*
X1488648Y1577997D03*
X1493372D03*
X1498097D03*
X1488648Y1581397D03*
X1493372D03*
X1498097D03*
X1493372Y1583797D03*
X1498097Y1583897D03*
X1488648Y1583697D03*
X1488511Y1622884D03*
X1495615D03*
X1484333Y1625380D03*
X1496393D03*
X1487733D03*
X1494541Y1637876D03*
X1489585D03*
X1494541Y1632884D03*
X1489585D03*
X1488511Y1627876D03*
X1495615D03*
X1488511Y1654796D03*
X1495615D03*
X1489585Y1649788D03*
X1494541D03*
X1489585Y1644796D03*
X1494541D03*
X1488511Y1659788D03*
X1495615D03*
X1484333Y1657292D03*
X1496393D03*
X1487733D03*
X1507546Y1577997D03*
X1512270D03*
X1502821D03*
X1507546Y1581397D03*
X1512270D03*
X1502821D03*
X1512270Y1583897D03*
X1502821D03*
X1507546D03*
X1500571Y1622884D03*
X1512631D03*
X1507675D03*
X1508453Y1625380D03*
X1499793D03*
X1511853D03*
X1501645Y1637876D03*
Y1632884D03*
X1506601Y1637876D03*
Y1632884D03*
X1513705Y1637876D03*
Y1632884D03*
X1500571Y1627876D03*
X1512631D03*
X1507675D03*
X1500571Y1654796D03*
X1501645Y1649788D03*
X1507675Y1654796D03*
X1512631D03*
X1513705Y1649788D03*
X1506601D03*
X1501645Y1644796D03*
X1513705D03*
X1506601D03*
X1500571Y1659788D03*
X1507675D03*
X1512831Y1659588D03*
X1508453Y1657292D03*
X1499793D03*
X1511853D03*
X1513187Y1679320D03*
Y1683857D03*
X1505313Y1684454D03*
Y1679920D03*
Y1675383D03*
X1513187Y1688391D03*
Y1693493D03*
Y1698030D03*
X1505313Y1698627D03*
Y1694093D03*
Y1689556D03*
X1513187Y1716737D03*
Y1702564D03*
Y1707666D03*
Y1712203D03*
X1505313Y1712800D03*
Y1708266D03*
Y1703729D03*
X1513187Y1721840D03*
Y1726377D03*
Y1730911D03*
X1505313Y1726974D03*
Y1722440D03*
Y1717903D03*
X1516994Y1577997D03*
X1521718D03*
X1526443D03*
X1516994Y1581397D03*
X1521718D03*
X1526443D03*
Y1583897D03*
X1516994Y1583697D03*
X1521718Y1583897D03*
X1524691Y1622884D03*
X1519735D03*
X1520513Y1625380D03*
X1523913D03*
X1518661Y1637876D03*
Y1632884D03*
X1525765Y1637876D03*
Y1632884D03*
X1519735Y1627876D03*
X1524691D03*
X1518661Y1649788D03*
X1524691Y1654796D03*
X1519735D03*
X1525765Y1649788D03*
X1518661Y1644796D03*
X1525765D03*
X1524991Y1659788D03*
X1519735D03*
X1520513Y1657292D03*
X1523913D03*
X1521061Y1684454D03*
Y1679920D03*
Y1675383D03*
Y1698627D03*
Y1694093D03*
Y1689556D03*
Y1712800D03*
Y1708266D03*
Y1703729D03*
Y1726974D03*
Y1722440D03*
Y1717903D03*
X1531167Y1577997D03*
Y1581397D03*
Y1583797D03*
X1536751Y1622884D03*
X1531795D03*
X1532573Y1625380D03*
X1535973D03*
X1530721Y1637876D03*
Y1632884D03*
X1537825Y1637876D03*
X1542781D03*
X1537825Y1632790D03*
X1542781D03*
X1531795Y1627876D03*
X1536751D03*
X1531795Y1654796D03*
X1530721Y1649788D03*
X1536751Y1654796D03*
X1542781Y1649788D03*
X1537825D03*
X1530721Y1644796D03*
X1542781D03*
X1537825D03*
X1531795Y1659788D03*
X1536751D03*
X1532573Y1657292D03*
X1535973D03*
X1528935Y1679320D03*
Y1683857D03*
X1536809Y1684454D03*
Y1679920D03*
Y1675383D03*
X1528935Y1688391D03*
Y1693493D03*
Y1698030D03*
X1536809Y1698627D03*
Y1694093D03*
Y1689556D03*
X1528935Y1712203D03*
X1536809Y1712800D03*
Y1708266D03*
Y1703729D03*
X1528935Y1716737D03*
Y1702564D03*
Y1707666D03*
Y1721840D03*
Y1726377D03*
Y1730911D03*
X1536809Y1726974D03*
Y1722440D03*
Y1717903D03*
X1548811Y1622884D03*
X1543855D03*
X1555915D03*
X1544633Y1625380D03*
X1556693D03*
X1548033D03*
X1549885Y1637876D03*
X1554841D03*
X1549885Y1632884D03*
X1554841D03*
X1543855Y1627876D03*
X1548811D03*
X1555915D03*
X1543855Y1654796D03*
X1555915D03*
X1548811D03*
X1554841Y1649788D03*
X1549885D03*
X1554841Y1644796D03*
X1549885D03*
X1543855Y1659788D03*
X1555915D03*
X1548811D03*
X1544633Y1657292D03*
X1556693D03*
X1548033D03*
X1544683Y1679320D03*
Y1683857D03*
X1552557Y1684454D03*
Y1679920D03*
Y1675383D03*
X1544683Y1688391D03*
Y1693493D03*
Y1698030D03*
X1552557Y1698627D03*
Y1694093D03*
Y1689556D03*
X1544683Y1716737D03*
Y1702564D03*
Y1707666D03*
Y1712203D03*
X1552557Y1712800D03*
Y1708266D03*
Y1703729D03*
X1544683Y1721840D03*
Y1726377D03*
Y1730911D03*
X1552557Y1726974D03*
Y1722440D03*
Y1717903D03*
X1560871Y1622884D03*
X1572931D03*
X1567975D03*
X1568753Y1625380D03*
X1560093D03*
X1572153D03*
X1561945Y1637876D03*
Y1632884D03*
X1566901Y1637876D03*
Y1632884D03*
X1560871Y1627876D03*
X1572931D03*
X1567975D03*
X1560871Y1654796D03*
X1561945Y1649788D03*
X1567975Y1654796D03*
X1572931D03*
X1566901Y1649788D03*
X1561945Y1644796D03*
X1566901D03*
X1560871Y1659788D03*
X1567975D03*
X1572931D03*
X1568753Y1657292D03*
X1560093D03*
X1572153D03*
X1572243Y1684454D03*
Y1679920D03*
Y1675383D03*
X1560431Y1679320D03*
Y1683857D03*
X1572243Y1698627D03*
Y1694093D03*
Y1689556D03*
X1560431Y1688391D03*
Y1693493D03*
Y1698030D03*
X1572243Y1712800D03*
Y1708266D03*
Y1703729D03*
X1560431Y1716737D03*
Y1702564D03*
Y1707666D03*
Y1712203D03*
X1572243Y1726974D03*
Y1722440D03*
Y1717903D03*
X1560431Y1721840D03*
Y1726377D03*
Y1730911D03*
X1588363Y1577997D03*
Y1581397D03*
Y1583797D03*
X1584991Y1622884D03*
X1580035D03*
X1580813Y1625380D03*
X1584213D03*
X1574005Y1637876D03*
Y1632884D03*
X1578961Y1637876D03*
Y1632884D03*
X1586065Y1637876D03*
Y1632884D03*
X1580035Y1627876D03*
X1584991D03*
X1574005Y1649788D03*
X1580035Y1654796D03*
X1578961Y1649788D03*
X1584991Y1654796D03*
X1586065Y1649788D03*
X1574005Y1644796D03*
X1578961D03*
X1586065D03*
X1580035Y1659788D03*
X1584991D03*
X1580813Y1657292D03*
X1584213D03*
X1580117Y1679320D03*
Y1683857D03*
X1587991Y1684454D03*
Y1679920D03*
Y1675383D03*
X1580117Y1688391D03*
Y1693493D03*
Y1698030D03*
X1587991Y1698627D03*
Y1694093D03*
Y1689556D03*
X1580117Y1716737D03*
Y1702564D03*
Y1707666D03*
Y1712203D03*
X1587991Y1712800D03*
Y1708266D03*
Y1703729D03*
X1580117Y1721840D03*
Y1726377D03*
Y1730911D03*
X1587991Y1726974D03*
Y1722440D03*
Y1717903D03*
X1593087Y1577997D03*
X1597812D03*
X1602536D03*
X1593087Y1581397D03*
X1597812D03*
X1602536D03*
X1593087Y1583797D03*
X1597812Y1583897D03*
X1602536Y1583697D03*
X1597051Y1622884D03*
X1592095D03*
X1592873Y1625380D03*
X1596273D03*
X1591021Y1637876D03*
Y1632884D03*
X1598125Y1637876D03*
X1603081D03*
X1598125Y1632884D03*
X1603081D03*
X1592095Y1627876D03*
X1597051D03*
X1592095Y1654796D03*
X1591021Y1649788D03*
X1597051Y1654796D03*
X1603081Y1649788D03*
X1598125D03*
X1591021Y1644796D03*
X1603081D03*
X1598125D03*
X1592095Y1659788D03*
X1597051D03*
X1592873Y1657292D03*
X1596273D03*
X1595865Y1679320D03*
Y1683857D03*
Y1688391D03*
Y1693493D03*
Y1698030D03*
Y1716737D03*
Y1702564D03*
Y1707666D03*
Y1712203D03*
Y1721840D03*
Y1726377D03*
Y1730911D03*
X1607261Y1577997D03*
X1611985D03*
X1616710D03*
X1607261Y1581397D03*
X1611985D03*
X1616710D03*
X1607261Y1583897D03*
X1611985D03*
X1616710Y1583697D03*
X1609111Y1622884D03*
X1604155D03*
X1616215D03*
X1604933Y1625380D03*
X1616993D03*
X1608333D03*
X1610185Y1637876D03*
X1615141D03*
X1610185Y1632884D03*
X1615141D03*
X1604155Y1627876D03*
X1609111D03*
X1616215D03*
X1604155Y1654796D03*
X1616215D03*
X1609111D03*
X1615141Y1649788D03*
X1610185D03*
X1615141Y1644796D03*
X1610185D03*
X1604155Y1659788D03*
X1616215D03*
X1609111D03*
X1604933Y1657292D03*
X1616993D03*
X1608333D03*
X1611613Y1679320D03*
Y1683857D03*
X1603739Y1684454D03*
Y1679920D03*
Y1675383D03*
X1611613Y1688391D03*
Y1693493D03*
Y1698030D03*
X1603739Y1698627D03*
Y1694093D03*
Y1689556D03*
X1611613Y1702564D03*
Y1707666D03*
Y1712203D03*
X1603739Y1712800D03*
Y1708266D03*
Y1703729D03*
X1611613Y1716737D03*
Y1721840D03*
Y1726377D03*
Y1730911D03*
X1603739Y1726974D03*
Y1722440D03*
Y1717903D03*
X1621434Y1577997D03*
X1626159D03*
X1630883D03*
X1621434Y1581397D03*
X1626159D03*
X1630883D03*
X1621434Y1583797D03*
X1626159Y1583897D03*
X1630883D03*
X1621171Y1622884D03*
X1628275D03*
X1629053Y1625380D03*
X1620393D03*
X1632453D03*
X1622245Y1637876D03*
Y1632884D03*
X1627201Y1637876D03*
Y1632884D03*
X1621171Y1627876D03*
X1628275D03*
X1621171Y1654796D03*
X1622245Y1649788D03*
X1628275Y1654796D03*
X1627201Y1649788D03*
X1622245Y1644796D03*
X1627201D03*
X1621171Y1659788D03*
X1628275D03*
X1629053Y1657292D03*
X1620393D03*
X1632453D03*
X1627361Y1679320D03*
Y1683857D03*
X1619487Y1684454D03*
Y1679920D03*
Y1675383D03*
X1627361Y1688391D03*
Y1693493D03*
Y1698030D03*
X1619487Y1698627D03*
Y1694093D03*
Y1689556D03*
Y1708266D03*
Y1703729D03*
X1627361Y1716737D03*
Y1702564D03*
Y1707666D03*
Y1712203D03*
X1619487Y1712800D03*
X1627361Y1721840D03*
Y1726377D03*
Y1730911D03*
X1619487Y1726974D03*
Y1722440D03*
Y1717903D03*
X1635608Y1577997D03*
X1640332D03*
X1645056D03*
X1635608Y1581397D03*
X1640332D03*
X1645056D03*
X1640332Y1583897D03*
X1645056Y1583697D03*
X1635608Y1583897D03*
X1633231Y1622884D03*
X1645291D03*
X1640335D03*
X1641113Y1625380D03*
X1644513D03*
X1634305Y1637876D03*
Y1632790D03*
X1639261Y1637876D03*
Y1632790D03*
X1646365Y1637876D03*
Y1632884D03*
X1633231Y1627876D03*
X1640335D03*
X1645291D03*
X1633231Y1654796D03*
X1634305Y1649788D03*
X1640335Y1654796D03*
X1639261Y1649788D03*
X1645291Y1654796D03*
X1646365Y1649788D03*
X1634305Y1644796D03*
X1639261D03*
X1646365D03*
X1633231Y1659788D03*
X1640335D03*
X1645291D03*
X1641113Y1657292D03*
X1644513D03*
X1649780Y1577997D03*
X1654505D03*
X1659229D03*
X1649780Y1581397D03*
X1654505D03*
X1659229D03*
X1654505Y1583897D03*
X1659229Y1583797D03*
X1649780Y1583897D03*
X1651321Y1637876D03*
Y1632884D03*
Y1649788D03*
Y1644796D03*
X1736986Y109723D03*
Y112223D03*
X1740529D03*
Y109723D03*
X1744072Y112223D03*
Y109723D03*
X1747616Y112223D03*
Y109723D03*
X1757438Y1571982D03*
X1755008D03*
X1762195D03*
X1759868D03*
X1793181D03*
X1790751D03*
X1795611D03*
X1797938D03*
G54D66*
X77394Y734588D03*
Y1021399D03*
Y1277698D03*
X107095Y734588D03*
Y1021399D03*
Y1277698D03*
X136795Y734588D03*
Y1021399D03*
Y1277698D03*
X166496Y734588D03*
Y1021399D03*
Y1277698D03*
X196197Y734588D03*
Y1021399D03*
Y1277698D03*
X225898Y734588D03*
Y1021399D03*
Y1277698D03*
X655425Y734588D03*
Y1021399D03*
Y1277698D03*
X685126Y734588D03*
Y1021399D03*
Y1277698D03*
X714827Y734588D03*
Y1021399D03*
Y1277698D03*
X744528Y734588D03*
Y1021399D03*
Y1277698D03*
X774229Y734588D03*
Y1021399D03*
Y1277698D03*
X803929Y734588D03*
Y1021399D03*
Y1277698D03*
X1053536Y734587D03*
Y1021398D03*
Y1277697D03*
X1083237Y734587D03*
Y1021398D03*
Y1277697D03*
X1112937Y734587D03*
Y1021398D03*
Y1277697D03*
X1142638Y734587D03*
Y1021398D03*
Y1277697D03*
X1172339Y734587D03*
Y1021398D03*
Y1277697D03*
X1202040Y734587D03*
Y1021398D03*
Y1277697D03*
X1631567Y734587D03*
Y1021398D03*
Y1277697D03*
X1661268Y734587D03*
Y1021398D03*
Y1277697D03*
X1690969Y734587D03*
Y1021398D03*
Y1277697D03*
X1720670Y734587D03*
Y1021398D03*
Y1277697D03*
X1750371Y734587D03*
Y1021398D03*
Y1277697D03*
X1780071Y734587D03*
Y1021398D03*
Y1277697D03*
G54D94*
X129932Y1679174D03*
G54D187*
X481550Y295282D03*
X568550Y304282D03*
G54D169*
X418293Y1612725D03*
X1125516Y1646941D03*
G54D295*
X1176972Y76008D03*
X1171854D03*
Y83488D03*
X1176972D03*
G54D178*
X453472Y489760D03*
Y497240D03*
X462528Y493500D03*
G54D67*
X79740Y1418669D03*
X72260D03*
X76000Y1427331D03*
G54D268*
X897439Y1144562D03*
X944464D03*
X1303767Y548297D03*
X1613357Y550157D03*
G54D196*
X475559Y1643260D03*
X473000D03*
X470441D03*
Y1650740D03*
X473000D03*
X475559D03*
X748441Y220240D03*
X751000D03*
Y212760D03*
X748441D03*
X753559Y220240D03*
Y212760D03*
X822559Y520760D03*
X820000D03*
X817441D03*
Y528240D03*
X820000D03*
X822559D03*
X1183354Y75185D03*
Y82665D03*
X1188472Y75185D03*
X1185913D03*
Y82665D03*
X1188472D03*
X1192612Y1677910D03*
X1195171D03*
X1192612Y1685390D03*
X1197730D03*
X1195171D03*
X1197730Y1677910D03*
X1207954Y1677919D03*
X1210513D03*
X1207954Y1685399D03*
X1213072D03*
X1210513D03*
X1213072Y1677919D03*
X1344958Y75369D03*
X1342399D03*
X1339840D03*
Y82849D03*
X1342399D03*
X1344958D03*
X1356868Y75335D03*
X1354309D03*
X1351750D03*
Y82815D03*
X1354309D03*
X1356868D03*
X1388918Y1682898D03*
X1383800D03*
X1386359D03*
X1388918Y1690378D03*
X1386359D03*
X1383800D03*
X1405058Y1642107D03*
X1402499D03*
X1405058Y1634627D03*
X1399940D03*
X1402499D03*
X1399940Y1642107D03*
X1426513Y1640469D03*
X1429072D03*
X1431631D03*
Y1632989D03*
X1429072D03*
X1426513D03*
G54D58*
X67668Y1559357D03*
X74668D03*
X125298Y1564553D03*
X118298D03*
X125348Y1557644D03*
X118348D03*
X165360Y414250D03*
X158360D03*
X185140Y413710D03*
X184959Y1559098D03*
X184933Y1565952D03*
X192140Y413710D03*
X201789Y591145D03*
Y599245D03*
X191959Y1559098D03*
X191933Y1565952D03*
X208789Y591145D03*
Y599245D03*
X253166Y67826D03*
X260166D03*
X251969Y78930D03*
X258969D03*
X359408Y274970D03*
X366408D03*
X554078Y199041D03*
X561078D03*
X673700Y1521200D03*
X666700D03*
X673633Y1536745D03*
X666633D03*
X673633Y1543599D03*
X666633D03*
X685720Y83362D03*
X692720D03*
X783673Y1355396D03*
Y1362296D03*
X781494Y1409557D03*
X774494D03*
X797969Y1357980D03*
X790673Y1355396D03*
Y1362296D03*
X804969Y1357980D03*
X855576Y234068D03*
X862576D03*
X901500Y1117787D03*
Y1110979D03*
Y1124595D03*
Y1131403D03*
X914700Y1116200D03*
Y1109200D03*
X908500Y1117787D03*
Y1110979D03*
X914700Y1123200D03*
X908500Y1124595D03*
Y1131403D03*
X914700Y1130200D03*
X921700Y1116200D03*
Y1109200D03*
Y1123200D03*
Y1130200D03*
X944500Y1116200D03*
Y1109200D03*
Y1130200D03*
Y1123200D03*
X960442Y175917D03*
X953442D03*
X958419Y1117534D03*
Y1110534D03*
X951500Y1116200D03*
Y1109200D03*
X958419Y1124534D03*
X958300Y1131403D03*
X951500Y1130200D03*
Y1123200D03*
X965419Y1117534D03*
Y1110534D03*
Y1124534D03*
X965300Y1131403D03*
X1037394Y1658146D03*
X1044394D03*
X1126250Y1606927D03*
X1122250Y1615727D03*
X1130250D03*
X1199806Y1598952D03*
X1192806D03*
X1199832Y1592098D03*
X1192832D03*
X1217193Y145739D03*
X1224193D03*
X1302077Y151217D03*
X1295077D03*
X1320014Y519675D03*
X1306766Y532113D03*
X1313766D03*
X1320014Y540375D03*
Y533475D03*
Y526575D03*
X1327014Y519675D03*
Y540375D03*
Y533475D03*
Y526575D03*
X1633139Y533130D03*
X1626139D03*
X1633139Y526230D03*
X1626139D03*
X1633139Y540030D03*
X1626139D03*
X1673258Y1411694D03*
X1674574Y1554200D03*
X1674507Y1576599D03*
Y1569745D03*
X1680258Y1411694D03*
X1681574Y1554200D03*
X1681507Y1576599D03*
Y1569745D03*
X1730096Y63051D03*
X1737096D03*
X1750642Y93075D03*
X1752067Y299637D03*
X1745067D03*
X1757642Y93075D03*
X1757279Y1597550D03*
X1764279D03*
X1757279Y1604950D03*
X1764279D03*
X1808013Y1598316D03*
X1801013D03*
X1808013Y1605816D03*
X1801013D03*
G54D286*
X999455Y208592D03*
Y205049D03*
Y201506D03*
Y197962D03*
G54D49*
X71121Y1493645D03*
Y1511755D03*
X82974Y1326471D03*
Y1344581D03*
X99696Y1493645D03*
Y1511755D03*
X227957Y683164D03*
Y701274D03*
X438700Y1300918D03*
Y1319028D03*
X553787Y622456D03*
Y640566D03*
X1054712Y1326452D03*
Y1344562D03*
X1339222Y643716D03*
Y661826D03*
X1414559Y1300319D03*
Y1318429D03*
X1664127Y665084D03*
Y683194D03*
X1758404Y1526681D03*
Y1544791D03*
X1786979Y1526681D03*
Y1544791D03*
G54D259*
X828390Y1420331D03*
X841240Y1407481D03*
X832154Y1411245D03*
Y1429417D03*
X841240Y1433181D03*
X850326Y1411245D03*
Y1429417D03*
X854090Y1420331D03*
X916546Y309460D03*
X911495Y321654D03*
X916546Y333848D03*
X928740Y304409D03*
Y338899D03*
X940934Y309460D03*
X945985Y321654D03*
X940934Y333848D03*
X1007154Y1411245D03*
X1003390Y1420331D03*
X1007154Y1429417D03*
X1016240Y1407481D03*
Y1433181D03*
X1025326Y1411245D03*
Y1429417D03*
X1029090Y1420331D03*
G54D85*
X147270Y461272D03*
X174050Y460732D03*
X951402Y1520482D03*
X974768D03*
X998134D03*
X1021500D03*
X1044866D03*
X1068232D03*
X1091598D03*
G54D76*
X106843Y1381137D03*
X139443D03*
X172143Y1381249D03*
X205043Y1381144D03*
X237843Y1381004D03*
X264213Y649037D03*
X271443Y1334995D03*
X296957Y683158D03*
X304339Y1334995D03*
X329713Y703362D03*
X337243Y1334856D03*
X362773Y703129D03*
X370043Y1335042D03*
X395813Y703176D03*
X402625Y1354338D03*
X428813Y685444D03*
X461213Y660759D03*
X484865Y1340924D03*
X486135Y1351429D03*
X475865Y1361180D03*
X477135Y1371685D03*
X493813Y634326D03*
X519116Y124200D03*
X515385Y115300D03*
X527113Y600085D03*
X590156Y759400D03*
X581760Y759700D03*
X588886Y769200D03*
X580490Y769100D03*
X606091Y760386D03*
X598124Y759500D03*
X596854Y765500D03*
X714672Y515211D03*
X714399Y1399498D03*
X746632Y516077D03*
X747181Y1399598D03*
X827904Y1312682D03*
X829174Y1323187D03*
X1078581Y1381102D03*
X1111181Y1381074D03*
X1143881Y1380963D03*
X1176781D03*
X1209581Y1381149D03*
X1247572Y1335094D03*
X1289574Y562834D03*
X1291695Y567536D03*
X1280468Y1335001D03*
X1313372Y1334907D03*
X1346172Y1335141D03*
X1374765Y618274D03*
X1378754Y1354318D03*
X1407465Y651240D03*
X1440065Y683835D03*
X1472983Y703385D03*
X1506065Y703404D03*
X1538865Y703451D03*
X1571995Y681501D03*
X1604765Y647601D03*
X1637765Y628715D03*
X1662137Y1398599D03*
X1694919Y1398699D03*
G54D277*
X905815Y1155362D03*
X952840D03*
X1315608Y561302D03*
X1621733Y560957D03*
G54D86*
X129932Y1665000D03*
G54D188*
X478794Y293510D03*
X565794Y302510D03*
G54D179*
X455968Y288258D03*
Y294058D03*
X543208Y297268D03*
Y303068D03*
X646176Y206895D03*
Y201095D03*
X651612Y206890D03*
Y201090D03*
X983328Y211433D03*
X988228D03*
X983328Y217233D03*
X988228D03*
X1110000Y1680900D03*
Y1675100D03*
X1115217Y1680875D03*
Y1675075D03*
X1812174Y191599D03*
Y185799D03*
X1811827Y202598D03*
Y208398D03*
X1817674Y191799D03*
Y197599D03*
G54D278*
X910741Y1641723D03*
X947553D03*
G54D296*
X1196187Y98316D03*
Y100875D03*
Y103434D03*
X1204849D03*
Y98316D03*
G54D68*
X77000Y1447437D03*
X80740Y1439563D03*
X73260D03*
X154640Y431977D03*
X150900Y424103D03*
X158380D03*
X181420Y431437D03*
X185160Y423563D03*
X177680D03*
X426011Y532701D03*
X418531D03*
X422271Y540575D03*
X763029Y151312D03*
X766769Y143438D03*
X759289D03*
X757557Y1687769D03*
X765037D03*
X761297Y1679895D03*
X1050866Y1656096D03*
X1058346D03*
X1054606Y1648222D03*
G54D287*
X1008631Y514587D03*
Y517146D03*
Y519705D03*
Y522264D03*
Y524824D03*
Y527383D03*
Y529942D03*
Y532501D03*
X1030679Y522264D03*
Y519705D03*
Y517146D03*
Y514587D03*
Y532501D03*
Y529942D03*
Y527383D03*
Y524824D03*
X1040045Y376007D03*
Y378566D03*
Y381125D03*
Y383684D03*
Y386244D03*
Y388803D03*
Y391362D03*
Y393921D03*
X1040425Y411704D03*
Y414263D03*
Y416822D03*
Y419381D03*
Y421941D03*
Y424500D03*
Y427059D03*
Y429618D03*
X1062093Y388803D03*
Y386244D03*
Y383684D03*
Y381125D03*
Y378566D03*
Y376007D03*
Y393921D03*
Y391362D03*
X1062473Y419381D03*
Y416822D03*
Y414263D03*
Y411704D03*
Y429618D03*
Y427059D03*
Y424500D03*
Y421941D03*
X1097111Y375469D03*
Y378028D03*
Y380587D03*
Y383146D03*
Y385706D03*
Y388265D03*
Y390824D03*
Y393383D03*
X1119159Y388265D03*
Y385706D03*
Y383146D03*
Y380587D03*
Y378028D03*
Y375469D03*
Y393383D03*
Y390824D03*
X1220178Y162158D03*
Y164717D03*
Y167276D03*
Y169835D03*
Y172395D03*
Y174954D03*
Y177513D03*
Y180072D03*
X1242226Y164717D03*
Y162158D03*
Y180072D03*
Y177513D03*
Y174954D03*
Y172395D03*
Y169835D03*
Y167276D03*
G54D269*
X897437Y1141595D03*
X944462D03*
X1303765Y545330D03*
X1613355Y547190D03*
G54D95*
X139774Y1679174D03*
G54D197*
X496693Y297114D03*
X519723D03*
X583693Y306114D03*
X606723D03*
G54D77*
X111339Y1422181D03*
Y1444819D03*
X125512Y1422181D03*
X123937D03*
X122362D03*
X120787D03*
X119213D03*
X117638D03*
X116063D03*
X114488D03*
X112913D03*
Y1444819D03*
X114488D03*
X116063D03*
X117638D03*
X119213D03*
X120787D03*
X122362D03*
X123937D03*
X125512D03*
X128661Y1422181D03*
X127087D03*
Y1444819D03*
X128661D03*
X1213913Y1408681D03*
X1212339D03*
Y1431319D03*
X1213913D03*
X1229661Y1408681D03*
X1228087D03*
X1226512D03*
X1224937D03*
X1223362D03*
X1221787D03*
X1220213D03*
X1218638D03*
X1217063D03*
X1215488D03*
Y1431319D03*
X1217063D03*
X1218638D03*
X1220213D03*
X1221787D03*
X1223362D03*
X1224937D03*
X1226512D03*
X1228087D03*
X1229661D03*
G54D59*
X62831Y1575194D03*
X80153D03*
X116246Y1580308D03*
X133568D03*
X203980Y627557D03*
X221302D03*
X1655694Y604703D03*
X1673016D03*
X1745150Y1621650D03*
X1762472D03*
X1797091Y1621550D03*
X1814413D03*
G54D189*
X476826Y293510D03*
X563826Y302510D03*
G54D69*
X71307Y1535961D03*
X107050D03*
X118703Y1370083D03*
X151303D03*
X184003D03*
X216903D03*
X249703D03*
X252353Y660034D03*
X285083Y694275D03*
X283303Y1323937D03*
X317853Y714425D03*
X316199Y1323909D03*
X350913Y714157D03*
X349103Y1323852D03*
X383953Y714225D03*
X381903Y1324052D03*
X416953Y696425D03*
X414485Y1343383D03*
X449353Y671825D03*
X481953Y645325D03*
X515253Y611225D03*
X726259Y1388092D03*
X759041Y1388192D03*
X1090441Y1370064D03*
X1123041D03*
X1155741D03*
X1188641D03*
X1221441D03*
X1259432Y1323918D03*
X1292328Y1323890D03*
X1325232Y1323833D03*
X1362905Y629368D03*
X1358032Y1324033D03*
X1395605Y662268D03*
X1390614Y1343364D03*
X1428205Y694848D03*
X1461123Y714425D03*
X1494205Y714593D03*
X1527005Y714425D03*
X1560135Y692485D03*
X1592905Y658716D03*
X1625905Y639716D03*
X1673992Y1387381D03*
X1706774Y1387481D03*
X1758590Y1568997D03*
X1794333D03*
G54D198*
X492000Y413335D03*
X488260Y422665D03*
X495740D03*
X552000Y434835D03*
X548260Y444165D03*
X555740D03*
G54D288*
X1029035Y455244D03*
Y457803D03*
Y460362D03*
Y462921D03*
Y465480D03*
Y468039D03*
Y470599D03*
Y473158D03*
Y475717D03*
Y478276D03*
Y480835D03*
Y483394D03*
X1051083Y462921D03*
Y460362D03*
Y457803D03*
Y455244D03*
Y478276D03*
Y475717D03*
Y473158D03*
Y470599D03*
Y468039D03*
Y465480D03*
Y483394D03*
Y480835D03*
X1118614Y455244D03*
Y457803D03*
Y460362D03*
Y462921D03*
Y465480D03*
Y468039D03*
Y470599D03*
Y473158D03*
Y475717D03*
Y478276D03*
Y480835D03*
Y483394D03*
X1140662Y462921D03*
Y460362D03*
Y457803D03*
Y455244D03*
Y478276D03*
Y475717D03*
Y473158D03*
Y470599D03*
Y468039D03*
Y465480D03*
Y483394D03*
Y480835D03*
G54D297*
X1211531Y128748D03*
Y133866D03*
X1217831Y131307D03*
G54D87*
X139774Y1665000D03*
G54D279*
X938780Y1714890D03*
G54D96*
X136428Y1680945D03*
X134853D03*
X133278D03*
G54D78*
X108681Y1424839D03*
Y1426413D03*
Y1427988D03*
Y1429563D03*
Y1431138D03*
Y1432713D03*
Y1434287D03*
Y1435862D03*
Y1437437D03*
Y1439012D03*
Y1440587D03*
Y1442161D03*
X131319Y1432713D03*
Y1431138D03*
Y1429563D03*
Y1427988D03*
Y1426413D03*
Y1424839D03*
Y1442161D03*
Y1440587D03*
Y1439012D03*
Y1437437D03*
Y1435862D03*
Y1434287D03*
X1209681Y1411339D03*
Y1412913D03*
Y1414488D03*
Y1416063D03*
Y1417638D03*
Y1419213D03*
Y1420787D03*
Y1422362D03*
Y1423937D03*
Y1425512D03*
Y1427087D03*
Y1428661D03*
X1232319Y1417638D03*
Y1416063D03*
Y1414488D03*
Y1412913D03*
Y1411339D03*
Y1428661D03*
Y1427087D03*
Y1425512D03*
Y1423937D03*
Y1422362D03*
Y1420787D03*
Y1419213D03*
G54D97*
X131703Y1680945D03*
G54D79*
X120000Y1433500D03*
X1221000Y1420000D03*
G54D88*
X139774Y1671300D03*
Y1669725D03*
Y1666575D03*
Y1668150D03*
Y1674449D03*
Y1672874D03*
Y1677599D03*
Y1676024D03*
G54D298*
X1225530Y60384D03*
X1233404D03*
X1241278D03*
X1439049Y87432D03*
X1454797D03*
X1446923D03*
G54D289*
X1027520Y543499D03*
Y549799D03*
G54D199*
X507261Y135722D03*
Y134147D03*
Y149895D03*
Y148321D03*
Y146746D03*
Y145171D03*
Y143596D03*
Y142021D03*
Y140447D03*
Y138872D03*
Y137297D03*
Y156195D03*
Y154620D03*
Y153045D03*
Y151470D03*
X537575Y134147D03*
Y135722D03*
Y137297D03*
Y138872D03*
Y140447D03*
Y142021D03*
Y143596D03*
Y145171D03*
Y146746D03*
Y148321D03*
Y149895D03*
Y156195D03*
Y151470D03*
Y153045D03*
Y154620D03*
G54D98*
X138003Y1680945D03*
G54D89*
X136428Y1663229D03*
X134853D03*
X133278D03*
G54D299*
X1225530Y67471D03*
X1454797Y80345D03*
G54D99*
X150318Y230828D03*
Y227088D03*
X1214094Y277848D03*
Y274108D03*
X1230094Y277848D03*
Y274108D03*
X1222094Y277848D03*
Y274108D03*
X1238094Y277848D03*
Y274108D03*
X1246094Y277848D03*
Y274108D03*
X1254094Y277848D03*
Y274108D03*
X1270094Y277848D03*
Y274108D03*
X1262094Y277848D03*
Y274108D03*
X1278094Y277848D03*
Y274108D03*
X1286094Y277848D03*
Y274108D03*
X1294094Y277848D03*
Y274108D03*
X1302094Y277848D03*
Y274108D03*
X1310094Y277848D03*
Y274108D03*
X1318094Y277848D03*
Y274108D03*
X1325530Y60824D03*
Y64564D03*
X1326094Y277848D03*
Y274108D03*
X1334094Y277848D03*
Y274108D03*
X1337440Y60824D03*
Y64564D03*
X1342094Y277848D03*
Y274108D03*
X1350094Y277848D03*
Y274108D03*
X1361550Y60824D03*
Y64564D03*
X1358094Y277848D03*
Y274108D03*
X1373750Y60824D03*
Y64564D03*
X1366094Y277848D03*
Y274108D03*
M02*
